G04 ================== begin FILE IDENTIFICATION RECORD ==================*
G04 Layout Name:  15126-1b.brd*
G04 Film Name:    L1*
G04 File Format:  Gerber RS274X*
G04 File Origin:  Cadence Allegro 16.6-2015-S079*
G04 Origin Date:  Fri Feb 10 17:21:55 2017*
G04 *
G04 Layer:  VIA CLASS/TOP*
G04 Layer:  PIN/TOP*
G04 Layer:  ETCH/TOP*
G04 Layer:  DRAWING FORMAT/LAYER_PCB_STORY*
G04 Layer:  DRAWING FORMAT/LAYER_L1*
G04 *
G04 Offset:    (0.00 0.00)*
G04 Mirror:    No*
G04 Mode:      Positive*
G04 Rotation:  0*
G04 FullContactRelief:  No*
G04 UndefLineWidth:     6.00*
G04 ================== end FILE IDENTIFICATION RECORD ====================*
%FSLAX35Y35*MOIN*%
%IR0*IPPOS*OFA0.00000B0.00000*MIA0B0*SFA1.00000B1.00000*%
%AMMACRO221*
4,1,40,.017,-.013,
.017,.013,
.016939,.013695,
.016759,.014368,
.016464,.015,
.016064,.015571,
.015571,.016064,
.015,.016464,
.014368,.016759,
.013695,.016939,
.013,.017,
-.013,.017,
-.013695,.016939,
-.014368,.016759,
-.015,.016464,
-.015571,.016064,
-.016064,.015571,
-.016464,.015,
-.016759,.014368,
-.016939,.013695,
-.017,.013,
-.017,-.013,
-.016939,-.013695,
-.016759,-.014368,
-.016464,-.015,
-.016064,-.015571,
-.015571,-.016064,
-.015,-.016464,
-.014368,-.016759,
-.013695,-.016939,
-.013,-.017,
.013,-.017,
.013695,-.016939,
.014368,-.016759,
.015,-.016464,
.015571,-.016064,
.016064,-.015571,
.016464,-.015,
.016759,-.014368,
.016939,-.013695,
.017,-.013,
0.0*
%
%ADD221MACRO221*%
%AMMACRO36*
4,1,40,.013,.017,
-.013,.017,
-.013695,.016939,
-.014368,.016759,
-.015,.016464,
-.015571,.016064,
-.016064,.015571,
-.016464,.015,
-.016759,.014368,
-.016939,.013695,
-.017,.013,
-.017,-.013,
-.016939,-.013695,
-.016759,-.014368,
-.016464,-.015,
-.016064,-.015571,
-.015571,-.016064,
-.015,-.016464,
-.014368,-.016759,
-.013695,-.016939,
-.013,-.017,
.013,-.017,
.013695,-.016939,
.014368,-.016759,
.015,-.016464,
.015571,-.016064,
.016064,-.015571,
.016464,-.015,
.016759,-.014368,
.016939,-.013695,
.017,-.013,
.017,.013,
.016939,.013695,
.016759,.014368,
.016464,.015,
.016064,.015571,
.015571,.016064,
.015,.016464,
.014368,.016759,
.013695,.016939,
.013,.017,
0.0*
%
%ADD36MACRO36*%
%AMMACRO158*
4,1,6,-.0425,.1065,
.0145,.1065,
.0145,.0365,
.0425,.0365,
.0425,-.1065,
-.0425,-.1065,
-.0425,.1065,
0.0*
%
%ADD158MACRO158*%
%AMMACRO291*
4,1,21,.006,.015,
.006,-.009,
.005909,-.010042,
.005638,-.011052,
.005196,-.012,
.004596,-.012857,
.003857,-.013596,
.003,-.014196,
.002052,-.014638,
.001042,-.014909,
0.0,-.015,
-.001042,-.014909,
-.002052,-.014638,
-.003,-.014196,
-.003857,-.013596,
-.004596,-.012857,
-.005196,-.012,
-.005638,-.011052,
-.005909,-.010042,
-.006,-.009,
-.006,.015,
.006,.015,
0.0*
%
%ADD291MACRO291*%
%ADD122O,.062X.111*%
%AMMACRO205*
21,1,.02,.005,0.0,0.0,.1*%
%ADD205MACRO205*%
%AMMACRO131*
4,1,38,-.0015,-.0085,
.0015,-.0085,
.002976,-.008371,
.004407,-.007987,
.00575,-.007361,
.006964,-.006511,
.008011,-.005464,
.008861,-.00425,
.009487,-.002907,
.009871,-.001476,
.01,0.0,
.009871,.001476,
.009487,.002907,
.008861,.00425,
.008011,.005464,
.006964,.006511,
.00575,.007361,
.004407,.007987,
.002976,.008371,
.0015,.0085,
-.0015,.0085,
-.002976,.008371,
-.004407,.007987,
-.00575,.007361,
-.006964,.006511,
-.008011,.005464,
-.008861,.00425,
-.009487,.002907,
-.009871,.001476,
-.01,0.0,
-.009871,-.001476,
-.009487,-.002907,
-.008861,-.00425,
-.008011,-.005464,
-.006964,-.006511,
-.00575,-.007361,
-.004407,-.007987,
-.002976,-.008371,
-.0015,-.0085,
0.0*
%
%ADD131MACRO131*%
%AMMACRO124*
4,1,40,-.00707,-.00495,
-.00495,-.00707,
-.003816,-.008023,
-.002532,-.008764,
-.00114,-.009271,
.000319,-.009528,
.001801,-.009528,
.00326,-.009271,
.004652,-.008765,
.005935,-.008024,
.00707,-.007072,
.008023,-.005937,
.008764,-.004654,
.009271,-.003262,
.009528,-.001802,
.009528,-.000321,
.009271,.001138,
.008765,.002531,
.008024,.003814,
.007072,.004949,
.00707,.00495,
.00495,.00707,
.003816,.008023,
.002532,.008764,
.00114,.009271,
-.000319,.009528,
-.001801,.009528,
-.00326,.009271,
-.004652,.008765,
-.005935,.008024,
-.00707,.007072,
-.008023,.005937,
-.008764,.004654,
-.009271,.003262,
-.009528,.001802,
-.009528,.000321,
-.009271,-.001138,
-.008765,-.002531,
-.008024,-.003814,
-.007072,-.004949,
-.00707,-.00495,
0.0*
%
%ADD124MACRO124*%
%AMMACRO217*
21,1,.02,.005,0.0,0.0,12.5*%
%ADD217MACRO217*%
%ADD138R,.02X.004*%
%AMMACRO136*
21,1,.004,.02,0.0,0.0,45.*%
%ADD136MACRO136*%
%AMMACRO126*
4,1,24,.00425,.006,
.004296,.005479,
.004431,.004974,
.004652,.0045,
.004952,.004072,
.005322,.003702,
.00575,.003402,
.006224,.003181,
.006729,.003046,
.00725,.003,
.00875,.003,
.00875,-.003,
.00725,-.003,
.006729,-.003046,
.006224,-.003181,
.00575,-.003402,
.005322,-.003702,
.004952,-.004072,
.004652,-.0045,
.004431,-.004974,
.004296,-.005479,
.00425,-.006,
-.00875,-.006,
-.00875,.006,
.00425,.006,
0.0*
%
%ADD126MACRO126*%
%AMMACRO121*
4,1,38,-.0085,.0015,
-.0085,-.0015,
-.008371,-.002976,
-.007987,-.004407,
-.007361,-.00575,
-.006511,-.006964,
-.005464,-.008011,
-.00425,-.008861,
-.002907,-.009487,
-.001476,-.009871,
0.0,-.01,
.001476,-.009871,
.002907,-.009487,
.00425,-.008861,
.005464,-.008011,
.006511,-.006964,
.007361,-.00575,
.007987,-.004407,
.008371,-.002976,
.0085,-.0015,
.0085,.0015,
.008371,.002976,
.007987,.004407,
.007361,.00575,
.006511,.006964,
.005464,.008011,
.00425,.008861,
.002907,.009487,
.001476,.009871,
0.0,.01,
-.001476,.009871,
-.002907,.009487,
-.00425,.008861,
-.005464,.008011,
-.006511,.006964,
-.007361,.00575,
-.007987,.004407,
-.008371,.002976,
-.0085,.0015,
0.0*
%
%ADD121MACRO121*%
%ADD340R,.05X.115*%
%AMMACRO203*
21,1,.02,.005,0.0,0.0,45.*%
%ADD203MACRO203*%
%ADD155R,.005X.02*%
%ADD137R,.004X.02*%
%ADD17R,.09X.12*%
%AMMACRO321*
4,1,12,.0325,.0195,
-.0325,.0195,
-.0325,-.0195,
-.0195,-.0195,
-.0195,.0005,
-.0065,.0005,
-.0065,-.0195,
.0065,-.0195,
.0065,.0005,
.0195,.0005,
.0195,-.0195,
.0325,-.0195,
.0325,.0195,
0.0*
%
%ADD321MACRO321*%
%AMMACRO266*
21,1,.02,.005,0.0,0.0,45.1*%
%ADD266MACRO266*%
%AMMACRO220*
21,1,.02,.005,0.0,0.0,11.503*%
%ADD220MACRO220*%
%ADD110R,.12X.09*%
%ADD97R,.135X.031*%
%ADD74R,.02X.005*%
%AMMACRO61*
21,1,.02,.006,0.0,0.0,45.*%
%ADD61MACRO61*%
%ADD49R,.006X.02*%
%ADD316R,.108X.04*%
%ADD284R,.055X.13*%
%AMMACRO206*
21,1,.02,.005,0.0,0.0,35.3*%
%ADD206MACRO206*%
%ADD104R,.11X.039*%
%ADD81R,.031X.135*%
%ADD69R,.02X.006*%
%ADD304R,.138X.02*%
%ADD145R,.102X.066*%
%AMMACRO93*
4,1,21,.006,-.014,
-.006,-.014,
-.006,.008,
-.005909,.009042,
-.005638,.010052,
-.005196,.011,
-.004596,.011857,
-.003857,.012596,
-.003,.013196,
-.002052,.013638,
-.001042,.013909,
0.0,.014,
.001042,.013909,
.002052,.013638,
.003,.013196,
.003857,.012596,
.004596,.011857,
.005196,.011,
.005638,.010052,
.005909,.009042,
.006,.008,
.006,-.014,
0.0*
%
%ADD93MACRO93*%
%ADD59R,.134X.024*%
%ADD42R,.024X.171*%
%ADD25C,.01*%
%ADD13R,.053X.106*%
%ADD238R,.171X.024*%
%AMMACRO192*
21,1,.02,.005,0.0,0.0,37.003*%
%ADD192MACRO192*%
%ADD147R,.066X.102*%
%ADD12C,.02*%
%AMMACRO323*
4,1,16,-.045,-.0495,
.045,-.0495,
.045,.0495,
.032,.0495,
.032,.0185,
.01933,.0185,
.01933,.0495,
.00633,.0495,
.00633,.0185,
-.00633,.0185,
-.00633,.0495,
-.01933,.0495,
-.01933,.0185,
-.032,.0185,
-.032,.0495,
-.045,.0495,
-.045,-.0495,
0.0*
%
%ADD323MACRO323*%
%ADD231C,.012*%
%AMMACRO188*
21,1,.02,.005,0.0,0.0,45.104*%
%ADD188MACRO188*%
%ADD24C,.03*%
%AMMACRO292*
4,1,21,.015,-.006,
-.009,-.006,
-.010042,-.005909,
-.011052,-.005638,
-.012,-.005196,
-.012857,-.004596,
-.013596,-.003857,
-.014196,-.003,
-.014638,-.002052,
-.014909,-.001042,
-.015,0.0,
-.014909,.001042,
-.014638,.002052,
-.014196,.003,
-.013596,.003857,
-.012857,.004596,
-.012,.005196,
-.011052,.005638,
-.010042,.005909,
-.009,.006,
.015,.006,
.015,-.006,
0.0*
%
%ADD292MACRO292*%
%ADD270C,.031*%
%AMMACRO193*
21,1,.02,.005,0.0,0.0,37.014*%
%ADD193MACRO193*%
%AMMACRO189*
21,1,.02,.005,0.0,0.0,34.044*%
%ADD189MACRO189*%
%ADD28C,.04*%
%ADD10C,.022*%
%ADD326R,.014X.008*%
%ADD213C,.014*%
%ADD202C,.05*%
%ADD16C,.032*%
%ADD232C,.015*%
%ADD228R,.108X.047*%
%AMMACRO214*
21,1,.02,.005,0.0,0.0,44.9*%
%ADD214MACRO214*%
%ADD208R,.063X.118*%
%ADD58R,.134X.047*%
%ADD27C,.06*%
%ADD298C,.052*%
%ADD234C,.016*%
%AMMACRO194*
21,1,.02,.005,0.0,0.0,40.554*%
%ADD194MACRO194*%
%ADD135C,.025*%
%ADD15C,.034*%
%AMMACRO305*
4,1,6,-.0475,-.0155,
-.0475,.0445,
.0475,.0445,
.0475,-.0445,
-.0235,-.0445,
-.0235,-.0155,
-.0475,-.0155,
0.0*
%
%ADD305MACRO305*%
%AMMACRO190*
21,1,.02,.005,0.0,0.0,21.79*%
%ADD190MACRO190*%
%ADD113C,.017*%
%ADD107C,.026*%
%ADD55C,.044*%
%ADD18C,.071*%
%ADD255C,.054*%
%ADD118C,.018*%
%ADD78C,.045*%
%ADD338C,.055*%
%AMMACRO290*
4,1,21,-.015,.006,
.009,.006,
.010042,.005909,
.011052,.005638,
.012,.005196,
.012857,.004596,
.013596,.003857,
.014196,.003,
.014638,.002052,
.014909,.001042,
.015,0.0,
.014909,-.001042,
.014638,-.002052,
.014196,-.003,
.013596,-.003857,
.012857,-.004596,
.012,-.005196,
.011052,-.005638,
.010042,-.005909,
.009,-.006,
-.015,-.006,
-.015,.006,
0.0*
%
%ADD290MACRO290*%
%ADD209C,.064*%
%AMMACRO191*
21,1,.02,.005,0.0,0.0,34.77*%
%ADD191MACRO191*%
%AMMACRO187*
21,1,.02,.005,0.0,0.0,33.645*%
%ADD187MACRO187*%
%ADD149R,.173X.094*%
%ADD128C,.019*%
%ADD79C,.028*%
%ADD56C,.046*%
%ADD320R,.173X.059*%
%ADD318C,.047*%
%ADD306R,.013X.013*%
%ADD279R,.031X.031*%
%ADD227C,.056*%
%AMMACRO222*
4,1,21,.01,.004,
.010695,.003939,
.011368,.003759,
.012,.003464,
.012571,.003064,
.013064,.002571,
.013464,.002,
.013759,.001368,
.013939,.000695,
.014,0.0,
.013939,-.000695,
.013759,-.001368,
.013464,-.002,
.013064,-.002571,
.012571,-.003064,
.012,-.003464,
.011368,-.003759,
.010695,-.003939,
.01,-.004,
-.014,-.004,
-.014,.004,
.01,.004,
0.0*
%
%ADD222MACRO222*%
%ADD109R,.075X.165*%
%AMMACRO94*
4,1,21,-.014,-.006,
-.014,.006,
.008,.006,
.009042,.005909,
.010052,.005638,
.011,.005196,
.011857,.004596,
.012596,.003857,
.013196,.003,
.013638,.002052,
.013909,.001042,
.014,0.0,
.013909,-.001042,
.013638,-.002052,
.013196,-.003,
.012596,-.003857,
.011857,-.004596,
.011,-.005196,
.010052,-.005638,
.009042,-.005909,
.008,-.006,
-.014,-.006,
0.0*
%
%ADD94MACRO94*%
%ADD295R,.05X.05*%
%AMMACRO289*
4,1,21,-.006,-.015,
-.006,.009,
-.005909,.010042,
-.005638,.011052,
-.005196,.012,
-.004596,.012857,
-.003857,.013596,
-.003,.014196,
-.002052,.014638,
-.001042,.014909,
0.0,.015,
.001042,.014909,
.002052,.014638,
.003,.014196,
.003857,.013596,
.004596,.012857,
.005196,.012,
.005638,.011052,
.005909,.010042,
.006,.009,
.006,-.015,
-.006,-.015,
0.0*
%
%ADD289MACRO289*%
%AMMACRO98*
4,1,21,.004,-.01,
.003939,-.010695,
.003759,-.011368,
.003464,-.012,
.003064,-.012571,
.002571,-.013064,
.002,-.013464,
.001368,-.013759,
.000695,-.013939,
0.0,-.014,
-.000695,-.013939,
-.001368,-.013759,
-.002,-.013464,
-.002571,-.013064,
-.003064,-.012571,
-.003464,-.012,
-.003759,-.011368,
-.003939,-.010695,
-.004,-.01,
-.004,.014,
.004,.014,
.004,-.01,
0.0*
%
%ADD98MACRO98*%
%ADD75C,.039*%
%ADD70C,.057*%
%ADD26R,.06X.06*%
%AMMACRO106*
4,1,8,-.0585,.0835,
-.0585,-.0835,
.0585,-.0835,
.0585,-.04275,
.0185,-.04275,
.0185,.04275,
.0585,.04275,
.0585,.0835,
-.0585,.0835,
0.0*
%
%ADD106MACRO106*%
%ADD302R,.035X.035*%
%ADD315R,.045X.045*%
%ADD271R,.054X.054*%
%ADD264R,.081X.081*%
%ADD244R,.072X.072*%
%ADD339R,.055X.055*%
%ADD210R,.064X.064*%
%AMMACRO96*
4,1,21,.014,.006,
.014,-.006,
-.008,-.006,
-.009042,-.005909,
-.010052,-.005638,
-.011,-.005196,
-.011857,-.004596,
-.012596,-.003857,
-.013196,-.003,
-.013638,-.002052,
-.013909,-.001042,
-.014,0.0,
-.013909,.001042,
-.013638,.002052,
-.013196,.003,
-.012596,.003857,
-.011857,.004596,
-.011,.005196,
-.010052,.005638,
-.009042,.005909,
-.008,.006,
.014,.006,
0.0*
%
%ADD96MACRO96*%
%ADD319R,.047X.047*%
%AMMACRO165*
4,1,40,.011,-.007,
.011,.007,
.010939,.007695,
.010759,.008368,
.010464,.009,
.010064,.009571,
.009571,.010064,
.009,.010464,
.008368,.010759,
.007695,.010939,
.007,.011,
-.007,.011,
-.007695,.010939,
-.008368,.010759,
-.009,.010464,
-.009571,.010064,
-.010064,.009571,
-.010464,.009,
-.010759,.008368,
-.010939,.007695,
-.011,.007,
-.011,-.007,
-.010939,-.007695,
-.010759,-.008368,
-.010464,-.009,
-.010064,-.009571,
-.009571,-.010064,
-.009,-.010464,
-.008368,-.010759,
-.007695,-.010939,
-.007,-.011,
.007,-.011,
.007695,-.010939,
.008368,-.010759,
.009,-.010464,
.009571,-.010064,
.010064,-.009571,
.010464,-.009,
.010759,-.008368,
.010939,-.007695,
.011,-.007,
0.0*
%
%ADD165MACRO165*%
%AMMACRO29*
4,1,40,.007,.011,
-.007,.011,
-.007695,.010939,
-.008368,.010759,
-.009,.010464,
-.009571,.010064,
-.010064,.009571,
-.010464,.009,
-.010759,.008368,
-.010939,.007695,
-.011,.007,
-.011,-.007,
-.010939,-.007695,
-.010759,-.008368,
-.010464,-.009,
-.010064,-.009571,
-.009571,-.010064,
-.009,-.010464,
-.008368,-.010759,
-.007695,-.010939,
-.007,-.011,
.007,-.011,
.007695,-.010939,
.008368,-.010759,
.009,-.010464,
.009571,-.010064,
.010064,-.009571,
.010464,-.009,
.010759,-.008368,
.010939,-.007695,
.011,-.007,
.011,.007,
.010939,.007695,
.010759,.008368,
.010464,.009,
.010064,.009571,
.009571,.010064,
.009,.010464,
.008368,.010759,
.007695,.010939,
.007,.011,
0.0*
%
%ADD29MACRO29*%
%AMMACRO95*
4,1,21,-.006,.014,
.006,.014,
.006,-.008,
.005909,-.009042,
.005638,-.010052,
.005196,-.011,
.004596,-.011857,
.003857,-.012596,
.003,-.013196,
.002052,-.013638,
.001042,-.013909,
0.0,-.014,
-.001042,-.013909,
-.002052,-.013638,
-.003,-.013196,
-.003857,-.012596,
-.004596,-.011857,
-.005196,-.011,
-.005638,-.010052,
-.005909,-.009042,
-.006,-.008,
-.006,.014,
0.0*
%
%ADD95MACRO95*%
%ADD76R,.039X.039*%
%AMMACRO223*
4,1,21,.004,-.01,
.003939,-.010695,
.003759,-.011368,
.003464,-.012,
.003064,-.012571,
.002571,-.013064,
.002,-.013464,
.001368,-.013759,
.000695,-.013939,
0.0,-.014,
-.000695,-.013939,
-.001368,-.013759,
-.002,-.013464,
-.002571,-.013064,
-.003064,-.012571,
-.003464,-.012,
-.003759,-.011368,
-.003939,-.010695,
-.004,-.01,
-.004,.014,
.004,.014,
.004,-.01,
0.0*
%
%ADD223MACRO223*%
%AMMACRO99*
4,1,21,-.01,-.004,
-.010695,-.003939,
-.011368,-.003759,
-.012,-.003464,
-.012571,-.003064,
-.013064,-.002571,
-.013464,-.002,
-.013759,-.001368,
-.013939,-.000695,
-.014,0.0,
-.013939,.000695,
-.013759,.001368,
-.013464,.002,
-.013064,.002571,
-.012571,.003064,
-.012,.003464,
-.011368,.003759,
-.010695,.003939,
-.01,.004,
.014,.004,
.014,-.004,
-.01,-.004,
0.0*
%
%ADD99MACRO99*%
%AMMACRO31*
4,1,40,-.012,.008,
-.012,-.008,
-.011939,-.008695,
-.011759,-.009368,
-.011464,-.01,
-.011064,-.010571,
-.010571,-.011064,
-.01,-.011464,
-.009368,-.011759,
-.008695,-.011939,
-.008,-.012,
.008,-.012,
.008695,-.011939,
.009368,-.011759,
.01,-.011464,
.010571,-.011064,
.011064,-.010571,
.011464,-.01,
.011759,-.009368,
.011939,-.008695,
.012,-.008,
.012,.008,
.011939,.008695,
.011759,.009368,
.011464,.01,
.011064,.010571,
.010571,.011064,
.01,.011464,
.009368,.011759,
.008695,.011939,
.008,.012,
-.008,.012,
-.008695,.011939,
-.009368,.011759,
-.01,.011464,
-.010571,.011064,
-.011064,.010571,
-.011464,.01,
-.011759,.009368,
-.011939,.008695,
-.012,.008,
0.0*
%
%ADD31MACRO31*%
%AMMACRO332*
21,1,.02,.005,0.0,0.0,89.828*%
%ADD332MACRO332*%
%AMMACRO159*
4,1,40,-.013,-.017,
.013,-.017,
.013695,-.016939,
.014368,-.016759,
.015,-.016464,
.015571,-.016064,
.016064,-.015571,
.016464,-.015,
.016759,-.014368,
.016939,-.013695,
.017,-.013,
.017,.013,
.016939,.013695,
.016759,.014368,
.016464,.015,
.016064,.015571,
.015571,.016064,
.015,.016464,
.014368,.016759,
.013695,.016939,
.013,.017,
-.013,.017,
-.013695,.016939,
-.014368,.016759,
-.015,.016464,
-.015571,.016064,
-.016064,.015571,
-.016464,.015,
-.016759,.014368,
-.016939,.013695,
-.017,.013,
-.017,-.013,
-.016939,-.013695,
-.016759,-.014368,
-.016464,-.015,
-.016064,-.015571,
-.015571,-.016064,
-.015,-.016464,
-.014368,-.016759,
-.013695,-.016939,
-.013,-.017,
0.0*
%
%ADD159MACRO159*%
%AMMACRO281*
4,1,40,-.017,.013,
-.017,-.013,
-.016939,-.013695,
-.016759,-.014368,
-.016464,-.015,
-.016064,-.015571,
-.015571,-.016064,
-.015,-.016464,
-.014368,-.016759,
-.013695,-.016939,
-.013,-.017,
.013,-.017,
.013695,-.016939,
.014368,-.016759,
.015,-.016464,
.015571,-.016064,
.016064,-.015571,
.016464,-.015,
.016759,-.014368,
.016939,-.013695,
.017,-.013,
.017,.013,
.016939,.013695,
.016759,.014368,
.016464,.015,
.016064,.015571,
.015571,.016064,
.015,.016464,
.014368,.016759,
.013695,.016939,
.013,.017,
-.013,.017,
-.013695,.016939,
-.014368,.016759,
-.015,.016464,
-.015571,.016064,
-.016064,.015571,
-.016464,.015,
-.016759,.014368,
-.016939,.013695,
-.017,.013,
0.0*
%
%ADD281MACRO281*%
%AMMACRO225*
4,1,21,-.004,.01,
-.003939,.010695,
-.003759,.011368,
-.003464,.012,
-.003064,.012571,
-.002571,.013064,
-.002,.013464,
-.001368,.013759,
-.000695,.013939,
0.0,.014,
.000695,.013939,
.001368,.013759,
.002,.013464,
.002571,.013064,
.003064,.012571,
.003464,.012,
.003759,.011368,
.003939,.010695,
.004,.01,
.004,-.014,
-.004,-.014,
-.004,.01,
0.0*
%
%ADD225MACRO225*%
%AMMACRO101*
4,1,21,.01,.004,
.010695,.003939,
.011368,.003759,
.012,.003464,
.012571,.003064,
.013064,.002571,
.013464,.002,
.013759,.001368,
.013939,.000695,
.014,0.0,
.013939,-.000695,
.013759,-.001368,
.013464,-.002,
.013064,-.002571,
.012571,-.003064,
.012,-.003464,
.011368,-.003759,
.010695,-.003939,
.01,-.004,
-.014,-.004,
-.014,.004,
.01,.004,
0.0*
%
%ADD101MACRO101*%
%AMMACRO224*
4,1,21,-.01,-.004,
-.010695,-.003939,
-.011368,-.003759,
-.012,-.003464,
-.012571,-.003064,
-.013064,-.002571,
-.013464,-.002,
-.013759,-.001368,
-.013939,-.000695,
-.014,0.0,
-.013939,.000695,
-.013759,.001368,
-.013464,.002,
-.013064,.002571,
-.012571,.003064,
-.012,.003464,
-.011368,.003759,
-.010695,.003939,
-.01,.004,
.014,.004,
.014,-.004,
-.01,-.004,
0.0*
%
%ADD224MACRO224*%
%AMMACRO100*
4,1,21,-.004,.01,
-.003939,.010695,
-.003759,.011368,
-.003464,.012,
-.003064,.012571,
-.002571,.013064,
-.002,.013464,
-.001368,.013759,
-.000695,.013939,
0.0,.014,
.000695,.013939,
.001368,.013759,
.002,.013464,
.002571,.013064,
.003064,.012571,
.003464,.012,
.003759,.011368,
.003939,.010695,
.004,.01,
.004,-.014,
-.004,-.014,
-.004,.01,
0.0*
%
%ADD100MACRO100*%
%AMMACRO166*
4,1,40,.011,-.007,
.011,.007,
.010939,.007695,
.010759,.008368,
.010464,.009,
.010064,.009571,
.009571,.010064,
.009,.010464,
.008368,.010759,
.007695,.010939,
.007,.011,
-.007,.011,
-.007695,.010939,
-.008368,.010759,
-.009,.010464,
-.009571,.010064,
-.010064,.009571,
-.010464,.009,
-.010759,.008368,
-.010939,.007695,
-.011,.007,
-.011,-.007,
-.010939,-.007695,
-.010759,-.008368,
-.010464,-.009,
-.010064,-.009571,
-.009571,-.010064,
-.009,-.010464,
-.008368,-.010759,
-.007695,-.010939,
-.007,-.011,
.007,-.011,
.007695,-.010939,
.008368,-.010759,
.009,-.010464,
.009571,-.010064,
.010064,-.009571,
.010464,-.009,
.010759,-.008368,
.010939,-.007695,
.011,-.007,
0.0*
%
%ADD166MACRO166*%
%AMMACRO30*
4,1,40,.007,.011,
-.007,.011,
-.007695,.010939,
-.008368,.010759,
-.009,.010464,
-.009571,.010064,
-.010064,.009571,
-.010464,.009,
-.010759,.008368,
-.010939,.007695,
-.011,.007,
-.011,-.007,
-.010939,-.007695,
-.010759,-.008368,
-.010464,-.009,
-.010064,-.009571,
-.009571,-.010064,
-.009,-.010464,
-.008368,-.010759,
-.007695,-.010939,
-.007,-.011,
.007,-.011,
.007695,-.010939,
.008368,-.010759,
.009,-.010464,
.009571,-.010064,
.010064,-.009571,
.010464,-.009,
.010759,-.008368,
.010939,-.007695,
.011,-.007,
.011,.007,
.010939,.007695,
.010759,.008368,
.010464,.009,
.010064,.009571,
.009571,.010064,
.009,.010464,
.008368,.010759,
.007695,.010939,
.007,.011,
0.0*
%
%ADD30MACRO30*%
%ADD132R,.12X.1*%
%AMMACRO129*
4,1,38,.00295,-.00811,
.00555,-.00661,
.006764,-.00576,
.007811,-.004713,
.008661,-.003499,
.009287,-.002156,
.00967,-.000725,
.009799,.000751,
.00967,.002227,
.009286,.003659,
.00866,.005001,
.007809,.006215,
.006762,.007262,
.005548,.008112,
.004205,.008738,
.002774,.009121,
.001298,.00925,
-.000178,.009121,
-.001609,.008737,
-.00295,.00811,
-.00555,.00661,
-.006764,.00576,
-.007811,.004713,
-.008661,.003499,
-.009287,.002156,
-.00967,.000725,
-.009799,-.000751,
-.00967,-.002227,
-.009286,-.003659,
-.00866,-.005001,
-.007809,-.006215,
-.006762,-.007262,
-.005548,-.008112,
-.004205,-.008738,
-.002774,-.009121,
-.001298,-.00925,
.000178,-.009121,
.001609,-.008737,
.00295,-.00811,
0.0*
%
%ADD129MACRO129*%
%ADD143R,.1X.12*%
%AMMACRO259*
4,1,13,.05895,-.0275,
.055324,-.025079,
.051332,-.023324,
.047096,-.022289,
.042745,-.022006,
.03841,-.022482,
.034225,-.023704,
.030315,-.025634,
.02765,-.0275,
-.115,-.0275,
-.115,.0275,
.115,.0275,
.115,-.0275,
.05895,-.0275,
0.0*
%
%ADD259MACRO259*%
%AMMACRO32*
4,1,40,-.012,.008,
-.012,-.008,
-.011939,-.008695,
-.011759,-.009368,
-.011464,-.01,
-.011064,-.010571,
-.010571,-.011064,
-.01,-.011464,
-.009368,-.011759,
-.008695,-.011939,
-.008,-.012,
.008,-.012,
.008695,-.011939,
.009368,-.011759,
.01,-.011464,
.010571,-.011064,
.011064,-.010571,
.011464,-.01,
.011759,-.009368,
.011939,-.008695,
.012,-.008,
.012,.008,
.011939,.008695,
.011759,.009368,
.011464,.01,
.011064,.010571,
.010571,.011064,
.01,.011464,
.009368,.011759,
.008695,.011939,
.008,.012,
-.008,.012,
-.008695,.011939,
-.009368,.011759,
-.01,.011464,
-.010571,.011064,
-.011064,.010571,
-.011464,.01,
-.011759,.009368,
-.011939,.008695,
-.012,.008,
0.0*
%
%ADD32MACRO32*%
%AMMACRO335*
4,1,11,.016,-.006,
-.016,-.006,
-.016,.006,
.01122,.006,
.011821,.004838,
.012489,.003712,
.013222,.002627,
.014016,.001587,
.014869,.000594,
.015779,-.000347,
.016,-.00056,
.016,-.006,
0.0*
%
%ADD335MACRO335*%
%ADD235O,.013X.01*%
%ADD233O,.01X.013*%
%AMMACRO160*
4,1,40,-.013,-.017,
.013,-.017,
.013695,-.016939,
.014368,-.016759,
.015,-.016464,
.015571,-.016064,
.016064,-.015571,
.016464,-.015,
.016759,-.014368,
.016939,-.013695,
.017,-.013,
.017,.013,
.016939,.013695,
.016759,.014368,
.016464,.015,
.016064,.015571,
.015571,.016064,
.015,.016464,
.014368,.016759,
.013695,.016939,
.013,.017,
-.013,.017,
-.013695,.016939,
-.014368,.016759,
-.015,.016464,
-.015571,.016064,
-.016064,.015571,
-.016464,.015,
-.016759,.014368,
-.016939,.013695,
-.017,.013,
-.017,-.013,
-.016939,-.013695,
-.016759,-.014368,
-.016464,-.015,
-.016064,-.015571,
-.015571,-.016064,
-.015,-.016464,
-.014368,-.016759,
-.013695,-.016939,
-.013,-.017,
0.0*
%
%ADD160MACRO160*%
%AMMACRO282*
4,1,40,-.017,.013,
-.017,-.013,
-.016939,-.013695,
-.016759,-.014368,
-.016464,-.015,
-.016064,-.015571,
-.015571,-.016064,
-.015,-.016464,
-.014368,-.016759,
-.013695,-.016939,
-.013,-.017,
.013,-.017,
.013695,-.016939,
.014368,-.016759,
.015,-.016464,
.015571,-.016064,
.016064,-.015571,
.016464,-.015,
.016759,-.014368,
.016939,-.013695,
.017,-.013,
.017,.013,
.016939,.013695,
.016759,.014368,
.016464,.015,
.016064,.015571,
.015571,.016064,
.015,.016464,
.014368,.016759,
.013695,.016939,
.013,.017,
-.013,.017,
-.013695,.016939,
-.014368,.016759,
-.015,.016464,
-.015571,.016064,
-.016064,.015571,
-.016464,.015,
-.016759,.014368,
-.016939,.013695,
-.017,.013,
0.0*
%
%ADD282MACRO282*%
%AMMACRO83*
4,1,8,.0825,-.065,
.0825,.065,
-.0175,.065,
-.0175,.087,
-.0825,.087,
-.0825,-.087,
-.0175,-.087,
-.0175,-.065,
.0825,-.065,
0.0*
%
%ADD83MACRO83*%
%AMMACRO41*
4,1,6,.0425,-.1065,
-.0145,-.1065,
-.0145,-.0365,
-.0425,-.0365,
-.0425,.1065,
.0425,.1065,
.0425,-.1065,
0.0*
%
%ADD41MACRO41*%
%ADD22R,.02X.02*%
%AMMACRO237*
4,1,6,-.1065,-.0425,
-.1065,.0145,
-.0365,.0145,
-.0365,.0425,
.1065,.0425,
.1065,-.0425,
-.1065,-.0425,
0.0*
%
%ADD237MACRO237*%
%AMMACRO125*
4,1,40,.00495,-.00707,
.00707,-.00495,
.008023,-.003816,
.008764,-.002532,
.009271,-.00114,
.009528,.000319,
.009528,.001801,
.009271,.00326,
.008765,.004652,
.008024,.005935,
.007072,.00707,
.005937,.008023,
.004654,.008764,
.003262,.009271,
.001802,.009528,
.000321,.009528,
-.001138,.009271,
-.002531,.008765,
-.003814,.008024,
-.004949,.007072,
-.00495,.00707,
-.00707,.00495,
-.008023,.003816,
-.008764,.002532,
-.009271,.00114,
-.009528,-.000319,
-.009528,-.001801,
-.009271,-.00326,
-.008765,-.004652,
-.008024,-.005935,
-.007072,-.00707,
-.005937,-.008023,
-.004654,-.008764,
-.003262,-.009271,
-.001802,-.009528,
-.000321,-.009528,
.001138,-.009271,
.002531,-.008765,
.003814,-.008024,
.004949,-.007072,
.00495,-.00707,
0.0*
%
%ADD125MACRO125*%
%AMMACRO117*
4,1,38,.0085,-.0015,
.0085,.0015,
.008371,.002976,
.007987,.004407,
.007361,.00575,
.006511,.006964,
.005464,.008011,
.00425,.008861,
.002907,.009487,
.001476,.009871,
0.0,.01,
-.001476,.009871,
-.002907,.009487,
-.00425,.008861,
-.005464,.008011,
-.006511,.006964,
-.007361,.00575,
-.007987,.004407,
-.008371,.002976,
-.0085,.0015,
-.0085,-.0015,
-.008371,-.002976,
-.007987,-.004407,
-.007361,-.00575,
-.006511,-.006964,
-.005464,-.008011,
-.00425,-.008861,
-.002907,-.009487,
-.001476,-.009871,
0.0,-.01,
.001476,-.009871,
.002907,-.009487,
.00425,-.008861,
.005464,-.008011,
.006511,-.006964,
.007361,-.00575,
.007987,-.004407,
.008371,-.002976,
.0085,-.0015,
0.0*
%
%ADD117MACRO117*%
%AMMACRO116*
4,1,40,.00707,.00495,
.00495,.00707,
.003816,.008023,
.002532,.008764,
.00114,.009271,
-.000319,.009528,
-.001801,.009528,
-.00326,.009271,
-.004652,.008765,
-.005935,.008024,
-.00707,.007072,
-.008023,.005937,
-.008764,.004654,
-.009271,.003262,
-.009528,.001802,
-.009528,.000321,
-.009271,-.001138,
-.008765,-.002531,
-.008024,-.003814,
-.007072,-.004949,
-.00707,-.00495,
-.00495,-.00707,
-.003816,-.008023,
-.002532,-.008764,
-.00114,-.009271,
.000319,-.009528,
.001801,-.009528,
.00326,-.009271,
.004652,-.008765,
.005935,-.008024,
.00707,-.007072,
.008023,-.005937,
.008764,-.004654,
.009271,-.003262,
.009528,-.001802,
.009528,-.000321,
.009271,.001138,
.008765,.002531,
.008024,.003814,
.007072,.004949,
.00707,.00495,
0.0*
%
%ADD116MACRO116*%
%AMMACRO115*
4,1,40,-.00495,.00707,
-.00707,.00495,
-.008023,.003816,
-.008764,.002532,
-.009271,.00114,
-.009528,-.000319,
-.009528,-.001801,
-.009271,-.00326,
-.008765,-.004652,
-.008024,-.005935,
-.007072,-.00707,
-.005937,-.008023,
-.004654,-.008764,
-.003262,-.009271,
-.001802,-.009528,
-.000321,-.009528,
.001138,-.009271,
.002531,-.008765,
.003814,-.008024,
.004949,-.007072,
.00495,-.00707,
.00707,-.00495,
.008023,-.003816,
.008764,-.002532,
.009271,-.00114,
.009528,.000319,
.009528,.001801,
.009271,.00326,
.008765,.004652,
.008024,.005935,
.007072,.00707,
.005937,.008023,
.004654,.008764,
.003262,.009271,
.001802,.009528,
.000321,.009528,
-.001138,.009271,
-.002531,.008765,
-.003814,.008024,
-.004949,.007072,
-.00495,.00707,
0.0*
%
%ADD115MACRO115*%
%AMMACRO114*
4,1,38,.0015,.0085,
-.0015,.0085,
-.002976,.008371,
-.004407,.007987,
-.00575,.007361,
-.006964,.006511,
-.008011,.005464,
-.008861,.00425,
-.009487,.002907,
-.009871,.001476,
-.01,0.0,
-.009871,-.001476,
-.009487,-.002907,
-.008861,-.00425,
-.008011,-.005464,
-.006964,-.006511,
-.00575,-.007361,
-.004407,-.007987,
-.002976,-.008371,
-.0015,-.0085,
.0015,-.0085,
.002976,-.008371,
.004407,-.007987,
.00575,-.007361,
.006964,-.006511,
.008011,-.005464,
.008861,-.00425,
.009487,-.002907,
.009871,-.001476,
.01,0.0,
.009871,.001476,
.009487,.002907,
.008861,.00425,
.008011,.005464,
.006964,.006511,
.00575,.007361,
.004407,.007987,
.002976,.008371,
.0015,.0085,
0.0*
%
%ADD114MACRO114*%
%ADD21R,.02X.02*%
%ADD343R,.032X.01*%
%ADD263R,.012X.03*%
%ADD262R,.03X.012*%
%AMMACRO184*
21,1,.02,.005,0.0,0.0,153.*%
%ADD184MACRO184*%
%AMMACRO153*
4,1,21,.0095,.0055,
.010455,.005416,
.011381,.005168,
.01225,.004763,
.013035,.004213,
.013713,.003535,
.014263,.00275,
.014668,.001881,
.014916,.000955,
.015,0.0,
.014916,-.000955,
.014668,-.001881,
.014263,-.00275,
.013713,-.003535,
.013035,-.004213,
.01225,-.004763,
.011381,-.005168,
.010455,-.005416,
.0095,-.0055,
-.015,-.0055,
-.015,.0055,
.0095,.0055,
0.0*
%
%ADD153MACRO153*%
%AMMACRO103*
21,1,.02,.005,0.0,0.0,135.*%
%ADD103MACRO103*%
%ADD43R,.014X.02*%
%ADD346R,.05X.03*%
%ADD331R,.032X.012*%
%ADD329O,.041X.06*%
%AMMACRO285*
4,1,12,-.0195,.0325,
-.0195,-.0325,
.0195,-.0325,
.0195,-.0195,
-.0005,-.0195,
-.0005,-.0065,
.0195,-.0065,
.0195,.0065,
-.0005,.0065,
-.0005,.0195,
.0195,.0195,
.0195,.0325,
-.0195,.0325,
0.0*
%
%ADD285MACRO285*%
%AMMACRO269*
21,1,.02,.005,0.0,0.0,135.1*%
%ADD269MACRO269*%
%ADD239R,.02X.014*%
%AMMACRO162*
4,1,21,.015,-.006,
-.009,-.006,
-.010042,-.005909,
-.011052,-.005638,
-.012,-.005196,
-.012857,-.004596,
-.013596,-.003857,
-.014196,-.003,
-.014638,-.002052,
-.014909,-.001042,
-.015,0.0,
-.014909,.001042,
-.014638,.002052,
-.014196,.003,
-.013596,.003857,
-.012857,.004596,
-.012,.005196,
-.011052,.005638,
-.010042,.005909,
-.009,.006,
.015,.006,
.015,-.006,
0.0*
%
%ADD162MACRO162*%
%ADD134R,.125X.14*%
%AMMACRO48*
21,1,.02,.006,0.0,0.0,135.*%
%ADD48MACRO48*%
%ADD296R,.03X.05*%
%ADD278R,.102X.145*%
%ADD252R,.011X.033*%
%ADD251R,.033X.011*%
%AMMACRO245*
4,1,21,-.006,-.015,
-.006,.009,
-.005909,.010042,
-.005638,.011052,
-.005196,.012,
-.004596,.012857,
-.003857,.013596,
-.003,.014196,
-.002052,.014638,
-.001042,.014909,
0.0,.015,
.001042,.014909,
.002052,.014638,
.003,.014196,
.003857,.013596,
.004596,.012857,
.005196,.012,
.005638,.011052,
.005909,.010042,
.006,.009,
.006,-.015,
-.006,-.015,
0.0*
%
%ADD245MACRO245*%
%AMMACRO198*
21,1,.02,.005,0.0,0.0,124.4*%
%ADD198MACRO198*%
%ADD60R,.04X.05*%
%ADD294R,.104X.217*%
%AMMACRO253*
4,1,20,-.015,.084,
-.015,.0405,
-.0405,.0405,
-.0405,-.0405,
-.015,-.0405,
-.015,-.084,
-.0075,-.084,
-.0075,-.055,
.0075,-.055,
.0075,-.084,
.015,-.084,
.015,-.0405,
.0405,-.0405,
.0405,.0405,
.015,.0405,
.015,.084,
.0075,.084,
.0075,.055,
-.0075,.055,
-.0075,.084,
-.015,.084,
0.0*
%
%ADD253MACRO253*%
%ADD229R,.061X.012*%
%AMMACRO201*
21,1,.02,.005,0.0,0.0,110.064*%
%ADD201MACRO201*%
%AMMACRO185*
21,1,.02,.005,0.0,0.0,153.021*%
%ADD185MACRO185*%
%AMMACRO170*
21,1,.02,.005,0.0,0.0,124.5*%
%ADD170MACRO170*%
%AMMACRO169*
21,1,.02,.005,0.0,0.0,145.2*%
%ADD169MACRO169*%
%ADD108R,.02X.071*%
%ADD89R,.015X.04*%
%ADD88R,.05X.04*%
%ADD308R,.071X.02*%
%ADD276R,.012X.026*%
%ADD236R,.105X.145*%
%AMMACRO127*
4,1,24,-.00425,-.006,
-.004296,-.005479,
-.004431,-.004974,
-.004652,-.0045,
-.004952,-.004072,
-.005322,-.003702,
-.00575,-.003402,
-.006224,-.003181,
-.006729,-.003046,
-.00725,-.003,
-.00875,-.003,
-.00875,.003,
-.00725,.003,
-.006729,.003046,
-.006224,.003181,
-.00575,.003402,
-.005322,.003702,
-.004952,.004072,
-.004652,.0045,
-.004431,.004974,
-.004296,.005479,
-.00425,.006,
.00875,.006,
.00875,-.006,
-.00425,-.006,
0.0*
%
%ADD127MACRO127*%
%ADD86R,.012X.035*%
%ADD85R,.02X.045*%
%ADD84R,.06X.04*%
%ADD80R,.04X.015*%
%ADD57R,.015X.05*%
%ADD46R,.01X.028*%
%ADD45R,.028X.01*%
%ADD23R,.035X.03*%
%ADD19R,.04X.016*%
%ADD337R,.05X.015*%
%AMMACRO333*
4,1,48,.0225,.036,
.026668,.035635,
.030708,.034553,
.0345,.032785,
.037927,.030385,
.040885,.027427,
.043285,.024,
.045053,.020208,
.046135,.016168,
.0465,.012,
.046135,.007832,
.045053,.003792,
.043285,0.0,
.040885,-.003427,
.037927,-.006385,
.0345,-.008785,
.030708,-.010553,
.026668,-.011635,
.0225,-.012,
.0015,-.012,
.001135,-.016168,
.000053,-.020208,
-.001715,-.024,
-.004115,-.027427,
-.007073,-.030385,
-.0105,-.032785,
-.014292,-.034553,
-.018332,-.035635,
-.0225,-.036,
-.026668,-.035635,
-.030708,-.034553,
-.0345,-.032785,
-.037927,-.030385,
-.040885,-.027427,
-.043285,-.024,
-.045053,-.020208,
-.046135,-.016168,
-.0465,-.012,
-.0465,.012,
-.046135,.016168,
-.045053,.020208,
-.043285,.024,
-.040885,.027427,
-.037927,.030385,
-.0345,.032785,
-.030708,.034553,
-.026668,.035635,
-.0225,.036,
.0225,.036,
0.0*
%
%ADD333MACRO333*%
%ADD324R,.026X.012*%
%AMMACRO297*
21,1,.011,.09,0.0,0.0,90.001*%
%ADD297MACRO297*%
%ADD288O,.032X.036*%
%AMMACRO277*
4,1,16,.0495,-.045,
.0495,.045,
-.0495,.045,
-.0495,.032,
-.0185,.032,
-.0185,.01933,
-.0495,.01933,
-.0495,.00633,
-.0185,.00633,
-.0185,-.00633,
-.0495,-.00633,
-.0495,-.01933,
-.0185,-.01933,
-.0185,-.032,
-.0495,-.032,
-.0495,-.045,
.0495,-.045,
0.0*
%
%ADD277MACRO277*%
%ADD243R,.028X.01*%
%ADD242R,.01X.028*%
%AMMACRO197*
21,1,.02,.005,0.0,0.0,141.8*%
%ADD197MACRO197*%
%AMMACRO196*
21,1,.02,.005,0.0,0.0,142.016*%
%ADD196MACRO196*%
%AMMACRO183*
21,1,.02,.005,0.0,0.0,152.6*%
%ADD183MACRO183*%
%ADD167R,.045X.02*%
%ADD146R,.012X.027*%
%ADD77R,.016X.04*%
%ADD72C,.111*%
%ADD50R,.03X.035*%
%ADD47R,.145X.105*%
%ADD20R,.014X.06*%
%ADD341R,.071X.032*%
%ADD334R,.028X.012*%
%ADD328R,.061X.024*%
%ADD248R,.02X.047*%
%AMMACRO195*
21,1,.02,.005,0.0,0.0,141.9*%
%ADD195MACRO195*%
%ADD148R,.027X.012*%
%ADD87R,.012X.037*%
%ADD314O,.07X.046*%
%AMMACRO310*
4,1,21,-.0225,.006,
.0165,.006,
.017542,.005909,
.018552,.005638,
.0195,.005196,
.020357,.004596,
.021096,.003857,
.021696,.003,
.022138,.002052,
.022409,.001042,
.0225,0.0,
.022409,-.001042,
.022138,-.002052,
.021696,-.003,
.021096,-.003857,
.020357,-.004596,
.0195,-.005196,
.018552,-.005638,
.017542,-.005909,
.0165,-.006,
-.0225,-.006,
-.0225,.006,
0.0*
%
%ADD310MACRO310*%
%ADD265R,.045X.041*%
%ADD211R,.02X.047*%
%AMMACRO200*
21,1,.02,.005,0.0,0.0,110.716*%
%ADD200MACRO200*%
%AMMACRO171*
21,1,.02,.005,0.0,0.0,145.6*%
%ADD171MACRO171*%
%ADD111R,.05X.018*%
%ADD82R,.065X.02*%
%ADD53C,.14*%
%ADD283R,.02X.094*%
%AMMACRO258*
4,1,13,.05895,.0275,
.055324,.025079,
.051332,.023324,
.047096,.022289,
.042745,.022006,
.03841,.022482,
.034225,.023704,
.030315,.025634,
.02765,.0275,
-.115,.0275,
-.115,-.0275,
.115,-.0275,
.115,.0275,
.05895,.0275,
0.0*
%
%ADD258MACRO258*%
%AMMACRO249*
21,1,.02,.005,0.0,0.0,134.9*%
%ADD249MACRO249*%
%ADD216R,.041X.045*%
%ADD322R,.013X.039*%
%ADD268R,.063X.024*%
%ADD215R,.063X.06*%
%AMMACRO186*
21,1,.02,.005,0.0,0.0,161.721*%
%ADD186MACRO186*%
%ADD133R,.018X.07*%
%ADD64R,.063X.061*%
%ADD344R,.032X.039*%
%ADD286R,.039X.013*%
%ADD275R,.063X.035*%
%ADD267R,.071X.035*%
%ADD260R,.064X.024*%
%AMMACRO182*
21,1,.02,.005,0.0,0.0,153.28*%
%ADD182MACRO182*%
%AMMACRO154*
4,1,21,.0055,-.0095,
.005416,-.010455,
.005168,-.011381,
.004763,-.01225,
.004213,-.013035,
.003535,-.013713,
.00275,-.014263,
.001881,-.014668,
.000955,-.014916,
0.0,-.015,
-.000955,-.014916,
-.001881,-.014668,
-.00275,-.014263,
-.003535,-.013713,
-.004213,-.013035,
-.004763,-.01225,
-.005168,-.011381,
-.005416,-.010455,
-.0055,-.0095,
-.0055,.015,
.0055,.015,
.0055,-.0095,
0.0*
%
%ADD154MACRO154*%
%ADD144R,.07X.018*%
%ADD14R,.061X.063*%
%ADD327R,.037X.016*%
%ADD325R,.035X.063*%
%ADD307R,.055X.08*%
%AMMACRO303*
4,1,21,.004,-.013,
-.004,-.013,
-.004,.009,
-.003939,.009695,
-.003759,.010368,
-.003464,.011,
-.003064,.011571,
-.002571,.012064,
-.002,.012464,
-.001368,.012759,
-.000695,.012939,
0.0,.013,
.000695,.012939,
.001368,.012759,
.002,.012464,
.002571,.012064,
.003064,.011571,
.003464,.011,
.003759,.010368,
.003939,.009695,
.004,.009,
.004,-.013,
0.0*
%
%ADD303MACRO303*%
%ADD280R,.02X.079*%
%AMMACRO141*
4,1,21,-.006,-.015,
-.006,.009,
-.005909,.010042,
-.005638,.011052,
-.005196,.012,
-.004596,.012857,
-.003857,.013596,
-.003,.014196,
-.002052,.014638,
-.001042,.014909,
0.0,.015,
.001042,.014909,
.002052,.014638,
.003,.014196,
.003857,.013596,
.004596,.012857,
.005196,.012,
.005638,.011052,
.005909,.010042,
.006,.009,
.006,-.015,
-.006,-.015,
0.0*
%
%ADD141MACRO141*%
%ADD130R,.065X.033*%
%AMMACRO246*
4,1,21,-.015,.006,
.009,.006,
.010042,.005909,
.011052,.005638,
.012,.005196,
.012857,.004596,
.013596,.003857,
.014196,.003,
.014638,.002052,
.014909,.001042,
.015,0.0,
.014909,-.001042,
.014638,-.002052,
.014196,-.003,
.013596,-.003857,
.012857,-.004596,
.012,-.005196,
.011052,-.005638,
.010042,-.005909,
.009,-.006,
-.015,-.006,
-.015,.006,
0.0*
%
%ADD246MACRO246*%
%AMMACRO181*
21,1,.02,.005,0.0,0.0,152.58*%
%ADD181MACRO181*%
%AMMACRO176*
21,1,.02,.005,0.0,0.0,125.373*%
%ADD176MACRO176*%
%ADD163R,.015X.085*%
%ADD51R,.045X.055*%
%ADD230R,.085X.015*%
%AMMACRO204*
21,1,.02,.005,0.0,0.0,168.7*%
%ADD204MACRO204*%
%AMMACRO168*
21,1,.02,.005,0.0,0.0,142.195*%
%ADD168MACRO168*%
%ADD161R,.055X.045*%
%ADD123R,.039X.035*%
%AMMACRO120*
21,1,.035,.039,0.0,0.0,45.*%
%ADD120MACRO120*%
%ADD92R,.13X.13*%
%AMMACRO65*
4,1,21,-.01,-.004,
-.010695,-.003939,
-.011368,-.003759,
-.012,-.003464,
-.012571,-.003064,
-.013064,-.002571,
-.013464,-.002,
-.013759,-.001368,
-.013939,-.000695,
-.014,0.0,
-.013939,.000695,
-.013759,.001368,
-.013464,.002,
-.013064,.002571,
-.012571,.003064,
-.012,.003464,
-.011368,.003759,
-.010695,.003939,
-.01,.004,
.014,.004,
.014,-.004,
-.01,-.004,
0.0*
%
%ADD65MACRO65*%
%AMMACRO37*
4,1,21,-.004,.01,
-.003939,.010695,
-.003759,.011368,
-.003464,.012,
-.003064,.012571,
-.002571,.013064,
-.002,.013464,
-.001368,.013759,
-.000695,.013939,
0.0,.014,
.000695,.013939,
.001368,.013759,
.002,.013464,
.002571,.013064,
.003064,.012571,
.003464,.012,
.003759,.011368,
.003939,.010695,
.004,.01,
.004,-.014,
-.004,-.014,
-.004,.01,
0.0*
%
%ADD37MACRO37*%
%ADD212R,.076X.025*%
%AMMACRO179*
21,1,.02,.005,0.0,0.0,125.573*%
%ADD179MACRO179*%
%AMMACRO178*
21,1,.02,.005,0.0,0.0,124.673*%
%ADD178MACRO178*%
%ADD119R,.035X.039*%
%ADD54R,.14X.14*%
%ADD11C,.363*%
%ADD342O,.094X.048*%
%ADD336R,.075X.045*%
%ADD287R,.072X.057*%
%ADD273R,.047X.055*%
%AMMACRO173*
21,1,.02,.005,0.0,0.0,124.773*%
%ADD173MACRO173*%
%ADD250R,.09X.095*%
%AMMACRO199*
21,1,.02,.005,0.0,0.0,157.651*%
%ADD199MACRO199*%
%AMMACRO177*
21,1,.02,.005,0.0,0.0,125.386*%
%ADD177MACRO177*%
%AMMACRO174*
21,1,.02,.005,0.0,0.0,124.873*%
%ADD174MACRO174*%
%AMMACRO152*
4,1,21,-.0055,.0095,
-.005416,.010455,
-.005168,.011381,
-.004763,.01225,
-.004213,.013035,
-.003535,.013713,
-.00275,.014263,
-.001881,.014668,
-.000955,.014916,
0.0,.015,
.000955,.014916,
.001881,.014668,
.00275,.014263,
.003535,.013713,
.004213,.013035,
.004763,.01225,
.005168,.011381,
.005416,.010455,
.0055,.0095,
.0055,-.015,
-.0055,-.015,
-.0055,.0095,
0.0*
%
%ADD152MACRO152*%
%ADD102R,.142X.142*%
%ADD345R,.059X.028*%
%ADD317O,.098X.046*%
%ADD313R,.161X.161*%
%AMMACRO311*
4,1,21,.006,.0225,
.006,-.0165,
.005909,-.017542,
.005638,-.018552,
.005196,-.0195,
.004596,-.020357,
.003857,-.021096,
.003,-.021696,
.002052,-.022138,
.001042,-.022409,
0.0,-.0225,
-.001042,-.022409,
-.002052,-.022138,
-.003,-.021696,
-.003857,-.021096,
-.004596,-.020357,
-.005196,-.0195,
-.005638,-.018552,
-.005909,-.017542,
-.006,-.0165,
-.006,.0225,
.006,.0225,
0.0*
%
%ADD311MACRO311*%
%ADD293R,.095X.09*%
%AMMACRO274*
21,1,.02,.005,0.0,0.0,134.828*%
%ADD274MACRO274*%
%ADD261C,.276*%
%AMMACRO207*
21,1,.02,.005,0.0,0.0,179.9*%
%ADD207MACRO207*%
%AMMACRO175*
21,1,.02,.005,0.0,0.0,124.973*%
%ADD175MACRO175*%
%AMMACRO172*
21,1,.02,.005,0.0,0.0,125.486*%
%ADD172MACRO172*%
%AMMACRO140*
4,1,21,.006,.015,
.006,-.009,
.005909,-.010042,
.005638,-.011052,
.005196,-.012,
.004596,-.012857,
.003857,-.013596,
.003,-.014196,
.002052,-.014638,
.001042,-.014909,
0.0,-.015,
-.001042,-.014909,
-.002052,-.014638,
-.003,-.014196,
-.003857,-.013596,
-.004596,-.012857,
-.005196,-.012,
-.005638,-.011052,
-.005909,-.010042,
-.006,-.009,
-.006,.015,
.006,.015,
0.0*
%
%ADD140MACRO140*%
%ADD44R,.079X.071*%
%AMMACRO256*
4,1,21,.015,-.006,
-.009,-.006,
-.010042,-.005909,
-.011052,-.005638,
-.012,-.005196,
-.012857,-.004596,
-.013596,-.003857,
-.014196,-.003,
-.014638,-.002052,
-.014909,-.001042,
-.015,0.0,
-.014909,.001042,
-.014638,.002052,
-.014196,.003,
-.013596,.003857,
-.012857,.004596,
-.012,.005196,
-.011052,.005638,
-.010042,.005909,
-.009,.006,
.015,.006,
.015,-.006,
0.0*
%
%ADD256MACRO256*%
%ADD241R,.071X.079*%
%AMMACRO180*
21,1,.02,.005,0.0,0.0,157.851*%
%ADD180MACRO180*%
%AMMACRO151*
4,1,21,-.0095,-.0055,
-.010455,-.005416,
-.011381,-.005168,
-.01225,-.004763,
-.013035,-.004213,
-.013713,-.003535,
-.014263,-.00275,
-.014668,-.001881,
-.014916,-.000955,
-.015,0.0,
-.014916,.000955,
-.014668,.001881,
-.014263,.00275,
-.013713,.003535,
-.013035,.004213,
-.01225,.004763,
-.011381,.005168,
-.010455,.005416,
-.0095,.0055,
.015,.0055,
.015,-.0055,
-.0095,-.0055,
0.0*
%
%ADD151MACRO151*%
%ADD164R,.063X.089*%
%AMMACRO139*
4,1,21,-.015,.006,
.009,.006,
.010042,.005909,
.011052,.005638,
.012,.005196,
.012857,.004596,
.013596,.003857,
.014196,.003,
.014638,.002052,
.014909,.001042,
.015,0.0,
.014909,-.001042,
.014638,-.002052,
.014196,-.003,
.013596,-.003857,
.012857,-.004596,
.012,-.005196,
.011052,-.005638,
.010042,-.005909,
.009,-.006,
-.015,-.006,
-.015,.006,
0.0*
%
%ADD139MACRO139*%
%ADD40R,.145X.145*%
%AMMACRO247*
4,1,21,.006,.015,
.006,-.009,
.005909,-.010042,
.005638,-.011052,
.005196,-.012,
.004596,-.012857,
.003857,-.013596,
.003,-.014196,
.002052,-.014638,
.001042,-.014909,
0.0,-.015,
-.001042,-.014909,
-.002052,-.014638,
-.003,-.014196,
-.003857,-.013596,
-.004596,-.012857,
-.005196,-.012,
-.005638,-.011052,
-.005909,-.010042,
-.006,-.009,
-.006,.015,
.006,.015,
0.0*
%
%ADD247MACRO247*%
%AMMACRO218*
21,1,.02,.005,0.0,0.0,164.882*%
%ADD218MACRO218*%
%ADD105R,.089X.063*%
%ADD52R,.079X.092*%
%AMMACRO301*
4,1,21,-.013,-.004,
-.013,.004,
.009,.004,
.009695,.003939,
.010368,.003759,
.011,.003464,
.011571,.003064,
.012064,.002571,
.012464,.002,
.012759,.001368,
.012939,.000695,
.013,0.0,
.012939,-.000695,
.012759,-.001368,
.012464,-.002,
.012064,-.002571,
.011571,-.003064,
.011,-.003464,
.010368,-.003759,
.009695,-.003939,
.009,-.004,
-.013,-.004,
0.0*
%
%ADD301MACRO301*%
%ADD257R,.049X.068*%
%ADD240R,.092X.079*%
%ADD142R,.246X.246*%
%AMMACRO112*
4,1,8,.0585,-.0835,
.0585,.0835,
-.0585,.0835,
-.0585,.04275,
-.0185,.04275,
-.0185,-.04275,
-.0585,-.04275,
-.0585,-.0835,
.0585,-.0835,
0.0*
%
%ADD112MACRO112*%
%AMMACRO312*
4,1,21,-.006,-.0225,
-.006,.0165,
-.005909,.017542,
-.005638,.018552,
-.005196,.0195,
-.004596,.020357,
-.003857,.021096,
-.003,.021696,
-.002052,.022138,
-.001042,.022409,
0.0,.0225,
.001042,.022409,
.002052,.022138,
.003,.021696,
.003857,.021096,
.004596,.020357,
.005196,.0195,
.005638,.018552,
.005909,.017542,
.006,.0165,
.006,-.0225,
-.006,-.0225,
0.0*
%
%ADD312MACRO312*%
%ADD150R,.079X.059*%
%AMMACRO66*
4,1,21,-.004,.01,
-.003939,.010695,
-.003759,.011368,
-.003464,.012,
-.003064,.012571,
-.002571,.013064,
-.002,.013464,
-.001368,.013759,
-.000695,.013939,
0.0,.014,
.000695,.013939,
.001368,.013759,
.002,.013464,
.002571,.013064,
.003064,.012571,
.003464,.012,
.003759,.011368,
.003939,.010695,
.004,.01,
.004,-.014,
-.004,-.014,
-.004,.01,
0.0*
%
%ADD66MACRO66*%
%AMMACRO38*
4,1,21,.01,.004,
.010695,.003939,
.011368,.003759,
.012,.003464,
.012571,.003064,
.013064,.002571,
.013464,.002,
.013759,.001368,
.013939,.000695,
.014,0.0,
.013939,-.000695,
.013759,-.001368,
.013464,-.002,
.013064,-.002571,
.012571,-.003064,
.012,-.003464,
.011368,-.003759,
.010695,-.003939,
.01,-.004,
-.014,-.004,
-.014,.004,
.01,.004,
0.0*
%
%ADD38MACRO38*%
%AMMACRO309*
4,1,21,.0225,-.006,
-.0165,-.006,
-.017542,-.005909,
-.018552,-.005638,
-.0195,-.005196,
-.020357,-.004596,
-.021096,-.003857,
-.021696,-.003,
-.022138,-.002052,
-.022409,-.001042,
-.0225,0.0,
-.022409,.001042,
-.022138,.002052,
-.021696,.003,
-.021096,.003857,
-.020357,.004596,
-.0195,.005196,
-.018552,.005638,
-.017542,.005909,
-.0165,.006,
.0225,.006,
.0225,-.006,
0.0*
%
%ADD309MACRO309*%
%AMMACRO156*
4,1,40,-.007,-.011,
.007,-.011,
.007695,-.010939,
.008368,-.010759,
.009,-.010464,
.009571,-.010064,
.010064,-.009571,
.010464,-.009,
.010759,-.008368,
.010939,-.007695,
.011,-.007,
.011,.007,
.010939,.007695,
.010759,.008368,
.010464,.009,
.010064,.009571,
.009571,.010064,
.009,.010464,
.008368,.010759,
.007695,.010939,
.007,.011,
-.007,.011,
-.007695,.010939,
-.008368,.010759,
-.009,.010464,
-.009571,.010064,
-.010064,.009571,
-.010464,.009,
-.010759,.008368,
-.010939,.007695,
-.011,.007,
-.011,-.007,
-.010939,-.007695,
-.010759,-.008368,
-.010464,-.009,
-.010064,-.009571,
-.009571,-.010064,
-.009,-.010464,
-.008368,-.010759,
-.007695,-.010939,
-.007,-.011,
0.0*
%
%ADD156MACRO156*%
%AMMACRO90*
4,1,40,-.008,-.012,
.008,-.012,
.008695,-.011939,
.009368,-.011759,
.01,-.011464,
.010571,-.011064,
.011064,-.010571,
.011464,-.01,
.011759,-.009368,
.011939,-.008695,
.012,-.008,
.012,.008,
.011939,.008695,
.011759,.009368,
.011464,.01,
.011064,.010571,
.010571,.011064,
.01,.011464,
.009368,.011759,
.008695,.011939,
.008,.012,
-.008,.012,
-.008695,.011939,
-.009368,.011759,
-.01,.011464,
-.010571,.011064,
-.011064,.010571,
-.011464,.01,
-.011759,.009368,
-.011939,.008695,
-.012,.008,
-.012,-.008,
-.011939,-.008695,
-.011759,-.009368,
-.011464,-.01,
-.011064,-.010571,
-.010571,-.011064,
-.01,-.011464,
-.009368,-.011759,
-.008695,-.011939,
-.008,-.012,
0.0*
%
%ADD90MACRO90*%
%AMMACRO33*
4,1,40,.012,-.008,
.012,.008,
.011939,.008695,
.011759,.009368,
.011464,.01,
.011064,.010571,
.010571,.011064,
.01,.011464,
.009368,.011759,
.008695,.011939,
.008,.012,
-.008,.012,
-.008695,.011939,
-.009368,.011759,
-.01,.011464,
-.010571,.011064,
-.011064,.010571,
-.011464,.01,
-.011759,.009368,
-.011939,.008695,
-.012,.008,
-.012,-.008,
-.011939,-.008695,
-.011759,-.009368,
-.011464,-.01,
-.011064,-.010571,
-.010571,-.011064,
-.01,-.011464,
-.009368,-.011759,
-.008695,-.011939,
-.008,-.012,
.008,-.012,
.008695,-.011939,
.009368,-.011759,
.01,-.011464,
.010571,-.011064,
.011064,-.010571,
.011464,-.01,
.011759,-.009368,
.011939,-.008695,
.012,-.008,
0.0*
%
%ADD33MACRO33*%
%AMMACRO254*
21,1,.02,.005,0.0,0.0,179.828*%
%ADD254MACRO254*%
%AMMACRO219*
21,1,.02,.005,0.0,0.0,164.879*%
%ADD219MACRO219*%
%AMMACRO62*
4,1,40,-.011,.007,
-.011,-.007,
-.010939,-.007695,
-.010759,-.008368,
-.010464,-.009,
-.010064,-.009571,
-.009571,-.010064,
-.009,-.010464,
-.008368,-.010759,
-.007695,-.010939,
-.007,-.011,
.007,-.011,
.007695,-.010939,
.008368,-.010759,
.009,-.010464,
.009571,-.010064,
.010064,-.009571,
.010464,-.009,
.010759,-.008368,
.010939,-.007695,
.011,-.007,
.011,.007,
.010939,.007695,
.010759,.008368,
.010464,.009,
.010064,.009571,
.009571,.010064,
.009,.010464,
.008368,.010759,
.007695,.010939,
.007,.011,
-.007,.011,
-.007695,.010939,
-.008368,.010759,
-.009,.010464,
-.009571,.010064,
-.010064,.009571,
-.010464,.009,
-.010759,.008368,
-.010939,.007695,
-.011,.007,
0.0*
%
%ADD62MACRO62*%
%AMMACRO300*
4,1,21,.013,.004,
.013,-.004,
-.009,-.004,
-.009695,-.003939,
-.010368,-.003759,
-.011,-.003464,
-.011571,-.003064,
-.012064,-.002571,
-.012464,-.002,
-.012759,-.001368,
-.012939,-.000695,
-.013,0.0,
-.012939,.000695,
-.012759,.001368,
-.012464,.002,
-.012064,.002571,
-.011571,.003064,
-.011,.003464,
-.010368,.003759,
-.009695,.003939,
-.009,.004,
.013,.004,
0.0*
%
%ADD300MACRO300*%
%AMMACRO226*
4,1,40,.017,-.013,
.017,.013,
.016939,.013695,
.016759,.014368,
.016464,.015,
.016064,.015571,
.015571,.016064,
.015,.016464,
.014368,.016759,
.013695,.016939,
.013,.017,
-.013,.017,
-.013695,.016939,
-.014368,.016759,
-.015,.016464,
-.015571,.016064,
-.016064,.015571,
-.016464,.015,
-.016759,.014368,
-.016939,.013695,
-.017,.013,
-.017,-.013,
-.016939,-.013695,
-.016759,-.014368,
-.016464,-.015,
-.016064,-.015571,
-.015571,-.016064,
-.015,-.016464,
-.014368,-.016759,
-.013695,-.016939,
-.013,-.017,
.013,-.017,
.013695,-.016939,
.014368,-.016759,
.015,-.016464,
.015571,-.016064,
.016064,-.015571,
.016464,-.015,
.016759,-.014368,
.016939,-.013695,
.017,-.013,
0.0*
%
%ADD226MACRO226*%
%AMMACRO35*
4,1,40,.013,.017,
-.013,.017,
-.013695,.016939,
-.014368,.016759,
-.015,.016464,
-.015571,.016064,
-.016064,.015571,
-.016464,.015,
-.016759,.014368,
-.016939,.013695,
-.017,.013,
-.017,-.013,
-.016939,-.013695,
-.016759,-.014368,
-.016464,-.015,
-.016064,-.015571,
-.015571,-.016064,
-.015,-.016464,
-.014368,-.016759,
-.013695,-.016939,
-.013,-.017,
.013,-.017,
.013695,-.016939,
.014368,-.016759,
.015,-.016464,
.015571,-.016064,
.016064,-.015571,
.016464,-.015,
.016759,-.014368,
.016939,-.013695,
.017,-.013,
.017,.013,
.016939,.013695,
.016759,.014368,
.016464,.015,
.016064,.015571,
.015571,.016064,
.015,.016464,
.014368,.016759,
.013695,.016939,
.013,.017,
0.0*
%
%ADD35MACRO35*%
%AMMACRO272*
21,1,.02,.005,0.0,0.0,179.695*%
%ADD272MACRO272*%
%AMMACRO299*
4,1,21,-.004,.013,
.004,.013,
.004,-.009,
.003939,-.009695,
.003759,-.010368,
.003464,-.011,
.003064,-.011571,
.002571,-.012064,
.002,-.012464,
.001368,-.012759,
.000695,-.012939,
0.0,-.013,
-.000695,-.012939,
-.001368,-.012759,
-.002,-.012464,
-.002571,-.012064,
-.003064,-.011571,
-.003464,-.011,
-.003759,-.010368,
-.003939,-.009695,
-.004,-.009,
-.004,.013,
0.0*
%
%ADD299MACRO299*%
%AMMACRO73*
4,1,21,-.01,-.004,
-.010695,-.003939,
-.011368,-.003759,
-.012,-.003464,
-.012571,-.003064,
-.013064,-.002571,
-.013464,-.002,
-.013759,-.001368,
-.013939,-.000695,
-.014,0.0,
-.013939,.000695,
-.013759,.001368,
-.013464,.002,
-.013064,.002571,
-.012571,.003064,
-.012,.003464,
-.011368,.003759,
-.010695,.003939,
-.01,.004,
.014,.004,
.014,-.004,
-.01,-.004,
0.0*
%
%ADD73MACRO73*%
%AMMACRO68*
4,1,21,.004,-.01,
.003939,-.010695,
.003759,-.011368,
.003464,-.012,
.003064,-.012571,
.002571,-.013064,
.002,-.013464,
.001368,-.013759,
.000695,-.013939,
0.0,-.014,
-.000695,-.013939,
-.001368,-.013759,
-.002,-.013464,
-.002571,-.013064,
-.003064,-.012571,
-.003464,-.012,
-.003759,-.011368,
-.003939,-.010695,
-.004,-.01,
-.004,.014,
.004,.014,
.004,-.01,
0.0*
%
%ADD68MACRO68*%
%AMMACRO67*
4,1,21,.01,.004,
.010695,.003939,
.011368,.003759,
.012,.003464,
.012571,.003064,
.013064,.002571,
.013464,.002,
.013759,.001368,
.013939,.000695,
.014,0.0,
.013939,-.000695,
.013759,-.001368,
.013464,-.002,
.013064,-.002571,
.012571,-.003064,
.012,-.003464,
.011368,-.003759,
.010695,-.003939,
.01,-.004,
-.014,-.004,
-.014,.004,
.01,.004,
0.0*
%
%ADD67MACRO67*%
%AMMACRO39*
4,1,21,.004,-.01,
.003939,-.010695,
.003759,-.011368,
.003464,-.012,
.003064,-.012571,
.002571,-.013064,
.002,-.013464,
.001368,-.013759,
.000695,-.013939,
0.0,-.014,
-.000695,-.013939,
-.001368,-.013759,
-.002,-.013464,
-.002571,-.013064,
-.003064,-.012571,
-.003464,-.012,
-.003759,-.011368,
-.003939,-.010695,
-.004,-.01,
-.004,.014,
.004,.014,
.004,-.01,
0.0*
%
%ADD39MACRO39*%
%AMMACRO157*
4,1,40,-.007,-.011,
.007,-.011,
.007695,-.010939,
.008368,-.010759,
.009,-.010464,
.009571,-.010064,
.010064,-.009571,
.010464,-.009,
.010759,-.008368,
.010939,-.007695,
.011,-.007,
.011,.007,
.010939,.007695,
.010759,.008368,
.010464,.009,
.010064,.009571,
.009571,.010064,
.009,.010464,
.008368,.010759,
.007695,.010939,
.007,.011,
-.007,.011,
-.007695,.010939,
-.008368,.010759,
-.009,.010464,
-.009571,.010064,
-.010064,.009571,
-.010464,.009,
-.010759,.008368,
-.010939,.007695,
-.011,.007,
-.011,-.007,
-.010939,-.007695,
-.010759,-.008368,
-.010464,-.009,
-.010064,-.009571,
-.009571,-.010064,
-.009,-.010464,
-.008368,-.010759,
-.007695,-.010939,
-.007,-.011,
0.0*
%
%ADD157MACRO157*%
%AMMACRO91*
4,1,40,-.008,-.012,
.008,-.012,
.008695,-.011939,
.009368,-.011759,
.01,-.011464,
.010571,-.011064,
.011064,-.010571,
.011464,-.01,
.011759,-.009368,
.011939,-.008695,
.012,-.008,
.012,.008,
.011939,.008695,
.011759,.009368,
.011464,.01,
.011064,.010571,
.010571,.011064,
.01,.011464,
.009368,.011759,
.008695,.011939,
.008,.012,
-.008,.012,
-.008695,.011939,
-.009368,.011759,
-.01,.011464,
-.010571,.011064,
-.011064,.010571,
-.011464,.01,
-.011759,.009368,
-.011939,.008695,
-.012,.008,
-.012,-.008,
-.011939,-.008695,
-.011759,-.009368,
-.011464,-.01,
-.011064,-.010571,
-.010571,-.011064,
-.01,-.011464,
-.009368,-.011759,
-.008695,-.011939,
-.008,-.012,
0.0*
%
%ADD91MACRO91*%
%AMMACRO34*
4,1,40,.012,-.008,
.012,.008,
.011939,.008695,
.011759,.009368,
.011464,.01,
.011064,.010571,
.010571,.011064,
.01,.011464,
.009368,.011759,
.008695,.011939,
.008,.012,
-.008,.012,
-.008695,.011939,
-.009368,.011759,
-.01,.011464,
-.010571,.011064,
-.011064,.010571,
-.011464,.01,
-.011759,.009368,
-.011939,.008695,
-.012,.008,
-.012,-.008,
-.011939,-.008695,
-.011759,-.009368,
-.011464,-.01,
-.011064,-.010571,
-.010571,-.011064,
-.01,-.011464,
-.009368,-.011759,
-.008695,-.011939,
-.008,-.012,
.008,-.012,
.008695,-.011939,
.009368,-.011759,
.01,-.011464,
.010571,-.011064,
.011064,-.010571,
.011464,-.01,
.011759,-.009368,
.011939,-.008695,
.012,-.008,
0.0*
%
%ADD34MACRO34*%
%AMMACRO63*
4,1,40,-.011,.007,
-.011,-.007,
-.010939,-.007695,
-.010759,-.008368,
-.010464,-.009,
-.010064,-.009571,
-.009571,-.010064,
-.009,-.010464,
-.008368,-.010759,
-.007695,-.010939,
-.007,-.011,
.007,-.011,
.007695,-.010939,
.008368,-.010759,
.009,-.010464,
.009571,-.010064,
.010064,-.009571,
.010464,-.009,
.010759,-.008368,
.010939,-.007695,
.011,-.007,
.011,.007,
.010939,.007695,
.010759,.008368,
.010464,.009,
.010064,.009571,
.009571,.010064,
.009,.010464,
.008368,.010759,
.007695,.010939,
.007,.011,
-.007,.011,
-.007695,.010939,
-.008368,.010759,
-.009,.010464,
-.009571,.010064,
-.010064,.009571,
-.010464,.009,
-.010759,.008368,
-.010939,.007695,
-.011,.007,
0.0*
%
%ADD63MACRO63*%
%ADD347C,.011*%
%ADD348C,.013*%
%ADD349C,.004*%
%ADD350C,.00401*%
%ADD351C,.006*%
%ADD352C,.005*%
%ADD353C,.0042*%
%ADD354C,.007*%
%ADD355C,.0035*%
%ADD356C,.008*%
%ADD357C,.009*%
%ADD358C,.0045*%
%ADD359C,.0055*%
%ADD360C,.00352*%
%ADD361C,.0046*%
%ADD362C,.0065*%
%ADD363C,.00425*%
%ADD364C,.0049*%
%ADD365C,.00395*%
%ADD392O,.07202X.12102*%
%ADD397R,.008X.016*%
%ADD382C,.03004*%
%ADD390R,.008X.018*%
%ADD385C,.03204*%
%ADD398C,.06204*%
%ADD393C,.02803*%
%ADD391C,.02804*%
%ADD402C,.06504*%
%ADD388C,.02805*%
%ADD380C,.02904*%
%ADD366C,.09204*%
%ADD396C,.03904*%
%ADD395C,.07504*%
%ADD389C,.02806*%
%ADD387C,.02807*%
%ADD394R,.01638X.008*%
%ADD381C,.08604*%
%ADD400C,.02296*%
%ADD386C,.20004*%
%ADD384C,.12104*%
%ADD369C,.11204*%
%ADD375R,.23X.197*%
%ADD370C,.15004*%
%ADD367C,.11404*%
%ADD373R,.251X.197*%
%ADD371C,.15006*%
%ADD399C,.15502*%
%ADD383R,.008X.008*%
%ADD377R,.252X.197*%
%ADD376R,.234X.197*%
%ADD378R,.237X.197*%
%ADD368C,.11815*%
%ADD401R,.04202X.08108*%
%ADD379R,.229X.197*%
%ADD374R,.249X.197*%
%ADD372R,.278X.197*%
G75*
%LPD*%
G75*
G36*
G01X-19810Y-60000D02*
Y-34500D01*
X1973300D01*
Y-60000D01*
X-19810D01*
G37*
G36*
G01X-21500Y21200D02*
X-21700Y21400D01*
Y60600D01*
X-21100Y61200D01*
X-18542D01*
X-17724Y60382D01*
Y53014D01*
X-13522Y48812D01*
Y46648D01*
X-13500Y46625D01*
Y21700D01*
X-14000Y21200D01*
X-21500D01*
G37*
G36*
G01X-9252Y69658D02*
X-16802D01*
X-18802Y71658D01*
Y84958D01*
X-17400Y86360D01*
X-5780D01*
X-5002Y85582D01*
Y73908D01*
X-9252Y69658D01*
G37*
G36*
G01X-11230Y21910D02*
X-11940Y22620D01*
Y48720D01*
X-16722Y53503D01*
Y60797D01*
X-16740Y60814D01*
Y65193D01*
X-13304Y68629D01*
X-7819D01*
X-4810Y65620D01*
Y53290D01*
X-370Y48850D01*
Y35390D01*
X-3558Y32202D01*
Y27428D01*
G03Y27190I2211J-119D01*
G01Y22752D01*
X-4400Y21910D01*
X-11230D01*
G37*
G36*
G01X-18900Y170200D02*
X-21300Y172600D01*
Y174700D01*
X-21600Y175000D01*
Y341400D01*
X-19200Y343800D01*
X5100D01*
X8800Y340100D01*
Y313000D01*
X-3500Y300700D01*
Y275000D01*
X-2760Y274260D01*
Y268368D01*
X-417Y266026D01*
X2000D01*
Y237500D01*
X7000Y232500D01*
Y195800D01*
X11200Y191600D01*
X48600D01*
X52800Y187400D01*
Y171700D01*
X51300Y170200D01*
X25476D01*
G02X25203Y170893I0J400D01*
G03X11253I-6975J7493D01*
G02X10980Y170200I-273J-293D01*
G01X-18900D01*
G37*
G36*
G01X1972600Y662747D02*
Y637600D01*
X12918D01*
G03X4168I-4375J-1427D01*
G01X-20412D01*
G02X-20621Y638189I726J589D01*
G01Y661811D01*
G02X-19685Y662747I936J0D01*
G01X1972600D01*
G37*
G36*
G01X32500Y6025D02*
X46500D01*
Y-7975D01*
X32500D01*
Y6025D01*
G37*
G36*
G01X19976Y20432D02*
X19118Y21290D01*
Y24090D01*
X19080Y24128D01*
X18102Y25107D01*
Y25166D01*
X17462Y25806D01*
G03X17200Y26015I-1062J-1062D01*
G01Y30300D01*
X17000Y30500D01*
X13000D01*
X12995Y30495D01*
X11605D01*
X11600Y30500D01*
X10800D01*
X10500Y30800D01*
Y37000D01*
X10900Y37400D01*
X18800D01*
X19800Y38400D01*
Y49072D01*
X19412Y49460D01*
Y51458D01*
X19395D01*
Y52710D01*
X19426D01*
Y54712D01*
X19395D01*
Y55276D01*
X18426Y56245D01*
Y56533D01*
X17687Y57273D01*
G03X17464Y57456I-1060J-1064D01*
G01Y60910D01*
X17204Y61170D01*
Y61216D01*
X17158D01*
X17123Y61251D01*
X10885D01*
X10600Y61536D01*
Y68708D01*
X10878Y68986D01*
X18954D01*
X19190Y69222D01*
X19382D01*
Y69414D01*
X19800Y69832D01*
Y70272D01*
X19826Y70298D01*
Y80726D01*
X19884Y80784D01*
X20348D01*
Y82786D01*
X19952D01*
Y88852D01*
X21600Y90500D01*
X31500D01*
X33710Y88290D01*
Y79410D01*
X33200Y78900D01*
X29100D01*
X28400Y78200D01*
Y58000D01*
X29000Y57400D01*
Y55532D01*
X27525Y54057D01*
Y50710D01*
X28300Y49935D01*
Y29120D01*
X28310Y29110D01*
Y26963D01*
X28193Y26846D01*
X26324D01*
X25642Y26164D01*
Y24836D01*
X25803Y24675D01*
Y20711D01*
X25524Y20432D01*
X19976D01*
G37*
G36*
G01X30080Y27080D02*
X29600Y27560D01*
Y46000D01*
X30700Y47100D01*
X49500D01*
X51000Y45600D01*
Y29600D01*
X49250Y27850D01*
X36670D01*
X36259Y27439D01*
G03X35340Y27080I1429J-5015D01*
G01X30080D01*
G37*
G36*
G01X2276Y77177D02*
X2048Y77405D01*
Y88548D01*
X4200Y90700D01*
X18300D01*
X18786Y90214D01*
Y81986D01*
X18825Y81948D01*
Y70713D01*
X18335Y70223D01*
X11464D01*
X10992Y70695D01*
Y76135D01*
X10569Y76558D01*
X4918D01*
X4299Y77177D01*
X2276D01*
G37*
G36*
G01X10576Y38881D02*
Y44144D01*
X10439Y44281D01*
Y44327D01*
X9939Y44827D01*
X7110D01*
X6730Y45207D01*
Y49578D01*
X7172D01*
Y50936D01*
X7620Y51384D01*
X17732D01*
X17863Y51253D01*
Y48698D01*
X18380Y48181D01*
Y38881D01*
X10576D01*
G37*
G36*
G01X-2700Y69900D02*
X-3100Y70300D01*
Y76300D01*
X-2459Y76941D01*
X-442D01*
X-300Y76799D01*
Y76452D01*
X-302D01*
Y74648D01*
X-300D01*
Y73700D01*
X100Y73300D01*
X500D01*
X640Y73160D01*
Y70140D01*
X400Y69900D01*
X-2700D01*
G37*
G36*
G01X30100Y77400D02*
X32500D01*
X33100Y76800D01*
X42600D01*
X45600Y73800D01*
X49900D01*
X51000Y72700D01*
Y60600D01*
X44700Y54300D01*
X44600D01*
X43843Y53543D01*
X34657D01*
X34653Y53539D01*
X33270D01*
X30002Y56807D01*
Y58198D01*
X29600Y58600D01*
Y76900D01*
X30100Y77400D01*
G37*
G36*
G01X52550Y197050D02*
X13350D01*
X12100Y198300D01*
Y232700D01*
X9100Y235700D01*
Y264300D01*
X13900Y269100D01*
Y336900D01*
X16299Y339299D01*
X38759D01*
X41500Y336558D01*
Y285800D01*
X31800Y276100D01*
Y268300D01*
X31803Y268297D01*
Y267449D01*
X35600Y263652D01*
Y258800D01*
X35000Y258200D01*
X22200D01*
X20847Y259553D01*
X19134D01*
X17761Y258180D01*
Y253296D01*
X19030Y252027D01*
X20776D01*
X21749Y253000D01*
X35200D01*
X35600Y252600D01*
Y247800D01*
X38097Y245303D01*
Y227023D01*
X38098Y227022D01*
Y227015D01*
X45815Y219298D01*
X45822D01*
X45840Y219280D01*
X55418D01*
X55900Y218798D01*
Y208900D01*
X54000Y207000D01*
Y205002D01*
X53998D01*
Y202998D01*
X54000D01*
Y201502D01*
X53998D01*
Y199498D01*
X54000D01*
Y198500D01*
X52550Y197050D01*
G37*
G36*
G01X58668Y256422D02*
G03X56349Y258625I-1224J1034D01*
G02X56070Y258630I-137J146D01*
G01X55700Y259000D01*
X42500D01*
X42100Y259400D01*
Y263500D01*
X42294Y263694D01*
X42304Y263702D01*
G03X42648Y264046I-1304J1648D01*
G01X42656Y264056D01*
X45100Y266500D01*
X59300D01*
X60000Y267200D01*
X74300D01*
X75700Y265800D01*
Y239450D01*
X76177Y238973D01*
Y224477D01*
X75000Y223300D01*
X47472D01*
X42100Y228672D01*
Y252500D01*
X42200Y252600D01*
X55500D01*
X55764Y252864D01*
X56014Y252614D01*
G03X58986Y255586I1486J1486D01*
G01X58691Y255881D01*
G02X58668Y256422I282J283D01*
G37*
G36*
G01X33400Y422200D02*
X32814Y422786D01*
Y428304D01*
X33559Y429049D01*
Y434513D01*
X32783Y435289D01*
Y435580D01*
X32806D01*
Y437680D01*
X33889Y438762D01*
Y443556D01*
X34102Y443768D01*
X43528D01*
X43990Y443306D01*
Y429377D01*
X41554Y426941D01*
Y424901D01*
X38853Y422200D01*
X33400D01*
G37*
G36*
G01X273Y422065D02*
X-381Y422719D01*
Y432813D01*
X-372Y432842D01*
G03Y435346I-4116J1252D01*
G01X-381Y435375D01*
Y439648D01*
X307Y440336D01*
X3610D01*
X3617Y440328D01*
X10383D01*
X10408Y440322D01*
G03X10786Y440274I378J1463D01*
G01X15786D01*
G03X16164Y440322I0J1512D01*
G01X16189Y440328D01*
X19576D01*
X20198Y440950D01*
Y441281D01*
X20209Y441312D01*
G03Y442258I-1373J473D01*
G01X20198Y442289D01*
Y442580D01*
X18514Y444264D01*
Y460679D01*
X19902Y462067D01*
X29783D01*
X30300Y461550D01*
Y442865D01*
X30771Y442394D01*
Y434206D01*
X30498D01*
Y429204D01*
X30771D01*
Y423471D01*
X29369Y422069D01*
X25071D01*
X25067Y422065D01*
X273D01*
G37*
G36*
G01X33924Y445457D02*
X33871Y445510D01*
Y445889D01*
X33872D01*
Y450692D01*
X33871D01*
Y451017D01*
X35166Y452312D01*
X41120D01*
X46398Y457590D01*
Y470399D01*
X47322Y471323D01*
X53132D01*
X54213Y470242D01*
Y455574D01*
X44096Y445457D01*
X33924D01*
G37*
G36*
G01X1100Y496800D02*
Y510800D01*
X15100D01*
Y496800D01*
X1100D01*
G37*
G36*
G01X24802Y515500D02*
Y515502D01*
X22999D01*
X22800Y515700D01*
Y519300D01*
X24000Y520500D01*
X25500D01*
X28500Y517500D01*
Y516000D01*
X28001Y515502D01*
X26298D01*
Y515500D01*
X24802D01*
G37*
G36*
G01X31278Y493880D02*
Y489750D01*
X29364Y487836D01*
X26325D01*
X25776Y488385D01*
Y489274D01*
X27508Y491006D01*
Y501490D01*
X27566Y501548D01*
X28339D01*
X31048Y498839D01*
Y494110D01*
X31278Y493880D01*
G37*
G36*
G01X34788Y506401D02*
X34774Y506428D01*
G03X33928Y507274I-1774J-928D01*
G01X33901Y507288D01*
X32532Y508657D01*
X30643D01*
X29600Y509700D01*
Y512510D01*
X29604Y512530D01*
G03Y513470I-2304J470D01*
G01X29600Y513490D01*
Y524830D01*
X32370Y527600D01*
X42800D01*
X43400Y527000D01*
Y513800D01*
X41900Y512300D01*
Y507161D01*
X41024Y506285D01*
X34904D01*
X34788Y506401D01*
G37*
G36*
G01X51220Y497030D02*
X51040Y497210D01*
Y501210D01*
X49300Y502950D01*
Y512200D01*
X44900Y516600D01*
Y522109D01*
X45202Y522411D01*
X50049D01*
X51543Y523905D01*
Y524662D01*
X52081Y525200D01*
X58819D01*
X59639Y524380D01*
Y522963D01*
G03Y520837I1061J-1063D01*
G01Y517397D01*
G02X58965Y517106I-400J0D01*
G03Y514918I-1029J-1094D01*
G02X59639Y514627I274J-291D01*
G01Y510676D01*
X59698Y510617D01*
G02X59602Y509980I-282J-283D01*
G03X61630Y507952I698J-1330D01*
G02X62267Y508048I354J-186D01*
G01X65240Y505075D01*
Y497550D01*
X64720Y497030D01*
X51220D01*
G37*
G36*
G01X8002Y566856D02*
Y567622D01*
X7262Y568362D01*
G03X7200Y568420I-1056J-1067D01*
G01Y569300D01*
X7100Y569400D01*
Y573000D01*
X6900Y573200D01*
X700D01*
X500Y573400D01*
Y579900D01*
X600Y580000D01*
X9000D01*
X9800Y580800D01*
Y590524D01*
X7680Y592644D01*
Y593934D01*
X7845Y594100D01*
X34973D01*
X36236Y592837D01*
Y590862D01*
X34898Y589524D01*
X19058D01*
X18300Y588766D01*
Y571622D01*
X18598Y571324D01*
Y570985D01*
X19585Y569998D01*
X25636D01*
X26259Y569375D01*
Y565699D01*
X25671Y565111D01*
X22622D01*
X22054Y564543D01*
Y560646D01*
X22800Y559900D01*
X35400D01*
X36800Y561300D01*
Y565900D01*
X38500Y567600D01*
X41000D01*
X43800Y570400D01*
Y590680D01*
X40220Y594260D01*
Y604220D01*
X40500Y604500D01*
X44500D01*
X45000Y605000D01*
Y608287D01*
X45241Y608528D01*
X48818D01*
Y605476D01*
X48500Y605157D01*
Y566300D01*
X49300Y565500D01*
Y532200D01*
X49293Y532193D01*
Y531455D01*
X48411Y530573D01*
X34740D01*
X34368Y530944D01*
Y533328D01*
X39454D01*
X42078Y535952D01*
Y553182D01*
X39928Y555332D01*
X18374D01*
Y533328D01*
X31366D01*
Y532293D01*
X29663Y530590D01*
X22722D01*
X22005Y531307D01*
X18417D01*
X17000Y529890D01*
Y527900D01*
X16300Y527200D01*
X9828D01*
X9202Y527826D01*
Y529802D01*
X9168D01*
Y530400D01*
X7100Y532468D01*
Y536937D01*
X6900Y537137D01*
X3237D01*
X3230Y537130D01*
X1607D01*
X1600Y537137D01*
X976D01*
X476Y537637D01*
Y544137D01*
X576Y544237D01*
X9031D01*
X9776Y544982D01*
Y558062D01*
X9782D01*
Y560066D01*
X9776D01*
Y560800D01*
X9806Y560830D01*
Y562122D01*
X8980Y562948D01*
X9002Y562998D01*
Y565002D01*
X8926D01*
Y565932D01*
X8002Y566856D01*
G37*
G36*
G01X41076Y552767D02*
Y536367D01*
X39039Y534330D01*
X19376D01*
Y554330D01*
X39513D01*
X41076Y552767D01*
G37*
G36*
G01X40800Y572600D02*
X39200Y571000D01*
X20000D01*
X19600Y571400D01*
Y588000D01*
X20100Y588500D01*
X38900D01*
X40800Y586600D01*
Y572600D01*
G37*
G36*
G01X-3281Y595226D02*
X-3260Y595222D01*
G03X-3164Y595202I3260J15408D01*
G01X-3106Y595190D01*
X-2752Y594836D01*
X5472D01*
X6122Y594186D01*
Y591108D01*
X6432Y590798D01*
X8052D01*
X8280Y590570D01*
Y581537D01*
X476D01*
Y586800D01*
X339Y586937D01*
Y586983D01*
X-161Y587483D01*
X-4241D01*
X-7116Y590358D01*
Y593870D01*
X-5763Y595223D01*
X-5053D01*
X-5050Y595226D01*
X-3281D01*
G37*
G36*
G01X476Y545537D02*
Y550800D01*
X339Y550937D01*
Y550983D01*
X-161Y551483D01*
X-4061D01*
X-4615Y552037D01*
X-4624D01*
X-4894Y552306D01*
X-5562Y552974D01*
X-7538D01*
X-7900Y553337D01*
Y559500D01*
X-7063Y560337D01*
X8072D01*
X8278Y560130D01*
Y558062D01*
X8280D01*
Y545537D01*
X476D01*
G37*
G36*
G01X70658Y12441D02*
Y7097D01*
X71406Y6349D01*
Y5742D01*
X71400D01*
Y2738D01*
X71406D01*
Y2594D01*
X71757Y2243D01*
X72900D01*
Y2238D01*
X77638D01*
X78001Y1875D01*
Y-2841D01*
X77142Y-3700D01*
X67300D01*
X66000Y-2400D01*
Y1900D01*
X65315Y2585D01*
Y6999D01*
G03X65449Y7119I-975J1223D01*
G01X66334Y8003D01*
Y11341D01*
X65805Y11870D01*
Y11950D01*
X65000Y12755D01*
Y16119D01*
X65665Y16784D01*
Y18021D01*
X65000Y18686D01*
Y20000D01*
X65800Y20800D01*
X70316D01*
X70561Y20555D01*
Y12538D01*
X70658Y12441D01*
G37*
G36*
G01X73456Y3302D02*
X73404Y3354D01*
Y7022D01*
X73679Y7297D01*
Y15287D01*
X73577Y15389D01*
Y20549D01*
X72126Y22000D01*
X58402D01*
X58217Y22186D01*
X57815D01*
X57000Y23000D01*
Y81500D01*
X59000Y83500D01*
X81000D01*
X85078Y79422D01*
Y4186D01*
X84194Y3302D01*
X73456D01*
G37*
G36*
G01X100323Y-18923D02*
X98500Y-17100D01*
Y-13851D01*
G02X98944Y-13453I400J0D01*
G03X99362Y-10581I158J1443D01*
G02X99139Y-9917I71J393D01*
G03X98500Y-1125I-4456J4095D01*
G01Y8381D01*
G03Y17775I-3817J4697D01*
G01Y27281D01*
G03Y36675I-3817J4697D01*
G01Y46181D01*
G03Y55575I-3817J4697D01*
G01Y65081D01*
G03X98476Y74494I-3817J4697D01*
G01X97098Y75872D01*
X91904D01*
X90231Y77545D01*
Y78871D01*
X86400Y82702D01*
Y92348D01*
G02X86600Y92548I200J0D01*
G03X87207Y95319I0J1452D01*
G02X87091Y95965I167J363D01*
G01X93610Y102484D01*
X108384D01*
X109500Y103600D01*
Y104027D01*
X109515Y104064D01*
G03X109500Y105972I-2266J936D01*
G01Y107800D01*
X110400Y108700D01*
X114622D01*
Y108642D01*
X117626D01*
Y108700D01*
X119195D01*
X119600Y108295D01*
X119776D01*
X119821Y108269D01*
G03X121945Y109199I711J1266D01*
G01X121959Y109254D01*
X122100Y109395D01*
Y120000D01*
X122776Y120676D01*
X136024D01*
X136200Y120500D01*
Y109134D01*
X121420Y94354D01*
X115169D01*
X114142Y95381D01*
X108005D01*
X105617Y92993D01*
Y92872D01*
X105576Y92830D01*
Y90364D01*
G03X105614Y89927I2501J-3D01*
G01X105617Y89910D01*
Y89300D01*
X106160Y88757D01*
G03X106470Y88447I1917J1607D01*
G01X106530Y88387D01*
Y84079D01*
X106576Y84034D01*
Y83977D01*
X107323Y83229D01*
G03X107595Y83014I1061J1063D01*
G01X108309Y82300D01*
X117522D01*
Y78833D01*
G03X118120Y77120I2751J0D01*
G01Y57270D01*
X116910Y56060D01*
X116007D01*
G03X112561Y56621I-1925J-960D01*
G01X111999Y56060D01*
X108566D01*
X108517Y56189D01*
G03X103096Y55194I-2619J-995D01*
G01Y52750D01*
G03X104177Y50539I2802J0D01*
G01Y45953D01*
X104481Y45649D01*
X104463Y45546D01*
G03X107153Y44570I1429J-256D01*
G01X117522D01*
Y41033D01*
G03X117980Y39512I2751J-1D01*
G01Y19550D01*
X117400Y18970D01*
X116061D01*
G03X113299I-1381J-1650D01*
G01X108219D01*
G03X103198Y17260I-2219J-1710D01*
G01Y14828D01*
G03X104177Y12701I2802J1D01*
G01Y9220D01*
X104457Y8940D01*
X104447Y8846D01*
G03X106963Y7720I1445J-146D01*
G01X112689D01*
G02X112994Y7061I0J-400D01*
G03X113036Y5132I1106J-941D01*
G02X113014Y4566I-293J-272D01*
G03X115064Y4488I986J-1066D01*
G02X115086Y5054I293J272D01*
G03X115206Y7061I-986J1066D01*
G02X115511Y7720I305J259D01*
G01X117340D01*
X117522Y7538D01*
Y3233D01*
G03X117930Y1790I2751J-1D01*
G01Y-18510D01*
X117517Y-18923D01*
X100323D01*
G37*
G36*
G01X105120Y136800D02*
X103849Y138071D01*
Y143650D01*
G03Y147412I-3869J1881D01*
G01Y163739D01*
X105452Y165342D01*
X109991D01*
X110050Y165283D01*
X115164D01*
X115676Y165795D01*
X124225D01*
X127140Y162880D01*
Y140770D01*
X125400Y139030D01*
X117250D01*
X115020Y136800D01*
X105120D01*
G37*
G36*
G01X99500Y170900D02*
X96600Y173800D01*
Y189600D01*
X97000Y190000D01*
X105000D01*
X105750Y189250D01*
Y186450D01*
X105800Y186400D01*
Y173900D01*
X102800Y170900D01*
X99500D01*
G37*
G36*
G01X56002Y196500D02*
X55498Y197004D01*
Y199498D01*
X55502D01*
Y201502D01*
X55498D01*
Y202998D01*
X55502D01*
Y205002D01*
X55498D01*
Y206098D01*
X59010Y209610D01*
Y218688D01*
X59502Y219180D01*
X74396D01*
X75000Y218576D01*
Y209100D01*
X73200Y207300D01*
X61069D01*
X58900Y205131D01*
Y197400D01*
X58000Y196500D01*
X56002D01*
G37*
G36*
G01X84300Y208400D02*
X80200Y212500D01*
Y235800D01*
X80600Y236200D01*
X86500D01*
X87850Y237550D01*
X99950D01*
X102500Y235000D01*
Y228962D01*
G03Y226038I1510J-1462D01*
G01Y214600D01*
X96300Y208400D01*
X84300D01*
G37*
G36*
G01X114593Y200991D02*
Y194393D01*
X111400Y191200D01*
X96500D01*
X95800Y191900D01*
Y199881D01*
X93338Y202343D01*
Y206449D01*
X94164Y207275D01*
X108309D01*
X114593Y200991D01*
G37*
G36*
G01X98700Y242600D02*
X80400D01*
X79800Y243200D01*
Y258400D01*
X80100Y258700D01*
X85300D01*
X86650Y260050D01*
X98900D01*
X100000Y258950D01*
Y243900D01*
X98700Y242600D01*
G37*
G36*
G01X59788Y285788D02*
X59130Y285130D01*
X57811D01*
X56565Y283884D01*
Y283067D01*
X56569Y283063D01*
Y282569D01*
X55300Y281300D01*
X47517D01*
X46764Y282053D01*
Y285549D01*
X47668Y286453D01*
X49250D01*
X50211Y285492D01*
X55414D01*
X56633Y286711D01*
Y290233D01*
X59894Y293494D01*
X63429D01*
X63459Y293464D01*
Y293133D01*
X63290Y292964D01*
X61466D01*
X61052Y292550D01*
X60653D01*
Y292547D01*
X59788Y291682D01*
Y285788D01*
G37*
G36*
G01X57530Y294988D02*
X57705Y295163D01*
X63015D01*
X63485Y295633D01*
X64435D01*
X65021Y296219D01*
Y304339D01*
X65186Y304504D01*
X77481D01*
X78015Y303970D01*
Y292210D01*
X77378Y291573D01*
X65268D01*
X64960Y291881D01*
Y293958D01*
X64418Y294500D01*
X59400D01*
X55398Y290498D01*
Y288661D01*
X55239Y288502D01*
X47624D01*
X47000Y289126D01*
Y292500D01*
X48000Y293500D01*
X54500D01*
X55988Y294988D01*
X57530D01*
G37*
G36*
G01X77111Y395300D02*
X75910Y396502D01*
X73324D01*
X71322Y398503D01*
Y399578D01*
X71232Y399668D01*
Y411451D01*
X72759Y412978D01*
X84808D01*
X86376Y411410D01*
Y398188D01*
X85750Y397562D01*
X85688D01*
X83427Y395300D01*
X77111D01*
G37*
G36*
G01X69500Y357000D02*
Y371000D01*
X83500D01*
Y357000D01*
X69500D01*
G37*
G36*
G01X65927Y374100D02*
X62327Y377700D01*
X49600D01*
X48574Y378726D01*
Y381975D01*
X49599Y383000D01*
X52998D01*
Y382998D01*
X55002D01*
Y383000D01*
X56498D01*
Y382998D01*
X58502D01*
X58650Y382850D01*
Y382200D01*
X60003Y380847D01*
X63053D01*
X67100Y376800D01*
X68000D01*
X68200Y376600D01*
Y374500D01*
X67800Y374100D01*
X65927D01*
G37*
G36*
G01X69331Y374372D02*
X69250Y374453D01*
Y377036D01*
X68461Y377825D01*
X68075D01*
X63500Y382400D01*
Y384398D01*
X63502D01*
Y386402D01*
X63498D01*
X62400Y387500D01*
Y387798D01*
X62402D01*
Y389602D01*
X62398D01*
X61800Y390200D01*
X61000D01*
X60300Y390900D01*
Y391298D01*
X60302D01*
Y393168D01*
X60533Y393400D01*
X62600D01*
X62900Y393100D01*
Y391200D01*
X64500Y389600D01*
X65500D01*
X65600Y389500D01*
Y384400D01*
X69400Y380600D01*
X69407Y380529D01*
G03X69693Y379693I1893J181D01*
G01Y374451D01*
X69614Y374372D01*
X69331D01*
G37*
G36*
G01X111560Y401081D02*
X112493Y400148D01*
X112486Y400056D01*
G03X115509Y399205I1598J-119D01*
G01X123484D01*
X127702Y403423D01*
X129477D01*
X129610Y403290D01*
Y401696D01*
X129628D01*
Y398146D01*
X132404Y395370D01*
Y386070D01*
X124600D01*
Y389164D01*
X124766D01*
Y392566D01*
X120352D01*
X117829Y395090D01*
X110676D01*
G03X109172I-752J-1242D01*
G01X107976D01*
G03X106472I-752J-1242D01*
G01X103343D01*
G03X101569I-887J-1334D01*
G01X91630D01*
X91598Y395122D01*
X89085D01*
X87497Y396710D01*
Y432626D01*
X89519Y434648D01*
Y456751D01*
X92841Y460073D01*
X117326D01*
X120415Y456984D01*
Y427368D01*
X108900Y415853D01*
Y414790D01*
G03Y412914I1299J-938D01*
G01Y410000D01*
X106000Y407100D01*
Y407095D01*
X105954Y407049D01*
Y405591D01*
X106799Y404746D01*
X107147D01*
G03X107169Y404740I433J1543D01*
G01X107421Y404488D01*
Y402902D01*
X109242Y401081D01*
X111560D01*
G37*
G36*
G01X71457Y435957D02*
X76000Y440500D01*
X87079D01*
X88202Y439377D01*
Y434749D01*
X86287Y432834D01*
Y419700D01*
X74600D01*
X74461Y419561D01*
X72577D01*
X71457Y420681D01*
Y435957D01*
G37*
G36*
G01X72000Y494150D02*
X70400Y495750D01*
Y504900D01*
X71800Y506300D01*
X82400D01*
X85710Y502990D01*
Y496840D01*
X83020Y494150D01*
X72000D01*
G37*
G36*
G01X100531Y465247D02*
X100462Y465316D01*
X96890D01*
X95228Y466978D01*
Y478041D01*
X97109Y479922D01*
Y482391D01*
X95950Y483550D01*
X88314D01*
X86740Y485124D01*
Y500940D01*
X87900Y502100D01*
X143707D01*
X148722Y497085D01*
Y468491D01*
X145478Y465247D01*
X100531D01*
G37*
G36*
G01X91500Y505500D02*
X87550Y509450D01*
X65150D01*
X63400Y511200D01*
Y526800D01*
X64950Y528350D01*
X68510D01*
X69960Y526900D01*
X94600D01*
X94603Y526903D01*
X94686D01*
G03X94900Y539003I-4J6052D01*
G01Y545831D01*
G03Y557927I-217J6048D01*
G01Y564707D01*
G03Y576803I-217J6048D01*
G01Y583631D01*
G03Y595727I-217J6048D01*
G01Y602507D01*
G03X100662Y609493I-217J6048D01*
G02X101217Y609922I395J62D01*
G03X103208Y612572I681J1561D01*
G02X103239Y613117I307J256D01*
G03X103445Y613363I-1003J1050D01*
G02X104042Y613442I333J-222D01*
G03X103791Y615337I958J1091D01*
G02X103194Y615258I-333J222D01*
G03X101004Y613399I-958J-1091D01*
G02X100899Y612863I-339J-212D01*
G03X100321Y612128I999J-1380D01*
G02X99625Y612049I-370J152D01*
G03X94900Y614603I-4941J-3494D01*
G01Y617163D01*
G03X95176Y617646I-1100J949D01*
G01X95191Y617691D01*
X97500Y620000D01*
X104000D01*
X105679Y621679D01*
X117469D01*
X117892Y621256D01*
Y619086D01*
G03X117472Y617610I2381J-1475D01*
G01Y613994D01*
G03X117892Y610621I2420J-1411D01*
G01Y592483D01*
G02X117384Y592098I-400J0D01*
G03X116991Y589248I-392J-1398D01*
G02X117390Y588848I-1J-400D01*
G01Y586961D01*
G03X117892Y583738I2502J-1261D01*
G01Y581286D01*
G03X117472Y579810I2381J-1475D01*
G01Y576111D01*
G03X117892Y572738I2420J-1411D01*
G01Y553254D01*
G03X117190Y551400I2100J-1855D01*
G01Y548642D01*
X117184Y548617D01*
G03X117892Y545938I2708J-717D01*
G01Y543486D01*
G03X117472Y542010I2381J-1475D01*
G01Y538394D01*
G03X117892Y535021I2420J-1411D01*
G01Y512068D01*
X116734Y510910D01*
Y508234D01*
X114000Y505500D01*
X91500D01*
G37*
G36*
G01X83810Y617056D02*
Y537810D01*
X80500Y534500D01*
X55560D01*
X53370Y536690D01*
Y558630D01*
X52620Y559380D01*
Y596430D01*
X52180Y596870D01*
Y602670D01*
X50850Y604000D01*
Y616798D01*
X53861Y619809D01*
X80410D01*
G02X80800Y619318I0J-400D01*
G03X83229Y617413I1659J-386D01*
G02X83810Y617056I181J-357D01*
G37*
G36*
G01X102600Y611483D02*
G03I-702J0D01*
G37*
G36*
G01X83161Y618932D02*
G03I-702J0D01*
G37*
G36*
G01X125711Y89242D02*
X125253Y89700D01*
Y95901D01*
X142538Y113186D01*
X157486D01*
X158160Y112512D01*
Y89825D01*
X157577Y89242D01*
X143722D01*
G02X143335Y89741I0J400D01*
G03X140425I-1455J373D01*
G02X140038Y89242I-387J-99D01*
G01X138664D01*
G02X138268Y89696I0J400D01*
G03X135292I-1488J204D01*
G02X134896Y89242I-396J-54D01*
G01X125711D01*
G37*
G36*
G01X175280Y137475D02*
X165447Y127642D01*
X125336D01*
X123544Y129434D01*
X116988D01*
X115978Y130444D01*
Y135628D01*
X118241Y137891D01*
X127600D01*
X148782Y159073D01*
X174317D01*
X175280Y158110D01*
Y137475D01*
G37*
G36*
G01X116130Y167300D02*
X115126Y168304D01*
X110159D01*
X110090Y168373D01*
Y183490D01*
X111200Y184600D01*
X118900D01*
X120295Y183205D01*
Y168600D01*
X120300D01*
Y167800D01*
X119800Y167300D01*
X118476D01*
Y167302D01*
X116474D01*
Y167300D01*
X116130D01*
G37*
G36*
G01X148765Y169100D02*
X146900Y170965D01*
Y190808D01*
X147781Y191689D01*
X147797D01*
X149302Y193194D01*
X150418D01*
X150425Y193187D01*
X150872D01*
X151509Y193824D01*
X173843D01*
X175240Y192427D01*
Y170736D01*
X173604Y169100D01*
X148765D01*
G37*
G36*
G01X132125Y308212D02*
Y308355D01*
X131386Y309095D01*
G03X131234Y309227I-1058J-1065D01*
G01Y313422D01*
X131223Y313433D01*
Y313727D01*
X131050Y313900D01*
X124942D01*
X124742Y314100D01*
Y319700D01*
X125542Y320500D01*
X132442D01*
X132802Y320860D01*
X133662D01*
Y321720D01*
X134042Y322100D01*
Y332582D01*
X133252Y333373D01*
Y335002D01*
X133144D01*
Y335118D01*
X133114D01*
X132422Y335810D01*
X132520Y336048D01*
Y336548D01*
X133520D01*
Y338552D01*
X132520D01*
Y339052D01*
X131641D01*
X131202Y339491D01*
Y339494D01*
X131391Y339684D01*
Y341018D01*
X131388Y341021D01*
X131386Y341023D01*
G03X131247Y341154I-1063J-989D01*
G01Y345333D01*
X131230Y345350D01*
Y345860D01*
X131080Y346010D01*
X125132D01*
X125042Y346100D01*
Y352000D01*
X125542Y352500D01*
X131942D01*
X132302Y352860D01*
X133662D01*
Y354220D01*
X134042Y354600D01*
Y364005D01*
X133662Y364385D01*
Y364464D01*
X133584D01*
X133221Y364826D01*
X133252Y364898D01*
Y366874D01*
X133281Y366904D01*
X135481D01*
X136237Y366148D01*
X169500D01*
X170342Y365306D01*
Y210642D01*
X169948Y210248D01*
Y206300D01*
X164942D01*
X164842Y206400D01*
X157242D01*
X154944Y204102D01*
X154941D01*
Y204099D01*
X154442Y203600D01*
X140000D01*
X139942Y203658D01*
X136071D01*
X133096Y206633D01*
Y208532D01*
X133126D01*
Y210534D01*
X133096D01*
Y211509D01*
X131246Y213359D01*
Y217445D01*
X131079Y217612D01*
X124948D01*
X124760Y217800D01*
X124742D01*
X124542Y218000D01*
Y224000D01*
X125142Y224600D01*
X132742D01*
X133002Y224860D01*
X133662D01*
Y225520D01*
X133942Y225800D01*
Y236190D01*
X133380Y236752D01*
Y238704D01*
X133333D01*
Y242648D01*
X133324Y242657D01*
Y243153D01*
X132326Y244154D01*
Y244155D01*
X131657Y244824D01*
X131386Y245095D01*
G03X131271Y245198I-1058J-1066D01*
G01Y249509D01*
X131120Y249660D01*
X124835D01*
X124730Y249765D01*
Y256299D01*
X125014Y256583D01*
X132425D01*
X132702Y256860D01*
X133662D01*
Y257820D01*
X133942Y258100D01*
Y267862D01*
X133662Y268142D01*
Y268464D01*
X133340D01*
X132803Y269001D01*
Y272298D01*
X132926D01*
Y274302D01*
X132803D01*
Y275583D01*
X134446Y277226D01*
Y277434D01*
Y281026D01*
X135740D01*
Y284028D01*
X133338D01*
Y281038D01*
X132444D01*
Y277954D01*
X132210Y277720D01*
X131190D01*
X131170Y277740D01*
Y281360D01*
X131165Y281365D01*
Y281535D01*
X131030Y281670D01*
X124831D01*
X124648Y281853D01*
Y288446D01*
X124820Y288618D01*
X133418D01*
X133660Y288860D01*
X133700D01*
Y300558D01*
X133252Y301007D01*
Y303002D01*
X133168D01*
Y307169D01*
X132125Y308212D01*
G37*
G36*
G01X124600Y226070D02*
Y229164D01*
X124766D01*
Y232566D01*
X119504D01*
X119108Y232962D01*
X116208D01*
X115700Y233470D01*
Y238185D01*
X116702Y239187D01*
X121805D01*
X121973Y239019D01*
X123729D01*
X124005Y238743D01*
Y237135D01*
X124890Y236250D01*
X126214D01*
X127492Y237528D01*
X128563D01*
X130222Y239187D01*
X131458D01*
X131875Y238769D01*
Y236596D01*
X131929Y236542D01*
Y235845D01*
X132404Y235370D01*
Y226070D01*
X124600D01*
G37*
G36*
G01Y258070D02*
Y261164D01*
X124766D01*
Y264566D01*
X119504D01*
X119200Y264870D01*
X118502D01*
Y265002D01*
X116168D01*
X115700Y265470D01*
Y268380D01*
X116644Y269324D01*
X121057D01*
X122764Y271032D01*
X125626D01*
Y271035D01*
X126122D01*
Y271032D01*
X129126D01*
Y271035D01*
X131127D01*
X131312Y270850D01*
X131286Y270788D01*
Y268784D01*
X131419D01*
Y267937D01*
X132404Y266952D01*
Y258070D01*
X124600D01*
G37*
G36*
G01X118800Y298700D02*
G02X119100Y298400I0J-300D01*
G02X118800Y298100I-300J0D01*
G02X118500Y298400I0J300D01*
G02X118800Y298700I300J0D01*
G37*
G36*
G01X116605Y335190D02*
X118139D01*
X118285Y335044D01*
X122064D01*
X123565Y333543D01*
X126360D01*
X126448Y333558D01*
X128080Y335190D01*
X131550D01*
X131680Y335061D01*
Y332094D01*
X132404Y331370D01*
Y322070D01*
X124600D01*
Y327333D01*
X124463Y327470D01*
Y327516D01*
X123963Y328016D01*
X120063D01*
X119509Y328570D01*
X119500D01*
X119200Y328870D01*
X116300D01*
X115700Y329470D01*
Y334285D01*
X116605Y335190D01*
G37*
G36*
G01X124600Y290070D02*
Y295333D01*
X124463Y295470D01*
Y295516D01*
X123963Y296016D01*
X120551D01*
X120269Y296298D01*
Y299015D01*
X119426Y299858D01*
X113669D01*
X113502Y300026D01*
Y302001D01*
X113875Y302375D01*
X121684D01*
X122340Y303032D01*
X125126D01*
Y303073D01*
X125622D01*
Y303032D01*
X128626D01*
Y303073D01*
X131609D01*
X131727Y302955D01*
Y300047D01*
X132404Y299370D01*
Y290070D01*
X124600D01*
G37*
G36*
G01X160790Y373662D02*
X163661D01*
X166402Y376402D01*
Y393798D01*
X164135Y396064D01*
X142298D01*
Y373980D01*
X141400Y373082D01*
Y368980D01*
X140140Y367720D01*
X136213D01*
X135957Y367976D01*
X133370D01*
Y370242D01*
X132370D01*
Y371043D01*
X132086Y371327D01*
Y372085D01*
G03X131199Y373455I-1502J0D01*
G01Y377343D01*
X130642Y377900D01*
X127180D01*
X127145Y377865D01*
X125177D01*
X124742Y378300D01*
Y383600D01*
X125542Y384400D01*
X132142D01*
X132602Y384860D01*
X133662D01*
Y385920D01*
X133942Y386200D01*
Y395393D01*
X133927D01*
Y395605D01*
X131140Y398392D01*
Y403682D01*
X131105Y403717D01*
Y404112D01*
X131381Y404388D01*
X139130D01*
X139142Y404400D01*
X149929D01*
X152709Y401620D01*
X162122D01*
X168976Y394766D01*
Y369466D01*
X167883Y368373D01*
X160427D01*
X159990Y368810D01*
Y372862D01*
X160790Y373662D01*
G37*
G36*
G01X124600Y354070D02*
Y359333D01*
X124463Y359470D01*
Y359516D01*
X123963Y360016D01*
X121000D01*
X118856Y362160D01*
X113700D01*
X113500Y362360D01*
Y362698D01*
X113502D01*
Y364501D01*
X115954Y366954D01*
X124554D01*
X125937Y365571D01*
X128780D01*
X130422Y367213D01*
X131305D01*
X131633Y366885D01*
Y364141D01*
X132404Y363370D01*
Y354070D01*
X124600D01*
G37*
G36*
G01X165200Y393300D02*
Y376900D01*
X163163Y374863D01*
X143500D01*
Y394863D01*
X163637D01*
X165200Y393300D01*
G37*
G36*
G01X123365Y423871D02*
X122496Y424740D01*
Y456223D01*
X124949Y458676D01*
X143825D01*
X146543Y455958D01*
Y432705D01*
X140427Y426589D01*
X136970D01*
X136928Y426609D01*
G03X127077Y423871I-3365J-6983D01*
G01X123365D01*
G37*
G36*
G01X324196Y309007D02*
G03X325697Y310548I0J1502D01*
G02X326097Y310959I400J11D01*
G01X326805D01*
G02X327205Y310548I0J-400D01*
G03X328706Y309007I1501J-39D01*
G01X330956D01*
G03X332457Y310548I0J1502D01*
G02X332857Y310959I400J11D01*
G01X333565D01*
G02X333965Y310548I0J-400D01*
G03X335466Y309007I1501J-39D01*
G01X337716D01*
G03X339217Y310548I0J1502D01*
G02X339617Y310959I400J11D01*
G01X340325D01*
G02X340725Y310548I0J-400D01*
G03X342226Y309007I1501J-39D01*
G01X344476D01*
G03Y312011I0J1502D01*
G01X342996D01*
G02X342597Y312421I1J400D01*
G03Y312498I-1501J38D01*
G02X342997Y312908I400J10D01*
G01X344476Y312907D01*
G03Y315911I0J1502D01*
G01X344310D01*
G02X344027Y316593I0J400D01*
G01X344242Y316807D01*
X344476D01*
G03X345807Y317614I0J1501D01*
G01X346838D01*
X347386Y318162D01*
Y318759D01*
X347856D01*
G03Y321761I0J1501D01*
G01X347386D01*
Y322659D01*
X347856D01*
G03Y325661I0J1501D01*
G01X347386D01*
Y326559D01*
X347856D01*
G03Y329561I0J1501D01*
G01X347386D01*
Y330459D01*
X347856D01*
G03X349357Y331998I0J1501D01*
G02X349757Y332408I400J10D01*
G01X351236Y332407D01*
G03X352737Y333948I0J1502D01*
G02X353137Y334359I400J11D01*
G01X354615D01*
G03X356116Y335898I0J1501D01*
G02X356516Y336308I400J10D01*
G01X357995Y336307D01*
G03X359496Y337848I0J1502D01*
G02X359896Y338259I400J11D01*
G01X361375D01*
G03X362876Y339798I0J1501D01*
G02X363276Y340208I400J10D01*
G01X364755Y340207D01*
G03X366256Y341748I0J1502D01*
G02X366656Y342159I400J11D01*
G01X368135D01*
G03X369636Y343698I0J1501D01*
G02X370036Y344108I400J10D01*
G01X371515Y344107D01*
G03X373016Y345648I0J1502D01*
G02X373416Y346059I400J11D01*
G01X374124D01*
G02X374524Y345648I0J-400D01*
G03X376025Y344107I1501J-39D01*
G01X378275D01*
G03X379776Y345648I0J1502D01*
G02X380176Y346059I400J11D01*
G01X381655D01*
G03X383156Y347598I0J1501D01*
G02X383556Y348008I400J10D01*
G01X385035Y348007D01*
G03X386523Y349308I0J1501D01*
G01X386532Y349375D01*
X386728Y349572D01*
X386928Y349772D01*
X387116Y349959D01*
X388415D01*
G03X389895Y351209I0J1501D01*
G01X389923Y351375D01*
X391416D01*
X391444Y351208D01*
G03X391472Y351076I1481J245D01*
G02X391343Y350836I-193J-51D01*
G03X393194Y349548I451J-1325D01*
G02X393593Y349959I400J11D01*
G01X395174D01*
G03X396654Y351209I0J1501D01*
G01X396682Y351375D01*
X398176D01*
X398204Y351208D01*
G03X398232Y351076I1481J245D01*
G02X398103Y350836I-193J-51D01*
G03X399954Y349548I451J-1325D01*
G02X400353Y349959I400J11D01*
G01X401934D01*
G03X403414Y351209I0J1501D01*
G01X403442Y351375D01*
X404103D01*
G02X404399Y350706I0J-400D01*
G03X403811Y349364I907J-1197D01*
G01X403812Y349354D01*
Y347109D01*
G03X406816I1502J0D01*
G01Y349509D01*
G03X406270Y350667I-1501J0D01*
G02X406525Y351375I255J308D01*
G01X407185D01*
X407187Y351363D01*
G03X408737Y349959I1499J97D01*
G01X411094D01*
G03X412187Y350431I0J1502D01*
G01X412713D01*
X414624Y352341D01*
X420117D01*
G02X420416Y351676I-1J-400D01*
G03X422512I1048J-929D01*
G02X422811Y352341I299J265D01*
G01X423532D01*
X423581Y352213D01*
G03X425700Y351649I1263J483D01*
G01X425755Y351694D01*
X426040D01*
X426097Y351640D01*
G03X428462Y352208I997J1056D01*
G01X428509Y352341D01*
X430292D01*
X430341Y352213D01*
G03X432460Y351649I1263J483D01*
G01X432515Y351694D01*
X432800D01*
X432857Y351640D01*
G03X435222Y352208I997J1056D01*
G01X435269Y352341D01*
X437051D01*
X437100Y352213D01*
G03X439219Y351649I1263J483D01*
G01X439274Y351694D01*
X439559D01*
X439616Y351640D01*
G03X440276Y351284I996J1057D01*
G02X440424Y351045I-47J-194D01*
G03X440479Y350268I1319J-297D01*
G01X440492Y350234D01*
Y349233D01*
G03X442994I1251J-736D01*
G01Y350234D01*
X443007Y350268D01*
G03X442732Y351668I-1264J479D01*
G02X443024Y352341I293J273D01*
G01X443811D01*
X443860Y352213D01*
G03X446041Y351703I1263J483D01*
G02X446322Y351695I136J-146D01*
G03X447036Y351284I1051J1001D01*
G02X447184Y351045I-47J-194D01*
G03X449359Y349700I1319J-298D01*
G01X449414Y349746D01*
X449699D01*
X449756Y349691D01*
G03X450416Y349335I996J1057D01*
G02X450565Y349096I-46J-195D01*
G03X452791Y347794I1318J-300D01*
G01X452806D01*
X453758Y346842D01*
Y339742D01*
X453008Y338992D01*
X446400D01*
X444488Y337080D01*
X436270D01*
X431710Y332520D01*
X425120D01*
X425000Y332641D01*
Y337252D01*
X421852Y340400D01*
X387215D01*
X381906Y335091D01*
X378391D01*
X372641Y329341D01*
X366441D01*
X363656Y326556D01*
Y313257D01*
X363654Y313256D01*
Y310926D01*
X363656Y310925D01*
Y310841D01*
X364156Y310341D01*
X364240D01*
X364741Y309839D01*
X366571D01*
X367065Y310333D01*
X379658D01*
Y310843D01*
X380538Y311723D01*
Y314408D01*
X381230Y315100D01*
X408569D01*
X409190Y314478D01*
Y311148D01*
X409193D01*
Y309353D01*
X407900Y308060D01*
Y303942D01*
X387360D01*
Y303906D01*
X385058D01*
Y303847D01*
X383170D01*
Y303905D01*
X383162D01*
Y303906D01*
X380158D01*
Y303847D01*
X378270D01*
Y303905D01*
X378262D01*
Y303906D01*
X375258D01*
Y303847D01*
X373370D01*
Y303905D01*
X373362D01*
Y303906D01*
X370358D01*
Y303847D01*
X368470D01*
Y303905D01*
X368462D01*
Y303906D01*
X365458D01*
Y302943D01*
X364154D01*
Y301719D01*
X364146Y301712D01*
Y295185D01*
X364154Y295178D01*
Y293845D01*
X365487D01*
Y293844D01*
X387950D01*
X387964Y293857D01*
X407900D01*
Y287235D01*
X407600Y286935D01*
X387392D01*
X387345Y286982D01*
X366432D01*
X366356Y286906D01*
X365458D01*
Y286117D01*
X364154D01*
Y284878D01*
X364146Y284871D01*
Y279042D01*
X366611Y276578D01*
X366618D01*
X366619Y276577D01*
X378278D01*
X378370Y276485D01*
Y266447D01*
X388476D01*
Y262635D01*
X418435D01*
X418456Y262656D01*
X427144D01*
X428000Y261800D01*
X432400D01*
X433400Y262800D01*
Y263096D01*
G03X433748Y265668I-757J1412D01*
G02X433741Y266241I276J290D01*
G01X434000Y266500D01*
X435600D01*
X436800Y265300D01*
X437000D01*
X437100Y265200D01*
Y264300D01*
X438900Y262500D01*
X438943D01*
X438992Y262469D01*
G03X440583Y262500I772J1230D01*
G01X443800D01*
X444157Y262857D01*
X444276Y262816D01*
G03X446182Y263935I476J1372D01*
G01X446211Y264100D01*
X447800D01*
X448772Y265072D01*
X448886Y265040D01*
G03X450617Y267020I402J1395D01*
G01X450600Y267058D01*
Y268835D01*
X452119D01*
G03X453611I746J1246D01*
G01X456471D01*
X457105Y268201D01*
Y264367D01*
X456873D01*
X456843Y264376D01*
G03X456772Y264398I-465J-1375D01*
G02X456629Y264635I52J193D01*
G03X454853Y263606I-1366J311D01*
G02X454988Y263364I-58J-191D01*
G03X454969Y262713I1405J-367D01*
G02X454831Y262483I-196J-39D01*
G03X454242Y262141I440J-1436D01*
G02X453973Y262137I-137J146D01*
G03X453392Y262449I-960J-1090D01*
G02X453250Y262686I53J193D01*
G03X451473Y261656I-1367J310D01*
G02X451608Y261414I-58J-191D01*
G03X451589Y260762I1405J-367D01*
G02X451452Y260531I-196J-40D01*
G03X450863Y260189I440J-1435D01*
G02X450593Y260185I-137J146D01*
G03X450012Y260498I-961J-1088D01*
G02X449869Y260735I52J193D01*
G03X448094Y259706I-1366J311D01*
G02X448228Y259464I-59J-191D01*
G03X448209Y258813I1405J-367D01*
G02X448071Y258582I-196J-40D01*
G03X447482Y258240I440J-1435D01*
G02X447213Y258236I-137J146D01*
G03X446632Y258549I-961J-1088D01*
G02X446490Y258786I53J193D01*
G03X444713Y257756I-1367J310D01*
G02X444848Y257514I-58J-191D01*
G03X444802Y257108I1405J-365D01*
G02X444402Y256697I-400J-11D01*
G01X443553D01*
G02X443153Y257108I0J400D01*
G03X442913Y257932I-1402J39D01*
G03X441658Y258546I-1161J-783D01*
G03X441247Y255835I85J-1400D01*
G01X441304Y255813D01*
X441439Y255625D01*
X441419Y255537D01*
G03X441380Y255158I1462J-342D01*
G02X440981Y254749I-400J-9D01*
G01X440172D01*
G02X439772Y255159I0J400D01*
G03X439686Y255681I-1401J37D01*
G03X438257Y256594I-1314J-482D01*
G03X437868Y253885I107J-1398D01*
G01X437924Y253863D01*
X438059Y253675D01*
X438039Y253587D01*
G03X438000Y253208I1462J-342D01*
G02X437600Y252797I-400J-11D01*
G01X436791D01*
G02X436391Y253209I0J400D01*
G03X433834Y252463I-1399J40D01*
G02X433503Y251838I-331J-225D01*
G01X433018D01*
X432963Y251951D01*
G03X431612Y252797I-1351J-656D01*
G01X430031D01*
G02X429631Y253209I0J400D01*
G03X427074Y252463I-1399J40D01*
G02X426743Y251838I-331J-225D01*
G01X426273D01*
X426151Y252049D01*
G03X423823Y252390I-1299J-753D01*
G02X423554Y252385I-137J145D01*
G03X422972Y252698I-961J-1089D01*
G02X422830Y252935I53J193D01*
G03X421055Y251907I-1366J312D01*
G02X421190Y251665I-59J-191D01*
G03X421142Y251259I1404J-372D01*
G02X420743Y250849I-400J-10D01*
G01X419892D01*
G02X419493Y251258I1J400D01*
G03X419459Y251603I-1401J36D01*
G03X417290Y252447I-1367J-304D01*
G03X416984Y250423I794J-1155D01*
G02X416629Y249841I-356J-182D01*
G01X403278D01*
Y250043D01*
G03X401070Y251107I-1352J17D01*
G01X401015Y251062D01*
X400730D01*
X400673Y251116D01*
G03X398224Y250043I-997J-1056D01*
G01Y249841D01*
X396518D01*
Y250043D01*
G03X394310Y251107I-1352J17D01*
G01X394255Y251062D01*
X393970D01*
X393913Y251116D01*
G03X391464Y250043I-997J-1056D01*
G01Y249841D01*
X389759D01*
Y250043D01*
G03X387551Y251107I-1352J17D01*
G01X387496Y251062D01*
X387211D01*
X387154Y251116D01*
G03X384705Y250043I-997J-1056D01*
G01Y249841D01*
X383353D01*
G02X383156Y250043I3J200D01*
G03X381655Y251561I-1501J17D01*
G01X379405D01*
G03X377904Y250043I0J-1501D01*
G02X377704Y249841I-200J-2D01*
G01X376596D01*
G02X376396Y250043I0J200D01*
G03X374895Y251561I-1501J17D01*
G01X373416D01*
G02X373016Y251971I0J400D01*
G03X371515Y253511I-1501J39D01*
G01X370035D01*
G02X369636Y253921I1J400D01*
G03X368135Y255461I-1501J39D01*
G01X366656D01*
G02X366256Y255871I0J400D01*
G03X364755Y257411I-1501J39D01*
G01X363275D01*
G02X362876Y257821I1J400D01*
G03X361375Y259361I-1501J39D01*
G01X359896D01*
G02X359496Y259771I0J400D01*
G03X357995Y261311I-1501J39D01*
G01X357300D01*
X353678Y264933D01*
X353733Y265058D01*
G03X351755Y267036I-1376J602D01*
G01X351630Y266981D01*
X350313Y268298D01*
X350299Y268324D01*
G03X349668Y268943I-1321J-715D01*
G01X349195Y269416D01*
X349199Y269504D01*
G03X347792Y270911I-1351J56D01*
G01X347704Y270907D01*
X346398Y272213D01*
X346545Y272359D01*
X346550Y272364D01*
G03X346595Y272404I-942J1105D01*
G01X346652Y272458D01*
X346937D01*
X346992Y272413D01*
G03Y274507I856J1047D01*
G01X346937Y274462D01*
X346652D01*
X346595Y274516D01*
G03X345951Y274868I-996J-1057D01*
G01X345800Y274906D01*
Y275177D01*
X345803Y275193D01*
G03Y275625I-1335J216D01*
G01X345800Y275641D01*
Y275863D01*
X345953Y275900D01*
G03Y278820I-355J1460D01*
G01X345800Y278857D01*
Y279078D01*
X345803Y279094D01*
G03Y279526I-1335J216D01*
G01X345800Y279542D01*
Y279763D01*
X345953Y279800D01*
G03Y282720I-355J1460D01*
G01X345800Y282757D01*
Y282977D01*
X345803Y282993D01*
G03Y283425I-1335J216D01*
G01X345800Y283441D01*
Y283917D01*
G03X344476Y284711I-1325J-708D01*
G01X342226D01*
G03X340775Y283596I0J-1502D01*
G01X340736Y283447D01*
X339206D01*
X339167Y283596D01*
G03X337716Y284711I-1451J-387D01*
G01X335466D01*
G03X334015Y283596I0J-1502D01*
G01X333976Y283447D01*
X332446D01*
X332407Y283596D01*
G03X330956Y284711I-1451J-387D01*
G01X328706D01*
G03X327255Y283596I0J-1502D01*
G01X327216Y283447D01*
X325686D01*
X325647Y283596D01*
G03X324196Y284711I-1451J-387D01*
G01X321946D01*
G03X320495Y283596I0J-1502D01*
G01X320456Y283447D01*
X318926D01*
X318887Y283596D01*
G03X317436Y284711I-1451J-387D01*
G01X315956D01*
G02X315557Y285121I1J400D01*
G03X314056Y286661I-1501J39D01*
G01X311806D01*
G03Y283659I0J-1501D01*
G01X313285D01*
G02X313685Y283248I0J-400D01*
G03X315186Y281707I1501J-39D01*
G01X315451D01*
G02X315734Y281025I0J-400D01*
G01X315520Y280811D01*
X315186D01*
G03X313699Y279102I0J-1501D01*
G01X313713Y279004D01*
X313570Y278861D01*
X311804D01*
G03X310669Y278341I1J-1501D01*
G01X308434D01*
G03X307299Y278861I-1136J-981D01*
G01X305045D01*
G03X303910Y278341I1J-1501D01*
G01X301674D01*
G03X300539Y278861I-1136J-981D01*
G01X298285D01*
G03X297150Y278341I1J-1501D01*
G01X294914D01*
G03X293779Y278861I-1136J-981D01*
G01X291525D01*
G03X290390Y278341I1J-1501D01*
G01X288154D01*
G03X287019Y278861I-1136J-981D01*
G01X284765D01*
G03X283630Y278341I1J-1501D01*
G01X283133D01*
X282373Y277581D01*
G02X281705Y277758I-282J283D01*
G03X280257Y278861I-1448J-399D01*
G01X278007D01*
G03X276506Y277321I0J-1501D01*
G02X276107Y276911I-400J-10D01*
G01X274627D01*
G03X273126Y275371I0J-1501D01*
G02X272726Y274962I-400J-9D01*
G01X271763Y274961D01*
G02X271363Y275372I0J400D01*
G03X270319Y276638I-1249J34D01*
G03X270207Y276610I-13J-186D01*
G03X270181Y276592I155J-251D01*
G03X270115Y276487I125J-152D01*
G03X270108Y276423I257J-60D01*
G01Y276284D01*
G03Y276254I179J-15D01*
G01X270156D01*
X270196Y276253D01*
X270226Y276247D01*
X270228Y276246D01*
G03X270243Y276245I12J71D01*
G02X270394Y276205I-153J-883D01*
G02X270582Y276112I-323J-889D01*
G02X270760Y275953I-591J-840D01*
G02X270872Y275778I-654J-542D01*
G02X270949Y275533I-958J-436D01*
G02X270959Y275401I-1651J-191D01*
G02X270938Y275219I-632J-19D01*
G02X270846Y274985I-944J236D01*
G03X270777Y274886I709J-568D01*
G03X270233Y274567I470J-1426D01*
G02X270107Y274557I-133J875D01*
G02X269752Y274341I-355J184D01*
G01X267953D01*
G03X266738Y274961I-1215J-881D01*
G01X264185D01*
G03X263632Y274855I1J-1501D01*
G01X263596Y274841D01*
X262356D01*
X192107Y204592D01*
X173908D01*
X171952Y206548D01*
Y209372D01*
X171800D01*
Y363512D01*
X172802Y364514D01*
X189503D01*
X189910Y364106D01*
Y358236D01*
X190698Y357448D01*
X198785D01*
X199938Y358601D01*
Y363047D01*
X200789Y363898D01*
X237978D01*
X263953Y337923D01*
G02X263780Y337256I-283J-282D01*
G03X265231Y334859I399J-1396D01*
G02X265511Y334868I145J-138D01*
G03X266116Y334545I918J992D01*
G02X266420Y334103I-92J-389D01*
G03Y333717I1439J-193D01*
G02X266116Y333275I-396J-53D01*
G03X265511Y332952I313J-1315D01*
G02X265231Y332961I-135J147D01*
G03Y330959I-1052J-1001D01*
G02X265511Y330968I145J-138D01*
G03X266116Y330645I918J992D01*
G02X266420Y330203I-92J-389D01*
G03Y329817I1439J-193D01*
G02X266116Y329375I-396J-53D01*
G03X265574Y329107I313J-1315D01*
G01X265519Y329062D01*
X265233D01*
X265176Y329116D01*
G03Y327004I-997J-1056D01*
G01X265233Y327058D01*
X265519D01*
X265574Y327013D01*
G03X266429Y326708I855J1046D01*
G01X266729D01*
G03X268047Y328358I0J1351D01*
G02X268196Y328597I195J44D01*
G03X268856Y328953I-336J1413D01*
G01X268913Y329008D01*
X269198D01*
X269253Y328962D01*
G03X269713Y328716I856J1047D01*
G02X269846Y328469I-59J-191D01*
G03X270074Y327193I1393J-409D01*
G01X270114Y327140D01*
Y326994D01*
X270113Y326988D01*
G03X270114Y326957I179J-10D01*
G01X270162Y326956D01*
X270202Y326954D01*
X270229Y326949D01*
X270236Y326947D01*
G03X270248Y326946I12J71D01*
G02X270331Y326927I-158J-882D01*
G03X270718Y326705I907J1133D01*
G02X270766Y326654I-724J-729D01*
G02X270878Y326479I-654J-542D01*
G02X270955Y326234I-959J-436D01*
G02X270964Y326102I-1653J-179D01*
G02X270944Y325920I-632J-23D01*
G02X270852Y325686I-945J236D01*
G03X270783Y325586I711J-564D01*
G02X270684Y325480I-2368J2112D01*
G02X270622Y325428I-669J735D01*
G02X270452Y325328I-445J562D01*
G01X270395Y325307D01*
G02X270218Y325265I-250J660D01*
G02X270113Y325258I-111J879D01*
G02X270114Y325200I-438J-37D01*
G03X270113Y325109I1067J-57D01*
G01X270114Y325105D01*
Y325091D01*
X270115Y325071D01*
X270113Y325061D01*
X270116Y325048D01*
G03X270122Y325022I178J27D01*
G01X270128Y325003D01*
X270131Y324995D01*
X270144Y324969D01*
X270149Y324963D01*
X270156Y324953D01*
G03X270159Y324949I15J8D01*
G03X270180Y324928I134J113D01*
G03X270192Y324918I64J65D01*
G03X270222Y324897I83J86D01*
G01X270246Y324887D01*
G03X270262Y324883I52J172D01*
G03X270280Y324877I63J158D01*
G01X270317Y324874D01*
G03X271361Y326240I-198J1233D01*
G02X271646Y326666I398J42D01*
G03X272236Y327004I-407J1394D01*
G01X272293Y327058D01*
X272578D01*
X272633Y327013D01*
G03X273093Y326767I856J1047D01*
G02X273226Y326520I-59J-191D01*
G03X275616Y325054I1393J-410D01*
G01X275673Y325108D01*
X275958D01*
X276013Y325063D01*
G03X276473Y324817I856J1047D01*
G02X276606Y324570I-59J-191D01*
G03Y323749I1393J-411D01*
G02X276473Y323502I-192J-56D01*
G03X276013Y323256I396J-1293D01*
G01X275958Y323210D01*
X275673D01*
X275616Y323265D01*
G03Y321153I-997J-1056D01*
G01X275673Y321208D01*
X275958D01*
X276013Y321162D01*
G03X276473Y320916I856J1047D01*
G02X276606Y320669I-59J-191D01*
G03X278996Y319204I1393J-409D01*
G01X279053Y319258D01*
X279338D01*
X279393Y319213D01*
G03X279853Y318967I856J1047D01*
G02X279986Y318720I-59J-191D01*
G03Y317900I1393J-410D01*
G02X279853Y317653I-192J-56D01*
G03X279393Y317407I396J-1293D01*
G01X279338Y317362D01*
X279053D01*
X278996Y317416D01*
G03Y315304I-997J-1056D01*
G01X279053Y315358D01*
X279338D01*
X279393Y315313D01*
G03X281568Y316658I856J1047D01*
G02X281716Y316897I195J45D01*
G03X282376Y317253I-336J1413D01*
G01X282433Y317308D01*
X282718D01*
X282773Y317262D01*
G03X283233Y317016I856J1047D01*
G02X283366Y316769I-59J-191D01*
G03X285756Y315304I1393J-409D01*
G01X285813Y315358D01*
X286098D01*
X286153Y315313D01*
G03X286797Y315025I855J1047D01*
G01X286861Y315015D01*
X287017Y314859D01*
G03X288378Y315726I0J1502D01*
G01X288432Y315841D01*
X290112D01*
X290166Y315726D01*
G03X291527Y314859I1361J635D01*
G01X293777D01*
G03X295138Y315726I0J1502D01*
G01X295192Y315841D01*
X296872D01*
X296926Y315726D01*
G03X298287Y314859I1361J635D01*
G01X300537D01*
G03X301898Y315726I0J1502D01*
G01X301952Y315841D01*
X303632D01*
X303686Y315726D01*
G03X305047Y314859I1361J635D01*
G01X307297D01*
G03X308658Y315726I0J1502D01*
G01X308712Y315841D01*
X310391D01*
X310445Y315726D01*
G03X311806Y314859I1361J635D01*
G01X313285D01*
G02X313685Y314448I0J-400D01*
G03X315186Y312907I1501J-39D01*
G01X316666D01*
G02X317065Y312498I-1J-400D01*
G03Y312421I1501J-39D01*
G02X316666Y312011I-400J-10D01*
G01X315186D01*
G03X313685Y310471I0J-1501D01*
G02X313285Y310061I-400J-10D01*
G01X311806D01*
G03Y307059I0J-1501D01*
G01X314056D01*
G03X315557Y308598I0J1501D01*
G02X315957Y309008I400J10D01*
G01X317436Y309007D01*
G03X318937Y310548I0J1502D01*
G02X319337Y310959I400J11D01*
G01X320045D01*
G02X320445Y310548I0J-400D01*
G03X321946Y309007I1501J-39D01*
G01X324196D01*
G37*
G36*
G01X197900Y358700D02*
X191800D01*
X191000Y359500D01*
Y364500D01*
X191262Y364762D01*
X198538D01*
X198700Y364600D01*
Y359500D01*
X197900Y358700D01*
G37*
G36*
G01X172233Y365800D02*
X169990Y368043D01*
Y389906D01*
X170832Y390748D01*
X175933Y395850D01*
X197150D01*
X207500Y385500D01*
Y370400D01*
X202900Y365800D01*
X196602D01*
Y365852D01*
X196102D01*
Y367352D01*
X193098D01*
Y365852D01*
X192598D01*
Y365800D01*
X172233D01*
G37*
G36*
G01X269532Y191635D02*
X269482Y190885D01*
X269082D01*
X269032Y191635D01*
Y191835D01*
X269532D01*
Y191635D01*
G37*
G36*
G01X267139Y190962D02*
X266644Y191528D01*
X266927Y191811D01*
X267493Y191316D01*
X267634Y191174D01*
X267281Y190821D01*
X267139Y190962D01*
G37*
G36*
G01X266855Y190112D02*
X267350Y189546D01*
X267067Y189264D01*
X266501Y189759D01*
X266360Y189900D01*
X266713Y190253D01*
X266855Y190112D01*
G37*
G36*
G01X279932Y191635D02*
X279882Y190885D01*
X279482D01*
X279432Y191635D01*
Y191835D01*
X279932D01*
Y191635D01*
G37*
G36*
G01X272132D02*
X272082Y190885D01*
X271682D01*
X271632Y191635D01*
Y191835D01*
X272132D01*
Y191635D01*
G37*
G36*
G01X274732D02*
X274682Y190885D01*
X274282D01*
X274232Y191635D01*
Y191835D01*
X274732D01*
Y191635D01*
G37*
G36*
G01X277332D02*
X277282Y190885D01*
X276882D01*
X276832Y191635D01*
Y191835D01*
X277332D01*
Y191635D01*
G37*
G36*
G01X278132Y192035D02*
X278182Y192785D01*
X278582D01*
X278632Y192035D01*
Y191835D01*
X278132D01*
Y192035D01*
G37*
G36*
G01X275532D02*
X275582Y192785D01*
X275982D01*
X276032Y192035D01*
Y191835D01*
X275532D01*
Y192035D01*
G37*
G36*
G01X270332D02*
X270382Y192785D01*
X270782D01*
X270832Y192035D01*
Y191835D01*
X270332D01*
Y192035D01*
G37*
G36*
G01X272932D02*
X272982Y192785D01*
X273382D01*
X273432Y192035D01*
Y191835D01*
X272932D01*
Y192035D01*
G37*
G36*
G01X265299Y189122D02*
X264804Y189688D01*
X265087Y189971D01*
X265653Y189476D01*
X265794Y189334D01*
X265441Y188981D01*
X265299Y189122D01*
G37*
G36*
G01X265016Y188274D02*
X265511Y187708D01*
X265229Y187425D01*
X264663Y187920D01*
X264521Y188061D01*
X264875Y188415D01*
X265016Y188274D01*
G37*
G36*
G01X287882Y192735D02*
X288022Y193135D01*
X288442D01*
X288582Y192735D01*
Y192535D01*
X287882D01*
Y192735D01*
G37*
G36*
G01X287732Y192335D02*
X287592Y191935D01*
X287172D01*
X287032Y192335D01*
Y192535D01*
X287732D01*
Y192335D01*
G37*
G36*
G01X289432D02*
X289292Y191935D01*
X288872D01*
X288732Y192335D01*
Y192535D01*
X289432D01*
Y192335D01*
G37*
G36*
G01X283332Y192035D02*
X283382Y192785D01*
X283782D01*
X283832Y192035D01*
Y191835D01*
X283332D01*
Y192035D01*
G37*
G36*
G01X280732D02*
X280782Y192785D01*
X281182D01*
X281232Y192035D01*
Y191835D01*
X280732D01*
Y192035D01*
G37*
G36*
G01X282532Y191635D02*
X282482Y190885D01*
X282082D01*
X282032Y191635D01*
Y191835D01*
X282532D01*
Y191635D01*
G37*
G36*
G01X289582Y192735D02*
X289722Y193135D01*
X290142D01*
X290282Y192735D01*
Y192535D01*
X289582D01*
Y192735D01*
G37*
G36*
G01X291132Y192335D02*
X290992Y191935D01*
X290572D01*
X290432Y192335D01*
Y192535D01*
X291132D01*
Y192335D01*
G37*
G36*
G01X291282Y192735D02*
X291422Y193135D01*
X291842D01*
X291982Y192735D01*
Y192535D01*
X291282D01*
Y192735D01*
G37*
G36*
G01X292832Y192335D02*
X292692Y191935D01*
X292272D01*
X292132Y192335D01*
Y192535D01*
X292832D01*
Y192335D01*
G37*
G36*
G01X259966Y187391D02*
X260016Y188141D01*
X260416D01*
X260466Y187391D01*
Y187191D01*
X259966D01*
Y187391D01*
G37*
G36*
G01X261766Y186991D02*
X261716Y186241D01*
X261316D01*
X261266Y186991D01*
Y187191D01*
X261766D01*
Y186991D01*
G37*
G36*
G01X262566Y187391D02*
X262616Y188141D01*
X263016D01*
X263066Y187391D01*
Y187191D01*
X262566D01*
Y187391D01*
G37*
G36*
G01X286129Y192291D02*
X286313Y191909D01*
X286016Y191612D01*
X285634Y191796D01*
X285492Y191937D01*
X285987Y192432D01*
X286129Y192291D01*
G37*
G36*
G01X279932Y190085D02*
X279882Y189335D01*
X279482D01*
X279432Y190085D01*
Y190285D01*
X279932D01*
Y190085D01*
G37*
G36*
G01X272132D02*
X272082Y189335D01*
X271682D01*
X271632Y190085D01*
Y190285D01*
X272132D01*
Y190085D01*
G37*
G36*
G01X274732D02*
X274682Y189335D01*
X274282D01*
X274232Y190085D01*
Y190285D01*
X274732D01*
Y190085D01*
G37*
G36*
G01X277332D02*
X277282Y189335D01*
X276882D01*
X276832Y190085D01*
Y190285D01*
X277332D01*
Y190085D01*
G37*
G36*
G01X278132Y190485D02*
X278182Y191235D01*
X278582D01*
X278632Y190485D01*
Y190285D01*
X278132D01*
Y190485D01*
G37*
G36*
G01X270332D02*
X270382Y191235D01*
X270782D01*
X270832Y190485D01*
Y190285D01*
X270332D01*
Y190485D01*
G37*
G36*
G01X272932D02*
X272982Y191235D01*
X273382D01*
X273432Y190485D01*
Y190285D01*
X272932D01*
Y190485D01*
G37*
G36*
G01X275532D02*
X275582Y191235D01*
X275982D01*
X276032Y190485D01*
Y190285D01*
X275532D01*
Y190485D01*
G37*
G36*
G01X268236Y189866D02*
X267741Y190431D01*
X268024Y190714D01*
X268589Y190219D01*
X268731Y190078D01*
X268377Y189724D01*
X268236Y189866D01*
G37*
G36*
G01X267953Y189017D02*
X268448Y188451D01*
X268165Y188169D01*
X267599Y188664D01*
X267458Y188805D01*
X267812Y189159D01*
X267953Y189017D01*
G37*
G36*
G01X266396Y188026D02*
X265901Y188591D01*
X266184Y188874D01*
X266749Y188379D01*
X266891Y188238D01*
X266537Y187884D01*
X266396Y188026D01*
G37*
G36*
G01X266113Y187177D02*
X266608Y186611D01*
X266325Y186329D01*
X265759Y186824D01*
X265618Y186965D01*
X265972Y187319D01*
X266113Y187177D01*
G37*
G36*
G01X264556Y186186D02*
X264061Y186751D01*
X264344Y187034D01*
X264909Y186539D01*
X265051Y186398D01*
X264697Y186044D01*
X264556Y186186D01*
G37*
G36*
G01X287882Y191535D02*
X288022Y191935D01*
X288442D01*
X288582Y191535D01*
Y191335D01*
X287882D01*
Y191535D01*
G37*
G36*
G01X285599Y190629D02*
X285415Y191011D01*
X285712Y191308D01*
X286094Y191124D01*
X286235Y190982D01*
X285740Y190487D01*
X285599Y190629D01*
G37*
G36*
G01X285132Y190085D02*
X285082Y189335D01*
X284682D01*
X284632Y190085D01*
Y190285D01*
X285132D01*
Y190085D01*
G37*
G36*
G01X289432Y191135D02*
X289292Y190735D01*
X288872D01*
X288732Y191135D01*
Y191335D01*
X289432D01*
Y191135D01*
G37*
G36*
G01X283332Y190485D02*
X283382Y191235D01*
X283782D01*
X283832Y190485D01*
Y190285D01*
X283332D01*
Y190485D01*
G37*
G36*
G01X280732D02*
X280782Y191235D01*
X281182D01*
X281232Y190485D01*
Y190285D01*
X280732D01*
Y190485D01*
G37*
G36*
G01X282532Y190085D02*
X282482Y189335D01*
X282082D01*
X282032Y190085D01*
Y190285D01*
X282532D01*
Y190085D01*
G37*
G36*
G01X289582Y191535D02*
X289722Y191935D01*
X290142D01*
X290282Y191535D01*
Y191335D01*
X289582D01*
Y191535D01*
G37*
G36*
G01X291132Y191135D02*
X290992Y190735D01*
X290572D01*
X290432Y191135D01*
Y191335D01*
X291132D01*
Y191135D01*
G37*
G36*
G01X291282Y191535D02*
X291422Y191935D01*
X291842D01*
X291982Y191535D01*
Y191335D01*
X291282D01*
Y191535D01*
G37*
G36*
G01X292832Y191135D02*
X292692Y190735D01*
X292272D01*
X292132Y191135D01*
Y191335D01*
X292832D01*
Y191135D01*
G37*
G36*
G01X262566Y185841D02*
X262616Y186591D01*
X263016D01*
X263066Y185841D01*
Y185641D01*
X262566D01*
Y185841D01*
G37*
G36*
G01X264366Y185441D02*
X264316Y184691D01*
X263916D01*
X263866Y185441D01*
Y185641D01*
X264366D01*
Y185441D01*
G37*
G36*
G01X272233Y178511D02*
X271738Y179077D01*
X272021Y179360D01*
X272587Y178865D01*
X272728Y178723D01*
X272375Y178370D01*
X272233Y178511D01*
G37*
G36*
G01X274732Y179235D02*
X274682Y178485D01*
X274282D01*
X274232Y179235D01*
Y179435D01*
X274732D01*
Y179235D01*
G37*
G36*
G01X277332D02*
X277282Y178485D01*
X276882D01*
X276832Y179235D01*
Y179435D01*
X277332D01*
Y179235D01*
G37*
G36*
G01X279932D02*
X279882Y178485D01*
X279482D01*
X279432Y179235D01*
Y179435D01*
X279932D01*
Y179235D01*
G37*
G36*
G01X275532Y179635D02*
X275582Y180385D01*
X275982D01*
X276032Y179635D01*
Y179435D01*
X275532D01*
Y179635D01*
G37*
G36*
G01X278132D02*
X278182Y180385D01*
X278582D01*
X278632Y179635D01*
Y179435D01*
X278132D01*
Y179635D01*
G37*
G36*
G01X287936Y181080D02*
X287752Y181461D01*
X288049Y181758D01*
X288431Y181575D01*
X288572Y181433D01*
X288077Y180938D01*
X287936Y181080D01*
G37*
G36*
G01X289315Y181893D02*
X289499Y181511D01*
X289202Y181214D01*
X288820Y181398D01*
X288678Y181539D01*
X289173Y182034D01*
X289315Y181893D01*
G37*
G36*
G01X285132Y179235D02*
X285082Y178485D01*
X284682D01*
X284632Y179235D01*
Y179435D01*
X285132D01*
Y179235D01*
G37*
G36*
G01X288113Y180691D02*
X288296Y180309D01*
X287999Y180012D01*
X287618Y180196D01*
X287476Y180337D01*
X287971Y180832D01*
X288113Y180691D01*
G37*
G36*
G01X286734Y179878D02*
X286550Y180259D01*
X286847Y180556D01*
X287229Y180373D01*
X287370Y180231D01*
X286875Y179736D01*
X286734Y179878D01*
G37*
G36*
G01X283332Y179635D02*
X283382Y180385D01*
X283782D01*
X283832Y179635D01*
Y179435D01*
X283332D01*
Y179635D01*
G37*
G36*
G01X280732D02*
X280782Y180385D01*
X281182D01*
X281232Y179635D01*
Y179435D01*
X280732D01*
Y179635D01*
G37*
G36*
G01X282532Y179235D02*
X282482Y178485D01*
X282082D01*
X282032Y179235D01*
Y179435D01*
X282532D01*
Y179235D01*
G37*
G36*
G01X289138Y182282D02*
X288954Y182663D01*
X289251Y182960D01*
X289633Y182777D01*
X289774Y182635D01*
X289279Y182140D01*
X289138Y182282D01*
G37*
G36*
G01X291282Y183135D02*
X291422Y183535D01*
X291842D01*
X291982Y183135D01*
Y182935D01*
X291282D01*
Y183135D01*
G37*
G36*
G01X292832Y182735D02*
X292692Y182335D01*
X292272D01*
X292132Y182735D01*
Y182935D01*
X292832D01*
Y182735D01*
G37*
G36*
G01X271863Y175621D02*
X272613Y175571D01*
Y175171D01*
X271863Y175121D01*
X271613D01*
Y175621D01*
X271863D01*
G37*
G36*
G01X271413Y176421D02*
X270663Y176471D01*
Y176871D01*
X271413Y176921D01*
X271663D01*
Y176421D01*
X271413D01*
G37*
G36*
G01X273330Y177414D02*
X272835Y177980D01*
X273118Y178263D01*
X273684Y177768D01*
X273825Y177626D01*
X273472Y177273D01*
X273330Y177414D01*
G37*
G36*
G01X275532Y178085D02*
X275582Y178835D01*
X275982D01*
X276032Y178085D01*
Y177835D01*
X275532D01*
Y178085D01*
G37*
G36*
G01X278132D02*
X278182Y178835D01*
X278582D01*
X278632Y178085D01*
Y177835D01*
X278132D01*
Y178085D01*
G37*
G36*
G01X287582Y179029D02*
X287399Y179411D01*
X287696Y179708D01*
X288077Y179524D01*
X288254Y179347D01*
X287759Y178852D01*
X287582Y179029D01*
G37*
G36*
G01X285932Y178085D02*
X285982Y178835D01*
X286382D01*
X286432Y178085D01*
Y177835D01*
X285932D01*
Y178085D01*
G37*
G36*
G01X288784Y180231D02*
X288601Y180613D01*
X288898Y180910D01*
X289279Y180726D01*
X289456Y180549D01*
X288961Y180054D01*
X288784Y180231D01*
G37*
G36*
G01X283332Y178085D02*
X283382Y178835D01*
X283782D01*
X283832Y178085D01*
Y177835D01*
X283332D01*
Y178085D01*
G37*
G36*
G01X280732D02*
X280782Y178835D01*
X281182D01*
X281232Y178085D01*
Y177835D01*
X280732D01*
Y178085D01*
G37*
G36*
G01X291282Y181935D02*
X291422Y182335D01*
X291842D01*
X291982Y181935D01*
Y181685D01*
X291282D01*
Y181935D01*
G37*
G36*
G01X273013Y173821D02*
X272263Y173871D01*
Y174271D01*
X273013Y174321D01*
X273263D01*
Y173821D01*
X273013D01*
G37*
G36*
G01Y176421D02*
X272263Y176471D01*
Y176871D01*
X273013Y176921D01*
X273263D01*
Y176421D01*
X273013D01*
G37*
G36*
G01X289986Y181433D02*
X289803Y181815D01*
X290100Y182112D01*
X290481Y181928D01*
X290658Y181751D01*
X290163Y181256D01*
X289986Y181433D01*
G37*
G36*
G01X266502Y194145D02*
X266997Y193579D01*
X266714Y193296D01*
X266149Y193791D01*
X265972Y193968D01*
X266325Y194321D01*
X266502Y194145D01*
G37*
G36*
G01X269532Y194735D02*
X269482Y193985D01*
X269082D01*
X269032Y194735D01*
Y194985D01*
X269532D01*
Y194735D01*
G37*
G36*
G01X272132D02*
X272082Y193985D01*
X271682D01*
X271632Y194735D01*
Y194985D01*
X272132D01*
Y194735D01*
G37*
G36*
G01X274732D02*
X274682Y193985D01*
X274282D01*
X274232Y194735D01*
Y194985D01*
X274732D01*
Y194735D01*
G37*
G36*
G01X277332D02*
X277282Y193985D01*
X276882D01*
X276832Y194735D01*
Y194985D01*
X277332D01*
Y194735D01*
G37*
G36*
G01X279932D02*
X279882Y193985D01*
X279482D01*
X279432Y194735D01*
Y194985D01*
X279932D01*
Y194735D01*
G37*
G36*
G01X264662Y192305D02*
X265157Y191739D01*
X264874Y191456D01*
X264309Y191951D01*
X264132Y192128D01*
X264485Y192481D01*
X264662Y192305D01*
G37*
G36*
G01X287732Y194735D02*
X287592Y194335D01*
X287172D01*
X287032Y194735D01*
Y194985D01*
X287732D01*
Y194735D01*
G37*
G36*
G01X286032D02*
X285892Y194335D01*
X285472D01*
X285332Y194735D01*
Y194985D01*
X286032D01*
Y194735D01*
G37*
G36*
G01X289432D02*
X289292Y194335D01*
X288872D01*
X288732Y194735D01*
Y194985D01*
X289432D01*
Y194735D01*
G37*
G36*
G01X282532D02*
X282482Y193985D01*
X282082D01*
X282032Y194735D01*
Y194985D01*
X282532D01*
Y194735D01*
G37*
G36*
G01X291132D02*
X290992Y194335D01*
X290572D01*
X290432Y194735D01*
Y194985D01*
X291132D01*
Y194735D01*
G37*
G36*
G01X292832D02*
X292692Y194335D01*
X292272D01*
X292132Y194735D01*
Y194985D01*
X292832D01*
Y194735D01*
G37*
G36*
G01X259166Y190091D02*
X259116Y189341D01*
X258716D01*
X258666Y190091D01*
Y190341D01*
X259166D01*
Y190091D01*
G37*
G36*
G01X256566D02*
X256516Y189341D01*
X256116D01*
X256066Y190091D01*
Y190341D01*
X256566D01*
Y190091D01*
G37*
G36*
G01X261766D02*
X261716Y189341D01*
X261316D01*
X261266Y190091D01*
Y190341D01*
X261766D01*
Y190091D01*
G37*
G36*
G01X262822Y190465D02*
X263317Y189899D01*
X263034Y189616D01*
X262469Y190111D01*
X262292Y190288D01*
X262645Y190641D01*
X262822Y190465D01*
G37*
G36*
G01X265758Y191209D02*
X266253Y190643D01*
X265971Y190360D01*
X265405Y190855D01*
X265263Y190996D01*
X265617Y191350D01*
X265758Y191209D01*
G37*
G36*
G01X264203Y190219D02*
X263708Y190784D01*
X263991Y191067D01*
X264556Y190572D01*
X264698Y190431D01*
X264344Y190077D01*
X264203Y190219D01*
G37*
G36*
G01X272932Y193585D02*
X272982Y194335D01*
X273382D01*
X273432Y193585D01*
Y193385D01*
X272932D01*
Y193585D01*
G37*
G36*
G01X270332D02*
X270382Y194335D01*
X270782D01*
X270832Y193585D01*
Y193385D01*
X270332D01*
Y193585D01*
G37*
G36*
G01X275532D02*
X275582Y194335D01*
X275982D01*
X276032Y193585D01*
Y193385D01*
X275532D01*
Y193585D01*
G37*
G36*
G01X278132D02*
X278182Y194335D01*
X278582D01*
X278632Y193585D01*
Y193385D01*
X278132D01*
Y193585D01*
G37*
G36*
G01X274732Y193185D02*
X274682Y192435D01*
X274282D01*
X274232Y193185D01*
Y193385D01*
X274732D01*
Y193185D01*
G37*
G36*
G01X272132D02*
X272082Y192435D01*
X271682D01*
X271632Y193185D01*
Y193385D01*
X272132D01*
Y193185D01*
G37*
G36*
G01X269532D02*
X269482Y192435D01*
X269082D01*
X269032Y193185D01*
Y193385D01*
X269532D01*
Y193185D01*
G37*
G36*
G01X277332D02*
X277282Y192435D01*
X276882D01*
X276832Y193185D01*
Y193385D01*
X277332D01*
Y193185D01*
G37*
G36*
G01X279932D02*
X279882Y192435D01*
X279482D01*
X279432Y193185D01*
Y193385D01*
X279932D01*
Y193185D01*
G37*
G36*
G01X267732Y193585D02*
X267782Y194335D01*
X268182D01*
X268232Y193585D01*
Y193385D01*
X267732D01*
Y193585D01*
G37*
G36*
G01X267598Y193049D02*
X268093Y192483D01*
X267811Y192200D01*
X267245Y192695D01*
X267103Y192836D01*
X267457Y193190D01*
X267598Y193049D01*
G37*
G36*
G01X283332Y193585D02*
X283382Y194335D01*
X283782D01*
X283832Y193585D01*
Y193385D01*
X283332D01*
Y193585D01*
G37*
G36*
G01X280732D02*
X280782Y194335D01*
X281182D01*
X281232Y193585D01*
Y193385D01*
X280732D01*
Y193585D01*
G37*
G36*
G01X282532Y193185D02*
X282482Y192435D01*
X282082D01*
X282032Y193185D01*
Y193385D01*
X282532D01*
Y193185D01*
G37*
G36*
G01X289582Y193935D02*
X289722Y194335D01*
X290142D01*
X290282Y193935D01*
Y193735D01*
X289582D01*
Y193935D01*
G37*
G36*
G01X291132Y193535D02*
X290992Y193135D01*
X290572D01*
X290432Y193535D01*
Y193735D01*
X291132D01*
Y193535D01*
G37*
G36*
G01X287882Y193935D02*
X288022Y194335D01*
X288442D01*
X288582Y193935D01*
Y193735D01*
X287882D01*
Y193935D01*
G37*
G36*
G01X286182D02*
X286322Y194335D01*
X286742D01*
X286882Y193935D01*
Y193735D01*
X286182D01*
Y193935D01*
G37*
G36*
G01X287732Y193535D02*
X287592Y193135D01*
X287172D01*
X287032Y193535D01*
Y193735D01*
X287732D01*
Y193535D01*
G37*
G36*
G01X285132Y193185D02*
X285082Y192435D01*
X284682D01*
X284632Y193185D01*
Y193385D01*
X285132D01*
Y193185D01*
G37*
G36*
G01X289432Y193535D02*
X289292Y193135D01*
X288872D01*
X288732Y193535D01*
Y193735D01*
X289432D01*
Y193535D01*
G37*
G36*
G01X291282Y193935D02*
X291422Y194335D01*
X291842D01*
X291982Y193935D01*
Y193735D01*
X291282D01*
Y193935D01*
G37*
G36*
G01X292832Y193535D02*
X292692Y193135D01*
X292272D01*
X292132Y193535D01*
Y193735D01*
X292832D01*
Y193535D01*
G37*
G36*
G01X259166Y188541D02*
X259116Y187791D01*
X258716D01*
X258666Y188541D01*
Y188741D01*
X259166D01*
Y188541D01*
G37*
G36*
G01X263918Y189369D02*
X264413Y188803D01*
X264131Y188520D01*
X263565Y189015D01*
X263423Y189156D01*
X263777Y189510D01*
X263918Y189369D01*
G37*
G36*
G01X261766Y188541D02*
X261716Y187791D01*
X261316D01*
X261266Y188541D01*
Y188741D01*
X261766D01*
Y188541D01*
G37*
G36*
G01X259966Y188941D02*
X260016Y189691D01*
X260416D01*
X260466Y188941D01*
Y188741D01*
X259966D01*
Y188941D01*
G37*
G36*
G01X266041Y192057D02*
X265546Y192623D01*
X265829Y192906D01*
X266395Y192411D01*
X266536Y192269D01*
X266183Y191916D01*
X266041Y192057D01*
G37*
G36*
G01X257366Y188941D02*
X257416Y189691D01*
X257816D01*
X257866Y188941D01*
Y188741D01*
X257366D01*
Y188941D01*
G37*
G36*
G01X275532Y182735D02*
X275582Y183485D01*
X275982D01*
X276032Y182735D01*
Y182535D01*
X275532D01*
Y182735D01*
G37*
G36*
G01X272932D02*
X272982Y183485D01*
X273382D01*
X273432Y182735D01*
Y182535D01*
X272932D01*
Y182735D01*
G37*
G36*
G01X271597Y181696D02*
X272092Y181130D01*
X271810Y180847D01*
X271244Y181342D01*
X271102Y181483D01*
X271456Y181837D01*
X271597Y181696D01*
G37*
G36*
G01X269757Y179856D02*
X270252Y179290D01*
X269970Y179007D01*
X269404Y179502D01*
X269262Y179643D01*
X269616Y179997D01*
X269757Y179856D01*
G37*
G36*
G01X268200Y178865D02*
X267705Y179430D01*
X267988Y179713D01*
X268553Y179218D01*
X268695Y179077D01*
X268341Y178723D01*
X268200Y178865D01*
G37*
G36*
G01X277332Y182335D02*
X277282Y181585D01*
X276882D01*
X276832Y182335D01*
Y182535D01*
X277332D01*
Y182335D01*
G37*
G36*
G01X278132Y182735D02*
X278182Y183485D01*
X278582D01*
X278632Y182735D01*
Y182535D01*
X278132D01*
Y182735D01*
G37*
G36*
G01X274732Y182335D02*
X274682Y181585D01*
X274282D01*
X274232Y182335D01*
Y182535D01*
X274732D01*
Y182335D01*
G37*
G36*
G01X279932D02*
X279882Y181585D01*
X279482D01*
X279432Y182335D01*
Y182535D01*
X279932D01*
Y182335D01*
G37*
G36*
G01X270040Y180705D02*
X269545Y181270D01*
X269828Y181553D01*
X270393Y181058D01*
X270535Y180917D01*
X270181Y180563D01*
X270040Y180705D01*
G37*
G36*
G01X289582Y185535D02*
X289722Y185935D01*
X290142D01*
X290282Y185535D01*
Y185335D01*
X289582D01*
Y185535D01*
G37*
G36*
G01X291132Y185135D02*
X290992Y184735D01*
X290572D01*
X290432Y185135D01*
Y185335D01*
X291132D01*
Y185135D01*
G37*
G36*
G01X285132Y182335D02*
X285082Y181585D01*
X284682D01*
X284632Y182335D01*
Y182535D01*
X285132D01*
Y182335D01*
G37*
G36*
G01X282532D02*
X282482Y181585D01*
X282082D01*
X282032Y182335D01*
Y182535D01*
X282532D01*
Y182335D01*
G37*
G36*
G01X287617Y183591D02*
X287801Y183209D01*
X287504Y182912D01*
X287122Y183096D01*
X286980Y183237D01*
X287475Y183732D01*
X287617Y183591D01*
G37*
G36*
G01X287440Y183980D02*
X287256Y184362D01*
X287553Y184659D01*
X287935Y184475D01*
X288076Y184333D01*
X287581Y183838D01*
X287440Y183980D01*
G37*
G36*
G01X288819Y184793D02*
X289003Y184411D01*
X288706Y184114D01*
X288324Y184298D01*
X288182Y184439D01*
X288677Y184934D01*
X288819Y184793D01*
G37*
G36*
G01X283332Y182735D02*
X283382Y183485D01*
X283782D01*
X283832Y182735D01*
Y182535D01*
X283332D01*
Y182735D01*
G37*
G36*
G01X280732D02*
X280782Y183485D01*
X281182D01*
X281232Y182735D01*
Y182535D01*
X280732D01*
Y182735D01*
G37*
G36*
G01X291282Y185535D02*
X291422Y185935D01*
X291842D01*
X291982Y185535D01*
Y185335D01*
X291282D01*
Y185535D01*
G37*
G36*
G01X292832Y185135D02*
X292692Y184735D01*
X292272D01*
X292132Y185135D01*
Y185335D01*
X292832D01*
Y185135D01*
G37*
G36*
G01X271880Y182545D02*
X271385Y183110D01*
X271668Y183393D01*
X272233Y182898D01*
X272375Y182757D01*
X272021Y182403D01*
X271880Y182545D01*
G37*
G36*
G01X288642Y185182D02*
X288458Y185564D01*
X288755Y185861D01*
X289137Y185677D01*
X289278Y185535D01*
X288783Y185040D01*
X288642Y185182D01*
G37*
G36*
G01X278132Y181185D02*
X278182Y181935D01*
X278582D01*
X278632Y181185D01*
Y180985D01*
X278132D01*
Y181185D01*
G37*
G36*
G01X279932Y180785D02*
X279882Y180035D01*
X279482D01*
X279432Y180785D01*
Y180985D01*
X279932D01*
Y180785D01*
G37*
G36*
G01X277332D02*
X277282Y180035D01*
X276882D01*
X276832Y180785D01*
Y180985D01*
X277332D01*
Y180785D01*
G37*
G36*
G01X274732D02*
X274682Y180035D01*
X274282D01*
X274232Y180785D01*
Y180985D01*
X274732D01*
Y180785D01*
G37*
G36*
G01X271136Y179608D02*
X270641Y180174D01*
X270924Y180457D01*
X271490Y179962D01*
X271631Y179820D01*
X271278Y179467D01*
X271136Y179608D01*
G37*
G36*
G01X272932Y181185D02*
X272982Y181935D01*
X273382D01*
X273432Y181185D01*
Y180985D01*
X272932D01*
Y181185D01*
G37*
G36*
G01X272693Y180599D02*
X273188Y180033D01*
X272906Y179750D01*
X272340Y180245D01*
X272198Y180386D01*
X272552Y180740D01*
X272693Y180599D01*
G37*
G36*
G01X270854Y178759D02*
X271349Y178193D01*
X271067Y177910D01*
X270501Y178405D01*
X270359Y178546D01*
X270713Y178900D01*
X270854Y178759D01*
G37*
G36*
G01X275532Y181185D02*
X275582Y181935D01*
X275982D01*
X276032Y181185D01*
Y180985D01*
X275532D01*
Y181185D01*
G37*
G36*
G01X288289Y183131D02*
X288105Y183513D01*
X288402Y183810D01*
X288784Y183626D01*
X288925Y183484D01*
X288430Y182989D01*
X288289Y183131D01*
G37*
G36*
G01X288466Y182742D02*
X288650Y182360D01*
X288353Y182063D01*
X287971Y182247D01*
X287829Y182388D01*
X288324Y182883D01*
X288466Y182742D01*
G37*
G36*
G01X289668Y183944D02*
X289852Y183562D01*
X289555Y183265D01*
X289173Y183449D01*
X289031Y183590D01*
X289526Y184085D01*
X289668Y183944D01*
G37*
G36*
G01X291132Y183935D02*
X290992Y183535D01*
X290572D01*
X290432Y183935D01*
Y184135D01*
X291132D01*
Y183935D01*
G37*
G36*
G01X287264Y181540D02*
X287448Y181158D01*
X287151Y180861D01*
X286769Y181045D01*
X286627Y181186D01*
X287122Y181681D01*
X287264Y181540D01*
G37*
G36*
G01X287087Y181929D02*
X286903Y182311D01*
X287200Y182608D01*
X287582Y182424D01*
X287723Y182282D01*
X287228Y181787D01*
X287087Y181929D01*
G37*
G36*
G01X285132Y180785D02*
X285082Y180035D01*
X284682D01*
X284632Y180785D01*
Y180985D01*
X285132D01*
Y180785D01*
G37*
G36*
G01X283332Y181185D02*
X283382Y181935D01*
X283782D01*
X283832Y181185D01*
Y180985D01*
X283332D01*
Y181185D01*
G37*
G36*
G01X280732D02*
X280782Y181935D01*
X281182D01*
X281232Y181185D01*
Y180985D01*
X280732D01*
Y181185D01*
G37*
G36*
G01X282532Y180785D02*
X282482Y180035D01*
X282082D01*
X282032Y180785D01*
Y180985D01*
X282532D01*
Y180785D01*
G37*
G36*
G01X292832Y183935D02*
X292692Y183535D01*
X292272D01*
X292132Y183935D01*
Y184135D01*
X292832D01*
Y183935D01*
G37*
G36*
G01X291282Y184335D02*
X291422Y184735D01*
X291842D01*
X291982Y184335D01*
Y184135D01*
X291282D01*
Y184335D01*
G37*
G36*
G01X275532Y187385D02*
X275582Y188135D01*
X275982D01*
X276032Y187385D01*
Y187185D01*
X275532D01*
Y187385D01*
G37*
G36*
G01X278132D02*
X278182Y188135D01*
X278582D01*
X278632Y187385D01*
Y187185D01*
X278132D01*
Y187385D01*
G37*
G36*
G01X277332Y186985D02*
X277282Y186235D01*
X276882D01*
X276832Y186985D01*
Y187185D01*
X277332D01*
Y186985D01*
G37*
G36*
G01X274732D02*
X274682Y186235D01*
X274282D01*
X274232Y186985D01*
Y187185D01*
X274732D01*
Y186985D01*
G37*
G36*
G01X272132D02*
X272082Y186235D01*
X271682D01*
X271632Y186985D01*
Y187185D01*
X272132D01*
Y186985D01*
G37*
G36*
G01X272932Y187385D02*
X272982Y188135D01*
X273382D01*
X273432Y187385D01*
Y187185D01*
X272932D01*
Y187385D01*
G37*
G36*
G01X279932Y186985D02*
X279882Y186235D01*
X279482D01*
X279432Y186985D01*
Y187185D01*
X279932D01*
Y186985D01*
G37*
G36*
G01X268306Y184984D02*
X268801Y184418D01*
X268518Y184136D01*
X267952Y184631D01*
X267811Y184772D01*
X268165Y185126D01*
X268306Y184984D01*
G37*
G36*
G01X266750Y183994D02*
X266255Y184560D01*
X266538Y184843D01*
X267104Y184348D01*
X267245Y184206D01*
X266892Y183853D01*
X266750Y183994D01*
G37*
G36*
G01X268589Y185833D02*
X268094Y186398D01*
X268377Y186681D01*
X268942Y186186D01*
X269084Y186045D01*
X268730Y185691D01*
X268589Y185833D01*
G37*
G36*
G01X270332Y187385D02*
X270382Y188135D01*
X270782D01*
X270832Y187385D01*
Y187185D01*
X270332D01*
Y187385D01*
G37*
G36*
G01X270146Y186824D02*
X270641Y186258D01*
X270358Y185976D01*
X269792Y186471D01*
X269651Y186612D01*
X270005Y186966D01*
X270146Y186824D01*
G37*
G36*
G01X266466Y183144D02*
X266961Y182578D01*
X266678Y182296D01*
X266112Y182791D01*
X265971Y182932D01*
X266325Y183286D01*
X266466Y183144D01*
G37*
G36*
G01X291132Y188735D02*
X290992Y188335D01*
X290572D01*
X290432Y188735D01*
Y188935D01*
X291132D01*
Y188735D01*
G37*
G36*
G01X287474Y188542D02*
X287658Y188160D01*
X287361Y187863D01*
X286979Y188047D01*
X286837Y188188D01*
X287332Y188683D01*
X287474Y188542D01*
G37*
G36*
G01X286095Y187729D02*
X285911Y188111D01*
X286208Y188408D01*
X286590Y188224D01*
X286731Y188082D01*
X286236Y187587D01*
X286095Y187729D01*
G37*
G36*
G01X285132Y186985D02*
X285082Y186235D01*
X284682D01*
X284632Y186985D01*
Y187185D01*
X285132D01*
Y186985D01*
G37*
G36*
G01X289432Y188735D02*
X289292Y188335D01*
X288872D01*
X288732Y188735D01*
Y188935D01*
X289432D01*
Y188735D01*
G37*
G36*
G01X283332Y187385D02*
X283382Y188135D01*
X283782D01*
X283832Y187385D01*
Y187185D01*
X283332D01*
Y187385D01*
G37*
G36*
G01X280732D02*
X280782Y188135D01*
X281182D01*
X281232Y187385D01*
Y187185D01*
X280732D01*
Y187385D01*
G37*
G36*
G01X282532Y186985D02*
X282482Y186235D01*
X282082D01*
X282032Y186985D01*
Y187185D01*
X282532D01*
Y186985D01*
G37*
G36*
G01X289582Y189135D02*
X289722Y189535D01*
X290142D01*
X290282Y189135D01*
Y188935D01*
X289582D01*
Y189135D01*
G37*
G36*
G01X292832Y188735D02*
X292692Y188335D01*
X292272D01*
X292132Y188735D01*
Y188935D01*
X292832D01*
Y188735D01*
G37*
G36*
G01X291282Y189135D02*
X291422Y189535D01*
X291842D01*
X291982Y189135D01*
Y188935D01*
X291282D01*
Y189135D01*
G37*
G36*
G01X286272Y187340D02*
X286456Y186958D01*
X286159Y186661D01*
X285777Y186845D01*
X285635Y186986D01*
X286130Y187481D01*
X286272Y187340D01*
G37*
G36*
G01X266007Y181058D02*
X265512Y181623D01*
X265795Y181906D01*
X266360Y181411D01*
X266502Y181270D01*
X266148Y180916D01*
X266007Y181058D01*
G37*
G36*
G01X267564Y182049D02*
X268059Y181483D01*
X267776Y181201D01*
X267210Y181696D01*
X267069Y181837D01*
X267423Y182191D01*
X267564Y182049D01*
G37*
G36*
G01X269402Y183888D02*
X269897Y183322D01*
X269615Y183039D01*
X269049Y183534D01*
X268907Y183675D01*
X269261Y184029D01*
X269402Y183888D01*
G37*
G36*
G01X267847Y182898D02*
X267352Y183463D01*
X267635Y183746D01*
X268200Y183251D01*
X268342Y183110D01*
X267988Y182756D01*
X267847Y182898D01*
G37*
G36*
G01X275532Y185835D02*
X275582Y186585D01*
X275982D01*
X276032Y185835D01*
Y185635D01*
X275532D01*
Y185835D01*
G37*
G36*
G01X272932D02*
X272982Y186585D01*
X273382D01*
X273432Y185835D01*
Y185635D01*
X272932D01*
Y185835D01*
G37*
G36*
G01X278132D02*
X278182Y186585D01*
X278582D01*
X278632Y185835D01*
Y185635D01*
X278132D01*
Y185835D01*
G37*
G36*
G01X277332Y185435D02*
X277282Y184685D01*
X276882D01*
X276832Y185435D01*
Y185635D01*
X277332D01*
Y185435D01*
G37*
G36*
G01X274732D02*
X274682Y184685D01*
X274282D01*
X274232Y185435D01*
Y185635D01*
X274732D01*
Y185435D01*
G37*
G36*
G01X279932D02*
X279882Y184685D01*
X279482D01*
X279432Y185435D01*
Y185635D01*
X279932D01*
Y185435D01*
G37*
G36*
G01X269687Y184738D02*
X269192Y185303D01*
X269475Y185586D01*
X270040Y185091D01*
X270182Y184950D01*
X269828Y184596D01*
X269687Y184738D01*
G37*
G36*
G01X272132Y185435D02*
X272082Y184685D01*
X271682D01*
X271632Y185435D01*
Y185635D01*
X272132D01*
Y185435D01*
G37*
G36*
G01X286944Y186880D02*
X286760Y187262D01*
X287057Y187559D01*
X287439Y187375D01*
X287580Y187233D01*
X287085Y186738D01*
X286944Y186880D01*
G37*
G36*
G01X287121Y186491D02*
X287305Y186109D01*
X287008Y185812D01*
X286626Y185996D01*
X286484Y186137D01*
X286979Y186632D01*
X287121Y186491D01*
G37*
G36*
G01X285132Y185435D02*
X285082Y184685D01*
X284682D01*
X284632Y185435D01*
Y185635D01*
X285132D01*
Y185435D01*
G37*
G36*
G01X289432Y187535D02*
X289292Y187135D01*
X288872D01*
X288732Y187535D01*
Y187735D01*
X289432D01*
Y187535D01*
G37*
G36*
G01X283332Y185835D02*
X283382Y186585D01*
X283782D01*
X283832Y185835D01*
Y185635D01*
X283332D01*
Y185835D01*
G37*
G36*
G01X280732D02*
X280782Y186585D01*
X281182D01*
X281232Y185835D01*
Y185635D01*
X280732D01*
Y185835D01*
G37*
G36*
G01X282532Y185435D02*
X282482Y184685D01*
X282082D01*
X282032Y185435D01*
Y185635D01*
X282532D01*
Y185435D01*
G37*
G36*
G01X289582Y187935D02*
X289722Y188335D01*
X290142D01*
X290282Y187935D01*
Y187735D01*
X289582D01*
Y187935D01*
G37*
G36*
G01X291132Y187535D02*
X290992Y187135D01*
X290572D01*
X290432Y187535D01*
Y187735D01*
X291132D01*
Y187535D01*
G37*
G36*
G01X292832D02*
X292692Y187135D01*
X292272D01*
X292132Y187535D01*
Y187735D01*
X292832D01*
Y187535D01*
G37*
G36*
G01X291282Y187935D02*
X291422Y188335D01*
X291842D01*
X291982Y187935D01*
Y187735D01*
X291282D01*
Y187935D01*
G37*
G36*
G01X269049Y187921D02*
X269544Y187355D01*
X269262Y187072D01*
X268696Y187567D01*
X268554Y187708D01*
X268908Y188062D01*
X269049Y187921D01*
G37*
G36*
G01X270332Y188935D02*
X270382Y189685D01*
X270782D01*
X270832Y188935D01*
Y188735D01*
X270332D01*
Y188935D01*
G37*
G36*
G01X267209Y186081D02*
X267704Y185515D01*
X267422Y185232D01*
X266856Y185727D01*
X266714Y185868D01*
X267068Y186222D01*
X267209Y186081D01*
G37*
G36*
G01X279932Y188535D02*
X279882Y187785D01*
X279482D01*
X279432Y188535D01*
Y188735D01*
X279932D01*
Y188535D01*
G37*
G36*
G01X272132D02*
X272082Y187785D01*
X271682D01*
X271632Y188535D01*
Y188735D01*
X272132D01*
Y188535D01*
G37*
G36*
G01X274732D02*
X274682Y187785D01*
X274282D01*
X274232Y188535D01*
Y188735D01*
X274732D01*
Y188535D01*
G37*
G36*
G01X277332D02*
X277282Y187785D01*
X276882D01*
X276832Y188535D01*
Y188735D01*
X277332D01*
Y188535D01*
G37*
G36*
G01X278132Y188935D02*
X278182Y189685D01*
X278582D01*
X278632Y188935D01*
Y188735D01*
X278132D01*
Y188935D01*
G37*
G36*
G01X272932D02*
X272982Y189685D01*
X273382D01*
X273432Y188935D01*
Y188735D01*
X272932D01*
Y188935D01*
G37*
G36*
G01X275532D02*
X275582Y189685D01*
X275982D01*
X276032Y188935D01*
Y188735D01*
X275532D01*
Y188935D01*
G37*
G36*
G01X265654Y185091D02*
X265159Y185656D01*
X265442Y185939D01*
X266007Y185444D01*
X266149Y185303D01*
X265795Y184949D01*
X265654Y185091D01*
G37*
G36*
G01X267492Y186929D02*
X266997Y187495D01*
X267280Y187778D01*
X267846Y187283D01*
X267987Y187141D01*
X267634Y186788D01*
X267492Y186929D01*
G37*
G36*
G01X285132Y188535D02*
X285082Y187785D01*
X284682D01*
X284632Y188535D01*
Y188735D01*
X285132D01*
Y188535D01*
G37*
G36*
G01X289432Y189935D02*
X289292Y189535D01*
X288872D01*
X288732Y189935D01*
Y190135D01*
X289432D01*
Y189935D01*
G37*
G36*
G01X283332Y188935D02*
X283382Y189685D01*
X283782D01*
X283832Y188935D01*
Y188735D01*
X283332D01*
Y188935D01*
G37*
G36*
G01X280732D02*
X280782Y189685D01*
X281182D01*
X281232Y188935D01*
Y188735D01*
X280732D01*
Y188935D01*
G37*
G36*
G01X282532Y188535D02*
X282482Y187785D01*
X282082D01*
X282032Y188535D01*
Y188735D01*
X282532D01*
Y188535D01*
G37*
G36*
G01X289582Y190335D02*
X289722Y190735D01*
X290142D01*
X290282Y190335D01*
Y190135D01*
X289582D01*
Y190335D01*
G37*
G36*
G01X291132Y189935D02*
X290992Y189535D01*
X290572D01*
X290432Y189935D01*
Y190135D01*
X291132D01*
Y189935D01*
G37*
G36*
G01X286448Y189780D02*
X286264Y190162D01*
X286561Y190459D01*
X286943Y190275D01*
X287084Y190133D01*
X286589Y189638D01*
X286448Y189780D01*
G37*
G36*
G01X287882Y190335D02*
X288022Y190735D01*
X288442D01*
X288582Y190335D01*
Y190135D01*
X287882D01*
Y190335D01*
G37*
G36*
G01X286625Y189391D02*
X286809Y189009D01*
X286512Y188712D01*
X286130Y188896D01*
X285988Y189037D01*
X286483Y189532D01*
X286625Y189391D01*
G37*
G36*
G01X291282Y190335D02*
X291422Y190735D01*
X291842D01*
X291982Y190335D01*
Y190135D01*
X291282D01*
Y190335D01*
G37*
G36*
G01X292832Y189935D02*
X292692Y189535D01*
X292272D01*
X292132Y189935D01*
Y190135D01*
X292832D01*
Y189935D01*
G37*
G36*
G01X265369Y184241D02*
X265864Y183675D01*
X265582Y183392D01*
X265016Y183887D01*
X264874Y184028D01*
X265228Y184382D01*
X265369Y184241D01*
G37*
G36*
G01X267103Y179961D02*
X266608Y180527D01*
X266891Y180810D01*
X267457Y180315D01*
X267598Y180173D01*
X267245Y179820D01*
X267103Y179961D01*
G37*
G36*
G01X268943Y181801D02*
X268448Y182367D01*
X268731Y182650D01*
X269297Y182155D01*
X269438Y182013D01*
X269085Y181660D01*
X268943Y181801D01*
G37*
G36*
G01X268660Y180953D02*
X269155Y180387D01*
X268873Y180104D01*
X268307Y180599D01*
X268165Y180740D01*
X268519Y181094D01*
X268660Y180953D01*
G37*
G36*
G01X270500Y182793D02*
X270995Y182227D01*
X270713Y181944D01*
X270147Y182439D01*
X270005Y182580D01*
X270359Y182934D01*
X270500Y182793D01*
G37*
G36*
G01X270783Y183641D02*
X270288Y184207D01*
X270571Y184490D01*
X271137Y183995D01*
X271278Y183853D01*
X270925Y183500D01*
X270783Y183641D01*
G37*
G36*
G01X278132Y184285D02*
X278182Y185035D01*
X278582D01*
X278632Y184285D01*
Y184085D01*
X278132D01*
Y184285D01*
G37*
G36*
G01X277332Y183885D02*
X277282Y183135D01*
X276882D01*
X276832Y183885D01*
Y184085D01*
X277332D01*
Y183885D01*
G37*
G36*
G01X274732D02*
X274682Y183135D01*
X274282D01*
X274232Y183885D01*
Y184085D01*
X274732D01*
Y183885D01*
G37*
G36*
G01X279932D02*
X279882Y183135D01*
X279482D01*
X279432Y183885D01*
Y184085D01*
X279932D01*
Y183885D01*
G37*
G36*
G01X272932Y184285D02*
X272982Y185035D01*
X273382D01*
X273432Y184285D01*
Y184085D01*
X272932D01*
Y184285D01*
G37*
G36*
G01X275532D02*
X275582Y185035D01*
X275982D01*
X276032Y184285D01*
Y184085D01*
X275532D01*
Y184285D01*
G37*
G36*
G01X291132Y186335D02*
X290992Y185935D01*
X290572D01*
X290432Y186335D01*
Y186535D01*
X291132D01*
Y186335D01*
G37*
G36*
G01X289582Y186735D02*
X289722Y187135D01*
X290142D01*
X290282Y186735D01*
Y186535D01*
X289582D01*
Y186735D01*
G37*
G36*
G01X285132Y183885D02*
X285082Y183135D01*
X284682D01*
X284632Y183885D01*
Y184085D01*
X285132D01*
Y183885D01*
G37*
G36*
G01X286768Y184440D02*
X286952Y184058D01*
X286655Y183761D01*
X286273Y183945D01*
X286131Y184086D01*
X286626Y184581D01*
X286768Y184440D01*
G37*
G36*
G01X287793Y186031D02*
X287609Y186413D01*
X287906Y186710D01*
X288288Y186526D01*
X288429Y186384D01*
X287934Y185889D01*
X287793Y186031D01*
G37*
G36*
G01X287970Y185642D02*
X288154Y185260D01*
X287857Y184963D01*
X287475Y185147D01*
X287333Y185288D01*
X287828Y185783D01*
X287970Y185642D01*
G37*
G36*
G01X286591Y184829D02*
X286407Y185211D01*
X286704Y185508D01*
X287086Y185324D01*
X287227Y185182D01*
X286732Y184687D01*
X286591Y184829D01*
G37*
G36*
G01X282532Y183885D02*
X282482Y183135D01*
X282082D01*
X282032Y183885D01*
Y184085D01*
X282532D01*
Y183885D01*
G37*
G36*
G01X283332Y184285D02*
X283382Y185035D01*
X283782D01*
X283832Y184285D01*
Y184085D01*
X283332D01*
Y184285D01*
G37*
G36*
G01X280732D02*
X280782Y185035D01*
X281182D01*
X281232Y184285D01*
Y184085D01*
X280732D01*
Y184285D01*
G37*
G36*
G01X291282Y186735D02*
X291422Y187135D01*
X291842D01*
X291982Y186735D01*
Y186535D01*
X291282D01*
Y186735D01*
G37*
G36*
G01X292832Y186335D02*
X292692Y185935D01*
X292272D01*
X292132Y186335D01*
Y186535D01*
X292832D01*
Y186335D01*
G37*
G36*
G01X291963Y402651D02*
X292103Y403051D01*
X292523D01*
X292663Y402651D01*
Y402401D01*
X291963D01*
Y402651D01*
G37*
G36*
G01X290365Y406497D02*
X290747Y406681D01*
X291044Y406384D01*
X290860Y406002D01*
X290718Y405861D01*
X290224Y406355D01*
X290365Y406497D01*
G37*
G36*
G01X285210Y408599D02*
X285070Y408199D01*
X284650D01*
X284510Y408599D01*
Y408799D01*
X285210D01*
Y408599D01*
G37*
G36*
G01X285360Y408999D02*
X285500Y409399D01*
X285920D01*
X286060Y408999D01*
Y408799D01*
X285360D01*
Y408999D01*
G37*
G36*
G01X287961Y408901D02*
X288343Y409085D01*
X288640Y408788D01*
X288456Y408406D01*
X288314Y408265D01*
X287819Y408760D01*
X287961Y408901D01*
G37*
G36*
G01X288774Y407522D02*
X288392Y407338D01*
X288095Y407635D01*
X288279Y408017D01*
X288420Y408159D01*
X288915Y407664D01*
X288774Y407522D01*
G37*
G36*
G01X287060Y408999D02*
X287200Y409399D01*
X287620D01*
X287760Y408999D01*
Y408799D01*
X287060D01*
Y408999D01*
G37*
G36*
G01X286910Y408599D02*
X286770Y408199D01*
X286350D01*
X286210Y408599D01*
Y408799D01*
X286910D01*
Y408599D01*
G37*
G36*
G01X289163Y407699D02*
X289545Y407883D01*
X289842Y407586D01*
X289658Y407204D01*
X289516Y407063D01*
X289021Y407558D01*
X289163Y407699D01*
G37*
G36*
G01X283660Y408999D02*
X283800Y409399D01*
X284220D01*
X284360Y408999D01*
Y408799D01*
X283660D01*
Y408999D01*
G37*
G36*
G01X289976Y406320D02*
X289594Y406136D01*
X289297Y406433D01*
X289481Y406815D01*
X289622Y406957D01*
X290117Y406462D01*
X289976Y406320D01*
G37*
G36*
G01X291963Y405051D02*
X292103Y405451D01*
X292523D01*
X292663Y405051D01*
Y404851D01*
X291963D01*
Y405051D01*
G37*
G36*
G01X291178Y405118D02*
X290796Y404934D01*
X290499Y405231D01*
X290683Y405613D01*
X290825Y405754D01*
X291320Y405259D01*
X291178Y405118D01*
G37*
G36*
G01X289623Y408371D02*
X289241Y408187D01*
X288944Y408484D01*
X289128Y408866D01*
X289269Y409008D01*
X289764Y408513D01*
X289623Y408371D01*
G37*
G36*
G01X288810Y409750D02*
X289192Y409934D01*
X289489Y409637D01*
X289305Y409255D01*
X289163Y409114D01*
X288668Y409609D01*
X288810Y409750D01*
G37*
G36*
G01X281960Y410199D02*
X282100Y410599D01*
X282520D01*
X282660Y410199D01*
Y409999D01*
X281960D01*
Y410199D01*
G37*
G36*
G01X290012Y408548D02*
X290394Y408732D01*
X290691Y408435D01*
X290507Y408053D01*
X290365Y407912D01*
X289870Y408407D01*
X290012Y408548D01*
G37*
G36*
G01X290825Y407169D02*
X290443Y406985D01*
X290146Y407282D01*
X290330Y407664D01*
X290471Y407806D01*
X290966Y407311D01*
X290825Y407169D01*
G37*
G36*
G01X286910Y409799D02*
X286770Y409399D01*
X286350D01*
X286210Y409799D01*
Y409999D01*
X286910D01*
Y409799D01*
G37*
G36*
G01X285210D02*
X285070Y409399D01*
X284650D01*
X284510Y409799D01*
Y409999D01*
X285210D01*
Y409799D01*
G37*
G36*
G01X283510D02*
X283370Y409399D01*
X282950D01*
X282810Y409799D01*
Y409999D01*
X283510D01*
Y409799D01*
G37*
G36*
G01X285360Y410199D02*
X285500Y410599D01*
X285920D01*
X286060Y410199D01*
Y409999D01*
X285360D01*
Y410199D01*
G37*
G36*
G01X287060D02*
X287200Y410599D01*
X287620D01*
X287760Y410199D01*
Y409999D01*
X287060D01*
Y410199D01*
G37*
G36*
G01X283660D02*
X283800Y410599D01*
X284220D01*
X284360Y410199D01*
Y409999D01*
X283660D01*
Y410199D01*
G37*
G36*
G01X291214Y407346D02*
X291596Y407530D01*
X291893Y407233D01*
X291709Y406851D01*
X291567Y406710D01*
X291072Y407205D01*
X291214Y407346D01*
G37*
G36*
G01X292027Y405967D02*
X291645Y405783D01*
X291348Y406080D01*
X291532Y406462D01*
X291673Y406604D01*
X292168Y406109D01*
X292027Y405967D01*
G37*
G36*
G01X289560Y420329D02*
X289178Y420145D01*
X288881Y420442D01*
X289065Y420824D01*
X289206Y420965D01*
X289701Y420470D01*
X289560Y420329D01*
G37*
G36*
G01X290762Y419127D02*
X290380Y418943D01*
X290083Y419240D01*
X290267Y419622D01*
X290408Y419763D01*
X290903Y419268D01*
X290762Y419127D01*
G37*
G36*
G01X289948Y420505D02*
X290330Y420689D01*
X290627Y420392D01*
X290443Y420010D01*
X290302Y419869D01*
X289807Y420364D01*
X289948Y420505D01*
G37*
G36*
G01X288746Y421707D02*
X289128Y421891D01*
X289425Y421594D01*
X289241Y421213D01*
X289100Y421071D01*
X288605Y421566D01*
X288746Y421707D01*
G37*
G36*
G01X288357Y421531D02*
X287976Y421347D01*
X287679Y421644D01*
X287862Y422026D01*
X288004Y422167D01*
X288499Y421672D01*
X288357Y421531D01*
G37*
G36*
G01X287155Y422733D02*
X286774Y422549D01*
X286477Y422846D01*
X286660Y423228D01*
X286802Y423369D01*
X287297Y422874D01*
X287155Y422733D01*
G37*
G36*
G01X287544Y422910D02*
X287926Y423093D01*
X288223Y422796D01*
X288039Y422415D01*
X287898Y422273D01*
X287403Y422768D01*
X287544Y422910D01*
G37*
G36*
G01X286342Y424112D02*
X286724Y424295D01*
X287021Y423999D01*
X286837Y423617D01*
X286696Y423475D01*
X286201Y423970D01*
X286342Y424112D01*
G37*
G36*
G01X285953Y423935D02*
X285572Y423751D01*
X285275Y424048D01*
X285458Y424430D01*
X285600Y424571D01*
X286095Y424076D01*
X285953Y423935D01*
G37*
G36*
G01X293166Y416722D02*
X292784Y416539D01*
X292487Y416836D01*
X292671Y417217D01*
X292812Y417359D01*
X293307Y416864D01*
X293166Y416722D01*
G37*
G36*
G01X291964Y417924D02*
X291582Y417741D01*
X291285Y418038D01*
X291469Y418419D01*
X291610Y418561D01*
X292105Y418066D01*
X291964Y417924D01*
G37*
G36*
G01X292353Y418101D02*
X292734Y418285D01*
X293031Y417988D01*
X292848Y417606D01*
X292706Y417465D01*
X292211Y417960D01*
X292353Y418101D01*
G37*
G36*
G01X291151Y419303D02*
X291532Y419487D01*
X291829Y419190D01*
X291646Y418808D01*
X291504Y418667D01*
X291009Y419162D01*
X291151Y419303D01*
G37*
G36*
G01X285140Y425314D02*
X285522Y425497D01*
X285819Y425201D01*
X285635Y424819D01*
X285494Y424677D01*
X284999Y425172D01*
X285140Y425314D01*
G37*
G36*
G01X285600Y425986D02*
X285218Y425802D01*
X284921Y426099D01*
X285105Y426481D01*
X285282Y426657D01*
X285777Y426162D01*
X285600Y425986D01*
G37*
G36*
G01X290408Y421177D02*
X290026Y420993D01*
X289729Y421290D01*
X289913Y421672D01*
X290090Y421849D01*
X290585Y421354D01*
X290408Y421177D01*
G37*
G36*
G01X289206Y422379D02*
X288824Y422195D01*
X288527Y422492D01*
X288711Y422874D01*
X288888Y423051D01*
X289383Y422556D01*
X289206Y422379D01*
G37*
G36*
G01X288004Y423581D02*
X287622Y423398D01*
X287325Y423695D01*
X287509Y424076D01*
X287686Y424253D01*
X288181Y423758D01*
X288004Y423581D01*
G37*
G36*
G01X286802Y424784D02*
X286420Y424600D01*
X286123Y424897D01*
X286307Y425278D01*
X286484Y425455D01*
X286979Y424960D01*
X286802Y424784D01*
G37*
G36*
G01X291610Y419975D02*
X291228Y419791D01*
X290931Y420088D01*
X291115Y420470D01*
X291292Y420647D01*
X291787Y420152D01*
X291610Y419975D01*
G37*
G36*
G01X292812Y418773D02*
X292431Y418589D01*
X292134Y418886D01*
X292317Y419268D01*
X292494Y419445D01*
X292989Y418950D01*
X292812Y418773D01*
G37*
G36*
G01X287465Y406001D02*
X287847Y406185D01*
X288144Y405888D01*
X287960Y405506D01*
X287783Y405330D01*
X287288Y405825D01*
X287465Y406001D01*
G37*
G36*
G01X285360Y406599D02*
X285500Y406999D01*
X285920D01*
X286060Y406599D01*
Y406349D01*
X285360D01*
Y406599D01*
G37*
G36*
G01X283434Y405480D02*
X283250Y405862D01*
X283547Y406159D01*
X283929Y405975D01*
X284106Y405799D01*
X283611Y405304D01*
X283434Y405480D01*
G37*
G36*
G01X288667Y404799D02*
X289049Y404983D01*
X289346Y404686D01*
X289162Y404304D01*
X288985Y404128D01*
X288491Y404622D01*
X288667Y404799D01*
G37*
G36*
G01X282232Y404278D02*
X282048Y404660D01*
X282345Y404957D01*
X282727Y404773D01*
X282903Y404596D01*
X282409Y404102D01*
X282232Y404278D01*
G37*
G36*
G01X289869Y403597D02*
X290251Y403781D01*
X290548Y403484D01*
X290364Y403102D01*
X290187Y402926D01*
X289693Y403420D01*
X289869Y403597D01*
G37*
G36*
G01X282585Y406329D02*
X282401Y406711D01*
X282698Y407008D01*
X283080Y406824D01*
X283257Y406648D01*
X282762Y406153D01*
X282585Y406329D01*
G37*
G36*
G01X289127Y405471D02*
X288745Y405287D01*
X288448Y405584D01*
X288632Y405966D01*
X288773Y406108D01*
X289268Y405613D01*
X289127Y405471D01*
G37*
G36*
G01X282762Y405940D02*
X282946Y405558D01*
X282649Y405261D01*
X282267Y405445D01*
X282126Y405587D01*
X282621Y406082D01*
X282762Y405940D01*
G37*
G36*
G01X281383Y405127D02*
X281199Y405509D01*
X281496Y405806D01*
X281878Y405622D01*
X282055Y405446D01*
X281560Y404951D01*
X281383Y405127D01*
G37*
G36*
G01X290329Y404269D02*
X289947Y404085D01*
X289650Y404382D01*
X289834Y404764D01*
X289976Y404905D01*
X290471Y404410D01*
X290329Y404269D01*
G37*
G36*
G01X289516Y405648D02*
X289898Y405832D01*
X290195Y405535D01*
X290011Y405153D01*
X289869Y405012D01*
X289375Y405506D01*
X289516Y405648D01*
G37*
G36*
G01X288314Y406850D02*
X288696Y407034D01*
X288993Y406737D01*
X288809Y406355D01*
X288667Y406214D01*
X288172Y406709D01*
X288314Y406850D01*
G37*
G36*
G01X285360Y407799D02*
X285500Y408199D01*
X285920D01*
X286060Y407799D01*
Y407599D01*
X285360D01*
Y407799D01*
G37*
G36*
G01X287925Y406673D02*
X287543Y406489D01*
X287246Y406786D01*
X287430Y407168D01*
X287571Y407310D01*
X288066Y406815D01*
X287925Y406673D01*
G37*
G36*
G01X286910Y407399D02*
X286770Y406999D01*
X286350D01*
X286210Y407399D01*
Y407599D01*
X286910D01*
Y407399D01*
G37*
G36*
G01X285210D02*
X285070Y406999D01*
X284650D01*
X284510Y407399D01*
Y407599D01*
X285210D01*
Y407399D01*
G37*
G36*
G01X283964Y407142D02*
X284148Y406760D01*
X283851Y406463D01*
X283469Y406647D01*
X283328Y406789D01*
X283823Y407284D01*
X283964Y407142D01*
G37*
G36*
G01X290718Y404446D02*
X291100Y404630D01*
X291397Y404333D01*
X291213Y403951D01*
X291071Y403810D01*
X290577Y404304D01*
X290718Y404446D01*
G37*
G36*
G01X291963Y403851D02*
X292103Y404251D01*
X292523D01*
X292663Y403851D01*
Y403651D01*
X291963D01*
Y403851D01*
G37*
G36*
G01X289064Y417429D02*
X288682Y417245D01*
X288385Y417542D01*
X288569Y417924D01*
X288710Y418065D01*
X289205Y417570D01*
X289064Y417429D01*
G37*
G36*
G01X290266Y416226D02*
X289884Y416043D01*
X289587Y416340D01*
X289771Y416721D01*
X289912Y416863D01*
X290407Y416368D01*
X290266Y416226D01*
G37*
G36*
G01X289453Y417605D02*
X289834Y417789D01*
X290131Y417492D01*
X289948Y417110D01*
X289806Y416969D01*
X289311Y417464D01*
X289453Y417605D01*
G37*
G36*
G01X288250Y418807D02*
X288632Y418991D01*
X288929Y418694D01*
X288745Y418312D01*
X288604Y418171D01*
X288109Y418666D01*
X288250Y418807D01*
G37*
G36*
G01X287048Y420009D02*
X287430Y420193D01*
X287727Y419896D01*
X287543Y419514D01*
X287402Y419373D01*
X286907Y419868D01*
X287048Y420009D01*
G37*
G36*
G01X287862Y418631D02*
X287480Y418447D01*
X287183Y418744D01*
X287367Y419126D01*
X287508Y419267D01*
X288003Y418772D01*
X287862Y418631D01*
G37*
G36*
G01X291468Y415024D02*
X291086Y414841D01*
X290789Y415138D01*
X290973Y415519D01*
X291114Y415661D01*
X291609Y415166D01*
X291468Y415024D01*
G37*
G36*
G01X292670Y413822D02*
X292288Y413638D01*
X291991Y413935D01*
X292175Y414317D01*
X292316Y414459D01*
X292811Y413964D01*
X292670Y413822D01*
G37*
G36*
G01X290655Y416403D02*
X291036Y416587D01*
X291333Y416290D01*
X291150Y415908D01*
X291008Y415767D01*
X290513Y416262D01*
X290655Y416403D01*
G37*
G36*
G01X291857Y415201D02*
X292239Y415385D01*
X292536Y415088D01*
X292352Y414706D01*
X292210Y414565D01*
X291715Y415060D01*
X291857Y415201D01*
G37*
G36*
G01X291115Y417075D02*
X290733Y416892D01*
X290436Y417189D01*
X290620Y417570D01*
X290761Y417712D01*
X291256Y417217D01*
X291115Y417075D01*
G37*
G36*
G01X290302Y418454D02*
X290683Y418638D01*
X290980Y418341D01*
X290797Y417959D01*
X290655Y417818D01*
X290160Y418313D01*
X290302Y418454D01*
G37*
G36*
G01X288711Y419480D02*
X288329Y419296D01*
X288032Y419593D01*
X288216Y419975D01*
X288357Y420116D01*
X288852Y419621D01*
X288711Y419480D01*
G37*
G36*
G01X287508Y420682D02*
X287127Y420498D01*
X286830Y420795D01*
X287013Y421177D01*
X287155Y421318D01*
X287650Y420823D01*
X287508Y420682D01*
G37*
G36*
G01X287897Y420858D02*
X288279Y421042D01*
X288576Y420745D01*
X288392Y420364D01*
X288251Y420222D01*
X287756Y420717D01*
X287897Y420858D01*
G37*
G36*
G01X289099Y419656D02*
X289481Y419840D01*
X289778Y419543D01*
X289594Y419161D01*
X289453Y419020D01*
X288958Y419515D01*
X289099Y419656D01*
G37*
G36*
G01X289913Y418278D02*
X289531Y418094D01*
X289234Y418391D01*
X289418Y418773D01*
X289559Y418914D01*
X290054Y418419D01*
X289913Y418278D01*
G37*
G36*
G01X286695Y422061D02*
X287077Y422244D01*
X287374Y421947D01*
X287190Y421566D01*
X287049Y421424D01*
X286554Y421919D01*
X286695Y422061D01*
G37*
G36*
G01X292317Y415873D02*
X291935Y415690D01*
X291638Y415987D01*
X291822Y416368D01*
X291963Y416510D01*
X292458Y416015D01*
X292317Y415873D01*
G37*
G36*
G01X291504Y417252D02*
X291885Y417436D01*
X292182Y417139D01*
X291999Y416757D01*
X291857Y416616D01*
X291362Y417111D01*
X291504Y417252D01*
G37*
G36*
G01X292706Y416050D02*
X293088Y416234D01*
X293385Y415937D01*
X293201Y415555D01*
X293059Y415414D01*
X292564Y415909D01*
X292706Y416050D01*
G37*
G36*
G01X288921Y412477D02*
X288539Y412294D01*
X288242Y412591D01*
X288426Y412972D01*
X288567Y413114D01*
X289062Y412619D01*
X288921Y412477D01*
G37*
G36*
G01X290123Y411275D02*
X289741Y411091D01*
X289444Y411388D01*
X289628Y411770D01*
X289769Y411912D01*
X290264Y411417D01*
X290123Y411275D01*
G37*
G36*
G01X289310Y412654D02*
X289692Y412838D01*
X289989Y412541D01*
X289805Y412159D01*
X289663Y412018D01*
X289168Y412513D01*
X289310Y412654D01*
G37*
G36*
G01X290512Y411452D02*
X290894Y411636D01*
X291191Y411339D01*
X291007Y410957D01*
X290865Y410816D01*
X290370Y411311D01*
X290512Y411452D01*
G37*
G36*
G01X291325Y410073D02*
X290943Y409889D01*
X290646Y410186D01*
X290830Y410568D01*
X290971Y410710D01*
X291466Y410215D01*
X291325Y410073D01*
G37*
G36*
G01X292527Y408871D02*
X292145Y408687D01*
X291848Y408984D01*
X292032Y409366D01*
X292173Y409508D01*
X292668Y409013D01*
X292527Y408871D01*
G37*
G36*
G01X291714Y410250D02*
X292096Y410434D01*
X292393Y410137D01*
X292209Y409755D01*
X292067Y409614D01*
X291572Y410109D01*
X291714Y410250D01*
G37*
G36*
G01X288568Y414528D02*
X288186Y414345D01*
X287889Y414642D01*
X288073Y415023D01*
X288214Y415165D01*
X288709Y414670D01*
X288568Y414528D01*
G37*
G36*
G01X287755Y415907D02*
X288136Y416091D01*
X288433Y415794D01*
X288250Y415412D01*
X288108Y415271D01*
X287613Y415766D01*
X287755Y415907D01*
G37*
G36*
G01X289770Y413326D02*
X289388Y413143D01*
X289091Y413440D01*
X289275Y413821D01*
X289416Y413963D01*
X289911Y413468D01*
X289770Y413326D01*
G37*
G36*
G01X288957Y414705D02*
X289338Y414889D01*
X289635Y414592D01*
X289452Y414210D01*
X289310Y414069D01*
X288815Y414564D01*
X288957Y414705D01*
G37*
G36*
G01X290159Y413503D02*
X290541Y413687D01*
X290838Y413390D01*
X290654Y413008D01*
X290512Y412867D01*
X290017Y413362D01*
X290159Y413503D01*
G37*
G36*
G01X290972Y412124D02*
X290590Y411940D01*
X290293Y412237D01*
X290477Y412619D01*
X290618Y412761D01*
X291113Y412266D01*
X290972Y412124D01*
G37*
G36*
G01X292174Y410922D02*
X291792Y410738D01*
X291495Y411035D01*
X291679Y411417D01*
X291820Y411559D01*
X292315Y411064D01*
X292174Y410922D01*
G37*
G36*
G01X291361Y412301D02*
X291743Y412485D01*
X292040Y412188D01*
X291856Y411806D01*
X291714Y411665D01*
X291219Y412160D01*
X291361Y412301D01*
G37*
G36*
G01X292563Y411099D02*
X292945Y411283D01*
X293242Y410986D01*
X293058Y410604D01*
X292916Y410463D01*
X292421Y410958D01*
X292563Y411099D01*
G37*
G36*
G01X293376Y409720D02*
X292994Y409536D01*
X292697Y409833D01*
X292881Y410215D01*
X293022Y410357D01*
X293517Y409862D01*
X293376Y409720D01*
G37*
G36*
G01X288461Y411805D02*
X288843Y411989D01*
X289140Y411692D01*
X288956Y411310D01*
X288814Y411169D01*
X288319Y411664D01*
X288461Y411805D01*
G37*
G36*
G01X288072Y411628D02*
X287690Y411444D01*
X287393Y411741D01*
X287577Y412123D01*
X287718Y412265D01*
X288213Y411770D01*
X288072Y411628D01*
G37*
G36*
G01X289274Y410426D02*
X288892Y410242D01*
X288595Y410539D01*
X288779Y410921D01*
X288920Y411063D01*
X289415Y410568D01*
X289274Y410426D01*
G37*
G36*
G01X290476Y409224D02*
X290094Y409040D01*
X289797Y409337D01*
X289981Y409719D01*
X290122Y409861D01*
X290617Y409366D01*
X290476Y409224D01*
G37*
G36*
G01X289663Y410603D02*
X290045Y410787D01*
X290342Y410490D01*
X290158Y410108D01*
X290016Y409967D01*
X289521Y410462D01*
X289663Y410603D01*
G37*
G36*
G01X290865Y409401D02*
X291247Y409585D01*
X291544Y409288D01*
X291360Y408906D01*
X291218Y408765D01*
X290723Y409260D01*
X290865Y409401D01*
G37*
G36*
G01X291678Y408022D02*
X291296Y407838D01*
X290999Y408135D01*
X291183Y408517D01*
X291324Y408659D01*
X291819Y408164D01*
X291678Y408022D01*
G37*
G36*
G01X292067Y408199D02*
X292449Y408383D01*
X292746Y408086D01*
X292562Y407704D01*
X292420Y407563D01*
X291925Y408058D01*
X292067Y408199D01*
G37*
G36*
G01X288215Y416579D02*
X287833Y416396D01*
X287536Y416693D01*
X287720Y417074D01*
X287861Y417216D01*
X288356Y416721D01*
X288215Y416579D01*
G37*
G36*
G01X289417Y415377D02*
X289035Y415194D01*
X288738Y415491D01*
X288922Y415872D01*
X289063Y416014D01*
X289558Y415519D01*
X289417Y415377D01*
G37*
G36*
G01X288604Y416756D02*
X288985Y416940D01*
X289282Y416643D01*
X289099Y416261D01*
X288957Y416120D01*
X288462Y416615D01*
X288604Y416756D01*
G37*
G36*
G01X290619Y414175D02*
X290237Y413992D01*
X289940Y414289D01*
X290124Y414670D01*
X290265Y414812D01*
X290760Y414317D01*
X290619Y414175D01*
G37*
G36*
G01X289806Y415554D02*
X290187Y415738D01*
X290484Y415441D01*
X290301Y415059D01*
X290159Y414918D01*
X289664Y415413D01*
X289806Y415554D01*
G37*
G36*
G01X291821Y412973D02*
X291439Y412789D01*
X291142Y413086D01*
X291326Y413468D01*
X291467Y413610D01*
X291962Y413115D01*
X291821Y412973D01*
G37*
G36*
G01X291008Y414352D02*
X291390Y414536D01*
X291687Y414239D01*
X291503Y413857D01*
X291361Y413716D01*
X290866Y414211D01*
X291008Y414352D01*
G37*
G36*
G01X292210Y413150D02*
X292592Y413334D01*
X292889Y413037D01*
X292705Y412655D01*
X292563Y412514D01*
X292068Y413009D01*
X292210Y413150D01*
G37*
G36*
G01X293023Y411771D02*
X292641Y411587D01*
X292344Y411884D01*
X292528Y412266D01*
X292669Y412408D01*
X293164Y411913D01*
X293023Y411771D01*
G37*
G36*
G01X299866Y7640D02*
X299412Y8094D01*
Y12838D01*
X302515Y15941D01*
Y18419D01*
X303000Y18904D01*
Y23000D01*
X303700Y23700D01*
X305100D01*
X305500Y23300D01*
Y19507D01*
X306175Y18832D01*
X306510D01*
G02X306769Y18127I0J-400D01*
G03X308185Y15751I906J-1070D01*
G02X308731Y15379I146J-372D01*
G01Y8379D01*
X307992Y7640D01*
X299866D01*
G37*
G36*
G01X309892Y27500D02*
X309392Y28000D01*
Y31452D01*
X309410Y31492D01*
G03Y32708I-1318J608D01*
G01X309392Y32748D01*
Y34639D01*
G02X310065Y34932I400J0D01*
G03X312419Y36068I956J1025D01*
G02X312817Y36500I399J32D01*
G01X316150D01*
Y35957D01*
G03X319278I1564J0D01*
G01Y36500D01*
X322611D01*
G02X323009Y36068I-1J-400D01*
G03X325776Y36257I1398J-111D01*
G01X325772Y36278D01*
Y36500D01*
X326389D01*
Y36278D01*
X326385Y36257D01*
G03X329152Y36068I1369J-300D01*
G02X329550Y36500I399J32D01*
G01X332651D01*
G02X333049Y36068I-1J-400D01*
G03X335816Y36257I1398J-111D01*
G01X335812Y36278D01*
Y36500D01*
X336428D01*
Y36278D01*
X336424Y36257D01*
G03X339191Y36068I1369J-300D01*
G02X339589Y36500I399J32D01*
G01X342690D01*
G02X343088Y36068I-1J-400D01*
G03X345855Y36257I1398J-111D01*
G01X345851Y36278D01*
Y36500D01*
X346468D01*
Y36278D01*
X346464Y36257D01*
G03X349231Y36068I1369J-300D01*
G02X349629Y36500I399J32D01*
G01X352730D01*
G02X353128Y36068I-1J-400D01*
G03X355924I1398J-111D01*
G02X356322Y36500I399J32D01*
G01X359323D01*
G02X359721Y36067I-1J-400D01*
G03X362540Y35228I1497J-126D01*
G02X363243I352J-190D01*
G03X366062Y36067I1322J713D01*
G02X366460Y36500I399J33D01*
G01X368392D01*
X368892Y36000D01*
Y35516D01*
X368890Y35515D01*
Y27998D01*
X368392Y27500D01*
X366363D01*
G02X365964Y27925I0J400D01*
G03X363190Y27739I-1399J89D01*
G01X363194Y27720D01*
Y27500D01*
X362589D01*
Y27720D01*
X362593Y27739D01*
G03X359819Y27925I-1375J275D01*
G02X359420Y27500I-399J-25D01*
G01X356323D01*
G02X355924Y27927I0J400D01*
G03X353152Y27740I-1399J95D01*
G01X353156Y27720D01*
Y27500D01*
X352548D01*
Y27720D01*
X352552Y27740D01*
G03X349780Y27927I-1373J282D01*
G02X349381Y27500I-399J-27D01*
G01X346284D01*
G02X345885Y27927I0J400D01*
G03X343113Y27740I-1399J95D01*
G01X343117Y27720D01*
Y27500D01*
X342509D01*
Y27720D01*
X342513Y27740D01*
G03X339741Y27927I-1373J282D01*
G02X339342Y27500I-399J-27D01*
G01X336244D01*
G02X335845Y27925I0J400D01*
G03X335783Y28437I-1399J90D01*
G01X335774Y28466D01*
Y28562D01*
X335706Y28630D01*
X335691Y28658D01*
G03X333071Y27739I-1245J-644D01*
G01X333075Y27720D01*
Y27500D01*
X332471D01*
Y27720D01*
X332475Y27739D01*
G03X329701Y27925I-1375J275D01*
G02X329302Y27500I-399J-25D01*
G01X326205D01*
G02X325806Y27925I0J400D01*
G03X323032Y27739I-1399J89D01*
G01X323036Y27720D01*
Y27500D01*
X322432D01*
Y27720D01*
X322436Y27739D01*
G03X319662Y27925I-1375J275D01*
G02X319263Y27500I-399J-25D01*
G01X316166D01*
G02X315767Y27925I0J400D01*
G03X312969I-1399J89D01*
G02X312570Y27500I-399J-25D01*
G01X309892D01*
G37*
G36*
G01Y-10500D02*
Y-6293D01*
G02X310445Y-5923I400J0D01*
G03X312368Y-3872I576J1387D01*
G01X312348Y-3830D01*
Y-2144D01*
X313192Y-1300D01*
X316150D01*
Y-4536D01*
G03X319278I1564J0D01*
G01Y-1300D01*
X323080D01*
Y-3830D01*
X323060Y-3872D01*
G03X325754I1347J-664D01*
G01X325734Y-3830D01*
Y-1300D01*
X326269D01*
Y-1514D01*
X326267Y-1529D01*
G03X329256Y-1709I1487J-214D01*
G02X329655Y-1300I400J9D01*
G01X332546D01*
G02X332945Y-1709I-1J-400D01*
G03X335934Y-1529I1502J-34D01*
G01X335932Y-1514D01*
Y-1300D01*
X336466D01*
Y-3830D01*
X336446Y-3872D01*
G03X339140I1347J-664D01*
G01X339120Y-3830D01*
Y-1300D01*
X343160D01*
Y-3830D01*
X343139Y-3872D01*
G03X345833I1347J-664D01*
G01X345812Y-3830D01*
Y-1300D01*
X346348D01*
Y-1514D01*
X346346Y-1529D01*
G03X349335Y-1709I1487J-214D01*
G02X349734Y-1300I400J9D01*
G01X352623D01*
G02X353023Y-1709I0J-400D01*
G03X356027I1502J-33D01*
G02X356427Y-1300I400J9D01*
G01X359323D01*
G02X359721Y-1733I-1J-400D01*
G03X362540Y-2572I1497J-126D01*
G02X363243I352J-190D01*
G03X366062Y-1733I1322J713D01*
G02X366460Y-1300I399J33D01*
G01X367992D01*
X368792Y-2100D01*
Y-9600D01*
X367892Y-10500D01*
X366441D01*
G02X366046Y-10034I0J400D01*
G03X363243Y-9072I-1481J248D01*
G02X362540I-351J190D01*
G03X359737Y-10034I-1322J-714D01*
G02X359342Y-10500I-395J-66D01*
G01X355852D01*
Y-7814D01*
X355873Y-7772D01*
G03X353179I-1347J664D01*
G01X353200Y-7814D01*
Y-10500D01*
X352634D01*
Y-10276D01*
X352639Y-10253D01*
G03X349685Y-10058I-1460J352D01*
G02X349287Y-10500I-398J-42D01*
G01X346362D01*
G02X345967Y-10034I0J400D01*
G03X343054Y-10240I-1481J248D01*
G01X343063Y-10269D01*
Y-10500D01*
X342466D01*
Y-7814D01*
X342487Y-7772D01*
G03X339793I-1347J664D01*
G01X339814Y-7814D01*
Y-10500D01*
X335774D01*
Y-7814D01*
X335794Y-7772D01*
G03X333100I-1347J664D01*
G01X333120Y-7814D01*
Y-10500D01*
X332523D01*
Y-10269D01*
X332532Y-10240D01*
G03X329619Y-10034I-1432J454D01*
G02X329224Y-10500I-395J-66D01*
G01X326299D01*
G02X325901Y-10058I0J400D01*
G03X322947Y-10253I-1494J157D01*
G01X322952Y-10276D01*
Y-10500D01*
X322388D01*
Y-7814D01*
X322408Y-7772D01*
G03X319714I-1347J664D01*
G01X319734Y-7814D01*
Y-10500D01*
X315694D01*
Y-7814D01*
X315715Y-7772D01*
G03X313021I-1347J664D01*
G01X313042Y-7814D01*
Y-10500D01*
X309892D01*
G37*
G36*
G01X350400Y2300D02*
X349900Y2800D01*
Y7300D01*
X349500Y7700D01*
X349317D01*
G02X348988Y8327I0J400D01*
G03X346678I-1155J795D01*
G02X346349Y7700I-329J-227D01*
G01X345970D01*
G02X345641Y8327I0J400D01*
G03X343331I-1155J795D01*
G02X343002Y7700I-329J-227D01*
G01X339282D01*
G02X338952Y8325I1J400D01*
G03X338814Y10075I-1159J789D01*
G02X339106Y10748I292J273D01*
G01X339894D01*
Y11248D01*
X341394D01*
Y15152D01*
X339894D01*
Y15466D01*
G02X340481Y15819I400J0D01*
G03X342412Y17647I659J1238D01*
G02X342781Y18200I370J153D01*
G01X342845D01*
G02X343214Y17647I-1J-400D01*
G03X345758I1272J-590D01*
G02X346127Y18200I370J153D01*
G01X346500Y18573D01*
Y23500D01*
X347000Y24000D01*
X348600D01*
X349200Y23400D01*
Y18300D01*
X349300Y18200D01*
X349538D01*
G02X349907Y17647I-1J-400D01*
G03X351065Y15659I1272J-590D01*
G02X351248Y15460I-17J-199D01*
G01Y15202D01*
Y15152D01*
X349748D01*
Y14702D01*
Y11698D01*
Y11248D01*
X351248D01*
Y11198D01*
Y10748D01*
X353205D01*
G02X353498Y10076I0J-400D01*
G03X353370Y8327I1027J-954D01*
G02X353041Y7700I-329J-227D01*
G01X352500Y7159D01*
Y2800D01*
X352000Y2300D01*
X350400D01*
G37*
G36*
G01X312510Y7700D02*
G02X312180Y8325I1J400D01*
G03X312200Y8355I-1156J793D01*
G03X312042Y10075I-1179J759D01*
G02X312334Y10748I292J273D01*
G01X314694D01*
Y11198D01*
Y11248D01*
X316194D01*
Y11698D01*
Y14702D01*
Y15152D01*
X314694D01*
Y15202D01*
Y15686D01*
X314828Y15732D01*
G03X315640Y17647I-460J1325D01*
G02X316009Y18200I370J153D01*
G01X319420D01*
G02X319789Y17647I-1J-400D01*
G03X322333I1272J-590D01*
G02X322702Y18200I370J153D01*
G01X322766D01*
G02X323135Y17647I-1J-400D01*
G03X323243Y16275I1272J-590D01*
G02X322911Y15652I-332J-223D01*
G01X322390D01*
Y14502D01*
X321837D01*
X321798Y14520D01*
G03Y11880I-606J-1320D01*
G01X321837Y11898D01*
X322390D01*
Y10748D01*
X323094D01*
G02X323386Y10075I0J-400D01*
G03X323248Y8325I1021J-961D01*
G02X322918Y7700I-331J-225D01*
G01X319203D01*
G02X318873Y8325I1J400D01*
G03X316555I-1159J789D01*
G02X316225Y7700I-331J-225D01*
G01X312510D01*
G37*
G36*
G01X329243D02*
G02X328913Y8325I1J400D01*
G03X327396Y10470I-1159J789D01*
G02X326894Y10856I-102J386D01*
G01Y11248D01*
X328394D01*
Y15152D01*
X326894D01*
Y15652D01*
X325903D01*
G02X325571Y16275I0J400D01*
G03X325679Y17647I-1164J782D01*
G02X326048Y18200I370J153D01*
G01X326500Y18652D01*
Y23500D01*
X327000Y24000D01*
X328400D01*
X329000Y23400D01*
Y18500D01*
X329300Y18200D01*
X329459D01*
G02X329828Y17647I-1J-400D01*
G03X332372I1272J-590D01*
G02X332741Y18200I370J153D01*
G01X332806D01*
G02X333175Y17647I-1J-400D01*
G03X334870Y15720I1272J-590D01*
G02X335390Y15339I120J-381D01*
G01Y14602D01*
X334672D01*
X334648Y14608D01*
G03Y11792I-356J-1408D01*
G01X334672Y11798D01*
X335390D01*
Y10748D01*
X336480D01*
G02X336772Y10075I0J-400D01*
G03X336634Y8325I1021J-961D01*
G02X336304Y7700I-331J-225D01*
G01X335935D01*
G02X335605Y8325I1J400D01*
G03X333287I-1159J789D01*
G02X332957Y7700I-331J-225D01*
G01X329243D01*
G37*
G36*
G01X309732Y14602D02*
Y17140D01*
X310792Y18200D01*
X312727D01*
G02X313096Y17647I-1J-400D01*
G03X313204Y16275I1272J-590D01*
G02X312872Y15652I-332J-223D01*
G01X310190D01*
Y15202D01*
Y14602D01*
X309732D01*
G37*
G36*
G01X335611Y16275D02*
G03X335719Y17647I-1164J782D01*
G02X336088Y18200I370J153D01*
G01X339499D01*
G02X339868Y17647I-1J-400D01*
G03X339976Y16275I1272J-590D01*
G02X339644Y15652I-332J-223D01*
G01X335943D01*
G02X335611Y16275I0J400D01*
G37*
G36*
G01X358470Y49024D02*
X353517D01*
X352353Y50188D01*
Y51935D01*
X352621Y52203D01*
X356069D01*
X356607Y52741D01*
X358219D01*
X358470Y52490D01*
Y49024D01*
G37*
G36*
G01X301654Y45169D02*
X300383Y46440D01*
Y50386D01*
X302521Y52524D01*
Y55996D01*
X303161Y56636D01*
X306515D01*
G02X306773Y55930I0J-400D01*
G03X308153Y53539I902J-1073D01*
G02X308689Y53163I136J-376D01*
G01Y45908D01*
X307950Y45169D01*
X301654D01*
G37*
G36*
G01X360432Y67714D02*
X360107Y67389D01*
X309903D01*
X309792Y67500D01*
Y68165D01*
X308584Y69373D01*
X306519D01*
X306392Y69500D01*
Y74112D01*
X306720Y74440D01*
X308952D01*
X311392Y72000D01*
X358211D01*
X358253Y71958D01*
X359524D01*
X360028Y72462D01*
Y74130D01*
X360398Y74500D01*
X365892D01*
X366212Y74180D01*
X366194Y74162D01*
Y72079D01*
X365998Y71883D01*
X362775D01*
X360432Y69540D01*
Y67714D01*
G37*
G36*
G01X312392Y45200D02*
X312119Y45473D01*
G02X312095Y46013I283J283D01*
G03X312042Y47875I-1074J901D01*
G02X312334Y48548I292J273D01*
G01X314694D01*
Y49048D01*
X316194D01*
Y52952D01*
X314694D01*
Y53486D01*
X314828Y53533D01*
G03X315257Y55941I-460J1324D01*
G02X315511Y56650I254J309D01*
G01X319918D01*
G02X320172Y55941I0J-400D01*
G03X321950I889J-1084D01*
G02X322204Y56650I254J309D01*
G01X323264D01*
G02X323518Y55941I0J-400D01*
G03X323244Y54075I889J-1084D01*
G02X322912Y53452I-332J-223D01*
G01X322390D01*
Y52302D01*
X321837D01*
X321798Y52320D01*
G03Y49680I-606J-1320D01*
G01X321837Y49698D01*
X322390D01*
Y48548D01*
X323094D01*
G02X323386Y47875I0J-400D01*
G03X323448Y45892I1021J-961D01*
G02X323174Y45200I-274J-292D01*
G01X318947D01*
G02X318673Y45892I0J400D01*
G03X316755I-959J1022D01*
G02X316481Y45200I-274J-292D01*
G01X312392D01*
G37*
G36*
G01X328713Y45892D02*
G03X327396Y48269I-960J1022D01*
G02X326894Y48656I-102J387D01*
G01Y49048D01*
X328394D01*
Y52952D01*
X326894D01*
Y53452D01*
X325902D01*
G02X325570Y54075I0J400D01*
G03X325296Y55941I-1163J782D01*
G02X325550Y56650I254J309D01*
G01X329957D01*
G02X330211Y55941I0J-400D01*
G03X331989I889J-1084D01*
G02X332243Y56650I254J309D01*
G01X333304D01*
G02X333558Y55941I0J-400D01*
G03X334870Y53520I889J-1084D01*
G02X335390Y53139I120J-381D01*
G01Y52302D01*
X334937D01*
X334898Y52320D01*
G03Y49680I-606J-1320D01*
G01X334937Y49698D01*
X335390D01*
Y48548D01*
X336480D01*
G02X336772Y47875I0J-400D01*
G03X336834Y45892I1021J-961D01*
G02X336560Y45200I-274J-292D01*
G01X335679D01*
G02X335405Y45892I0J400D01*
G03X333487I-959J1022D01*
G02X333213Y45200I-274J-292D01*
G01X328987D01*
G02X328713Y45892I0J400D01*
G37*
G36*
G01X338752D02*
G03X338814Y47875I-959J1022D01*
G02X339106Y48548I292J273D01*
G01X339894D01*
Y49048D01*
X341394D01*
Y52952D01*
X339894D01*
Y53266D01*
G02X340481Y53619I400J0D01*
G03X342029Y55941I659J1237D01*
G02X342283Y56650I254J309D01*
G01X343343D01*
G02X343597Y55941I0J-400D01*
G03X345375I889J-1084D01*
G02X345629Y56650I254J309D01*
G01X350036D01*
G02X350290Y55941I0J-400D01*
G03X351065Y53460I889J-1084D01*
G02X351248Y53260I-17J-199D01*
G01Y52952D01*
X349748D01*
Y49048D01*
X351248D01*
Y48548D01*
X352576D01*
X353102Y48022D01*
X353200D01*
G02X353365Y47710I0J-200D01*
G03X353572Y45893I1160J-788D01*
G02X353301Y45200I-272J-293D01*
G01X349057D01*
G02X348786Y45893I1J400D01*
G03X346880I-953J1029D01*
G02X346609Y45200I-272J-293D01*
G01X345710D01*
G02X345439Y45893I1J400D01*
G03X343533I-953J1029D01*
G02X343262Y45200I-272J-293D01*
G01X339026D01*
G02X338752Y45892I0J400D01*
G37*
G36*
G01X309690Y52302D02*
Y56448D01*
X309892Y56650D01*
X313225D01*
G02X313479Y55941I0J-400D01*
G03X313205Y54075I889J-1084D01*
G02X312873Y53452I-332J-223D01*
G01X310190D01*
Y52302D01*
X309690D01*
G37*
G36*
G01X335610Y54075D02*
G03X335336Y55941I-1163J782D01*
G02X335590Y56650I254J309D01*
G01X339997D01*
G02X340251Y55941I0J-400D01*
G03X339977Y54075I889J-1084D01*
G02X339645Y53452I-332J-223D01*
G01X335942D01*
G02X335610Y54075I0J400D01*
G37*
G36*
G01X304049Y194511D02*
X304233Y194129D01*
X303936Y193832D01*
X303554Y194016D01*
X303413Y194158D01*
X303908Y194653D01*
X304049Y194511D01*
G37*
G36*
G01X301332Y192335D02*
X301192Y191935D01*
X300772D01*
X300632Y192335D01*
Y192535D01*
X301332D01*
Y192335D01*
G37*
G36*
G01X292982Y192735D02*
X293122Y193135D01*
X293542D01*
X293682Y192735D01*
Y192535D01*
X292982D01*
Y192735D01*
G37*
G36*
G01X294532Y192335D02*
X294392Y191935D01*
X293972D01*
X293832Y192335D01*
Y192535D01*
X294532D01*
Y192335D01*
G37*
G36*
G01X297932D02*
X297792Y191935D01*
X297372D01*
X297232Y192335D01*
Y192535D01*
X297932D01*
Y192335D01*
G37*
G36*
G01X299632D02*
X299492Y191935D01*
X299072D01*
X298932Y192335D01*
Y192535D01*
X299632D01*
Y192335D01*
G37*
G36*
G01X299782Y192735D02*
X299922Y193135D01*
X300342D01*
X300482Y192735D01*
Y192535D01*
X299782D01*
Y192735D01*
G37*
G36*
G01X298082D02*
X298222Y193135D01*
X298642D01*
X298782Y192735D01*
Y192535D01*
X298082D01*
Y192735D01*
G37*
G36*
G01X296382D02*
X296522Y193135D01*
X296942D01*
X297082Y192735D01*
Y192535D01*
X296382D01*
Y192735D01*
G37*
G36*
G01X294682D02*
X294822Y193135D01*
X295242D01*
X295382Y192735D01*
Y192535D01*
X294682D01*
Y192735D01*
G37*
G36*
G01X296232Y192335D02*
X296092Y191935D01*
X295672D01*
X295532Y192335D01*
Y192535D01*
X296232D01*
Y192335D01*
G37*
G36*
G01X302847Y193309D02*
X303031Y192927D01*
X302734Y192630D01*
X302352Y192814D01*
X302210Y192955D01*
X302705Y193450D01*
X302847Y193309D01*
G37*
G36*
G01X306100Y194864D02*
X306284Y194482D01*
X305987Y194185D01*
X305605Y194369D01*
X305464Y194511D01*
X305959Y195006D01*
X306100Y194864D01*
G37*
G36*
G01X304721Y194051D02*
X304537Y194433D01*
X304834Y194730D01*
X305216Y194546D01*
X305358Y194405D01*
X304863Y193910D01*
X304721Y194051D01*
G37*
G36*
G01X305923Y195253D02*
X305739Y195635D01*
X306036Y195932D01*
X306418Y195748D01*
X306560Y195607D01*
X306065Y195112D01*
X305923Y195253D01*
G37*
G36*
G01X303696Y192460D02*
X303880Y192078D01*
X303583Y191781D01*
X303201Y191965D01*
X303059Y192106D01*
X303554Y192601D01*
X303696Y192460D01*
G37*
G36*
G01X304898Y193662D02*
X305082Y193280D01*
X304785Y192983D01*
X304403Y193167D01*
X304262Y193309D01*
X304757Y193804D01*
X304898Y193662D01*
G37*
G36*
G01X303519Y192849D02*
X303335Y193231D01*
X303632Y193528D01*
X304014Y193344D01*
X304155Y193202D01*
X303661Y192708D01*
X303519Y192849D01*
G37*
G36*
G01X302317Y191647D02*
X302133Y192029D01*
X302430Y192326D01*
X302812Y192142D01*
X302953Y192000D01*
X302459Y191506D01*
X302317Y191647D01*
G37*
G36*
G01X301332Y191135D02*
X301192Y190735D01*
X300772D01*
X300632Y191135D01*
Y191335D01*
X301332D01*
Y191135D01*
G37*
G36*
G01X294532D02*
X294392Y190735D01*
X293972D01*
X293832Y191135D01*
Y191335D01*
X294532D01*
Y191135D01*
G37*
G36*
G01X292982Y191535D02*
X293122Y191935D01*
X293542D01*
X293682Y191535D01*
Y191335D01*
X292982D01*
Y191535D01*
G37*
G36*
G01X298082D02*
X298222Y191935D01*
X298642D01*
X298782Y191535D01*
Y191335D01*
X298082D01*
Y191535D01*
G37*
G36*
G01X299782D02*
X299922Y191935D01*
X300342D01*
X300482Y191535D01*
Y191335D01*
X299782D01*
Y191535D01*
G37*
G36*
G01X297932Y191135D02*
X297792Y190735D01*
X297372D01*
X297232Y191135D01*
Y191335D01*
X297932D01*
Y191135D01*
G37*
G36*
G01X299632D02*
X299492Y190735D01*
X299072D01*
X298932Y191135D01*
Y191335D01*
X299632D01*
Y191135D01*
G37*
G36*
G01X296382Y191535D02*
X296522Y191935D01*
X296942D01*
X297082Y191535D01*
Y191335D01*
X296382D01*
Y191535D01*
G37*
G36*
G01X294682D02*
X294822Y191935D01*
X295242D01*
X295382Y191535D01*
Y191335D01*
X294682D01*
Y191535D01*
G37*
G36*
G01X296232Y191135D02*
X296092Y190735D01*
X295672D01*
X295532Y191135D01*
Y191335D01*
X296232D01*
Y191135D01*
G37*
G36*
G01X310664Y188108D02*
X310480Y188490D01*
X310777Y188787D01*
X311159Y188603D01*
X311301Y188462D01*
X310806Y187967D01*
X310664Y188108D01*
G37*
G36*
G01X312043Y188921D02*
X312227Y188539D01*
X311930Y188242D01*
X311548Y188426D01*
X311407Y188568D01*
X311902Y189063D01*
X312043Y188921D01*
G37*
G36*
G01X313245Y190123D02*
X313429Y189741D01*
X313132Y189444D01*
X312750Y189628D01*
X312609Y189770D01*
X313104Y190265D01*
X313245Y190123D01*
G37*
G36*
G01X314447Y191325D02*
X314631Y190944D01*
X314334Y190647D01*
X313952Y190830D01*
X313811Y190972D01*
X314306Y191467D01*
X314447Y191325D01*
G37*
G36*
G01X311866Y189310D02*
X311682Y189692D01*
X311979Y189989D01*
X312361Y189805D01*
X312503Y189664D01*
X312008Y189169D01*
X311866Y189310D01*
G37*
G36*
G01X313068Y190512D02*
X312884Y190894D01*
X313181Y191191D01*
X313563Y191007D01*
X313705Y190866D01*
X313210Y190371D01*
X313068Y190512D01*
G37*
G36*
G01X292982Y183135D02*
X293122Y183535D01*
X293542D01*
X293682Y183135D01*
Y182935D01*
X292982D01*
Y183135D01*
G37*
G36*
G01X294532Y182735D02*
X294392Y182335D01*
X293972D01*
X293832Y182735D01*
Y182935D01*
X294532D01*
Y182735D01*
G37*
G36*
G01X305856Y183300D02*
X305672Y183682D01*
X305969Y183979D01*
X306351Y183795D01*
X306492Y183653D01*
X305997Y183158D01*
X305856Y183300D01*
G37*
G36*
G01X308437Y185315D02*
X308621Y184933D01*
X308324Y184636D01*
X307942Y184820D01*
X307800Y184961D01*
X308295Y185456D01*
X308437Y185315D01*
G37*
G36*
G01X308260Y185704D02*
X308076Y186086D01*
X308373Y186383D01*
X308755Y186199D01*
X308896Y186057D01*
X308401Y185562D01*
X308260Y185704D01*
G37*
G36*
G01X307058Y184502D02*
X306874Y184884D01*
X307171Y185181D01*
X307553Y184997D01*
X307694Y184855D01*
X307199Y184360D01*
X307058Y184502D01*
G37*
G36*
G01X298082Y183135D02*
X298222Y183535D01*
X298642D01*
X298782Y183135D01*
Y182935D01*
X298082D01*
Y183135D01*
G37*
G36*
G01X299782D02*
X299922Y183535D01*
X300342D01*
X300482Y183135D01*
Y182935D01*
X299782D01*
Y183135D01*
G37*
G36*
G01X301482D02*
X301622Y183535D01*
X302042D01*
X302182Y183135D01*
Y182935D01*
X301482D01*
Y183135D01*
G37*
G36*
G01X303182D02*
X303322Y183535D01*
X303742D01*
X303882Y183135D01*
Y182935D01*
X303182D01*
Y183135D01*
G37*
G36*
G01X297932Y182735D02*
X297792Y182335D01*
X297372D01*
X297232Y182735D01*
Y182935D01*
X297932D01*
Y182735D01*
G37*
G36*
G01X299632D02*
X299492Y182335D01*
X299072D01*
X298932Y182735D01*
Y182935D01*
X299632D01*
Y182735D01*
G37*
G36*
G01X301332D02*
X301192Y182335D01*
X300772D01*
X300632Y182735D01*
Y182935D01*
X301332D01*
Y182735D01*
G37*
G36*
G01X303032D02*
X302892Y182335D01*
X302472D01*
X302332Y182735D01*
Y182935D01*
X303032D01*
Y182735D01*
G37*
G36*
G01X304732D02*
X304592Y182335D01*
X304172D01*
X304032Y182735D01*
Y182935D01*
X304732D01*
Y182735D01*
G37*
G36*
G01X296382Y183135D02*
X296522Y183535D01*
X296942D01*
X297082Y183135D01*
Y182935D01*
X296382D01*
Y183135D01*
G37*
G36*
G01X294682D02*
X294822Y183535D01*
X295242D01*
X295382Y183135D01*
Y182935D01*
X294682D01*
Y183135D01*
G37*
G36*
G01X296232Y182735D02*
X296092Y182335D01*
X295672D01*
X295532Y182735D01*
Y182935D01*
X296232D01*
Y182735D01*
G37*
G36*
G01X307235Y184113D02*
X307419Y183731D01*
X307122Y183434D01*
X306740Y183618D01*
X306598Y183759D01*
X307093Y184254D01*
X307235Y184113D01*
G37*
G36*
G01X309639Y186517D02*
X309823Y186135D01*
X309526Y185838D01*
X309144Y186022D01*
X309002Y186163D01*
X309497Y186658D01*
X309639Y186517D01*
G37*
G36*
G01X310841Y187719D02*
X311025Y187337D01*
X310728Y187040D01*
X310346Y187224D01*
X310205Y187366D01*
X310700Y187861D01*
X310841Y187719D01*
G37*
G36*
G01X309462Y186906D02*
X309278Y187288D01*
X309575Y187585D01*
X309957Y187401D01*
X310098Y187259D01*
X309604Y186765D01*
X309462Y186906D01*
G37*
G36*
G01X312715Y188461D02*
X312531Y188843D01*
X312828Y189140D01*
X313210Y188956D01*
X313387Y188780D01*
X312892Y188285D01*
X312715Y188461D01*
G37*
G36*
G01X313917Y189664D02*
X313733Y190045D01*
X314030Y190342D01*
X314412Y190159D01*
X314589Y189982D01*
X314094Y189487D01*
X313917Y189664D01*
G37*
G36*
G01X292982Y181935D02*
X293122Y182335D01*
X293542D01*
X293682Y181935D01*
Y181685D01*
X292982D01*
Y181935D01*
G37*
G36*
G01X307907Y183653D02*
X307723Y184035D01*
X308020Y184332D01*
X308402Y184148D01*
X308578Y183971D01*
X308083Y183476D01*
X307907Y183653D01*
G37*
G36*
G01X306704Y182451D02*
X306521Y182833D01*
X306818Y183130D01*
X307199Y182946D01*
X307376Y182769D01*
X306881Y182274D01*
X306704Y182451D01*
G37*
G36*
G01X298082Y181935D02*
X298222Y182335D01*
X298642D01*
X298782Y181935D01*
Y181685D01*
X298082D01*
Y181935D01*
G37*
G36*
G01X299782D02*
X299922Y182335D01*
X300342D01*
X300482Y181935D01*
Y181685D01*
X299782D01*
Y181935D01*
G37*
G36*
G01X301482D02*
X301622Y182335D01*
X302042D01*
X302182Y181935D01*
Y181685D01*
X301482D01*
Y181935D01*
G37*
G36*
G01X303182D02*
X303322Y182335D01*
X303742D01*
X303882Y181935D01*
Y181685D01*
X303182D01*
Y181935D01*
G37*
G36*
G01X304882D02*
X305022Y182335D01*
X305442D01*
X305582Y181935D01*
Y181685D01*
X304882D01*
Y181935D01*
G37*
G36*
G01X296382D02*
X296522Y182335D01*
X296942D01*
X297082Y181935D01*
Y181685D01*
X296382D01*
Y181935D01*
G37*
G36*
G01X294682D02*
X294822Y182335D01*
X295242D01*
X295382Y181935D01*
Y181685D01*
X294682D01*
Y181935D01*
G37*
G36*
G01X309109Y184855D02*
X308925Y185237D01*
X309222Y185534D01*
X309604Y185350D01*
X309780Y185173D01*
X309285Y184678D01*
X309109Y184855D01*
G37*
G36*
G01X310311Y186057D02*
X310127Y186439D01*
X310424Y186736D01*
X310806Y186552D01*
X310982Y186375D01*
X310488Y185881D01*
X310311Y186057D01*
G37*
G36*
G01X311513Y187259D02*
X311329Y187641D01*
X311626Y187938D01*
X312008Y187754D01*
X312185Y187578D01*
X311690Y187083D01*
X311513Y187259D01*
G37*
G36*
G01X301347Y200663D02*
X300710Y201070D01*
X300786Y201937D01*
X301484Y202227D01*
X301658Y202212D01*
X301522Y200648D01*
X301347Y200663D01*
G37*
G36*
G01X294532Y194735D02*
X294392Y194335D01*
X293972D01*
X293832Y194735D01*
Y194985D01*
X294532D01*
Y194735D01*
G37*
G36*
G01X298727Y195784D02*
X298911Y195402D01*
X298614Y195105D01*
X298232Y195289D01*
X298091Y195431D01*
X298586Y195926D01*
X298727Y195784D01*
G37*
G36*
G01X296232Y194735D02*
X296092Y194335D01*
X295672D01*
X295532Y194735D01*
Y194985D01*
X296232D01*
Y194735D01*
G37*
G36*
G01X303031Y200120D02*
X303701Y199770D01*
Y198900D01*
X303031Y198550D01*
X302856D01*
Y200120D01*
X303031D01*
G37*
G36*
G01X305870Y203454D02*
X305902Y202699D01*
X305149Y202264D01*
X304511Y202669D01*
X304423Y202821D01*
X305783Y203606D01*
X305870Y203454D01*
G37*
G36*
G01X292982Y193935D02*
X293122Y194335D01*
X293542D01*
X293682Y193935D01*
Y193735D01*
X292982D01*
Y193935D01*
G37*
G36*
G01X294532Y193535D02*
X294392Y193135D01*
X293972D01*
X293832Y193535D01*
Y193735D01*
X294532D01*
Y193535D01*
G37*
G36*
G01X299399Y195324D02*
X299215Y195706D01*
X299512Y196003D01*
X299894Y195819D01*
X300035Y195678D01*
X299540Y195183D01*
X299399Y195324D01*
G37*
G36*
G01X297932Y193535D02*
X297792Y193135D01*
X297372D01*
X297232Y193535D01*
Y193735D01*
X297932D01*
Y193535D01*
G37*
G36*
G01X298197Y194122D02*
X298013Y194504D01*
X298310Y194801D01*
X298692Y194617D01*
X298833Y194476D01*
X298338Y193981D01*
X298197Y194122D01*
G37*
G36*
G01X299576Y194936D02*
X299760Y194554D01*
X299463Y194257D01*
X299081Y194441D01*
X298940Y194582D01*
X299435Y195077D01*
X299576Y194936D01*
G37*
G36*
G01X296382Y193935D02*
X296522Y194335D01*
X296942D01*
X297082Y193935D01*
Y193735D01*
X296382D01*
Y193935D01*
G37*
G36*
G01X294682D02*
X294822Y194335D01*
X295242D01*
X295382Y193935D01*
Y193735D01*
X294682D01*
Y193935D01*
G37*
G36*
G01X296232Y193535D02*
X296092Y193135D01*
X295672D01*
X295532Y193535D01*
Y193735D01*
X296232D01*
Y193535D01*
G37*
G36*
G01X309143Y189417D02*
X309327Y189035D01*
X309030Y188738D01*
X308648Y188922D01*
X308507Y189064D01*
X309002Y189559D01*
X309143Y189417D01*
G37*
G36*
G01X308966Y189806D02*
X308782Y190188D01*
X309079Y190485D01*
X309461Y190301D01*
X309603Y190160D01*
X309108Y189665D01*
X308966Y189806D01*
G37*
G36*
G01X307764Y188604D02*
X307580Y188986D01*
X307877Y189283D01*
X308259Y189099D01*
X308400Y188957D01*
X307906Y188463D01*
X307764Y188604D01*
G37*
G36*
G01X311370Y192210D02*
X311186Y192592D01*
X311483Y192889D01*
X311865Y192705D01*
X312007Y192564D01*
X311512Y192069D01*
X311370Y192210D01*
G37*
G36*
G01X310345Y190619D02*
X310529Y190237D01*
X310232Y189940D01*
X309850Y190124D01*
X309709Y190266D01*
X310204Y190761D01*
X310345Y190619D01*
G37*
G36*
G01X311547Y191821D02*
X311731Y191439D01*
X311434Y191142D01*
X311052Y191326D01*
X310911Y191468D01*
X311406Y191963D01*
X311547Y191821D01*
G37*
G36*
G01X310168Y191008D02*
X309984Y191390D01*
X310281Y191687D01*
X310663Y191503D01*
X310805Y191362D01*
X310310Y190867D01*
X310168Y191008D01*
G37*
G36*
G01X312749Y193023D02*
X312933Y192642D01*
X312636Y192345D01*
X312254Y192528D01*
X312113Y192670D01*
X312608Y193165D01*
X312749Y193023D01*
G37*
G36*
G01X313951Y194225D02*
X314135Y193844D01*
X313838Y193547D01*
X313456Y193730D01*
X313315Y193872D01*
X313810Y194367D01*
X313951Y194225D01*
G37*
G36*
G01X312572Y193412D02*
X312388Y193794D01*
X312685Y194091D01*
X313067Y193907D01*
X313209Y193766D01*
X312714Y193271D01*
X312572Y193412D01*
G37*
G36*
G01X292982Y185535D02*
X293122Y185935D01*
X293542D01*
X293682Y185535D01*
Y185335D01*
X292982D01*
Y185535D01*
G37*
G36*
G01X294532Y185135D02*
X294392Y184735D01*
X293972D01*
X293832Y185135D01*
Y185335D01*
X294532D01*
Y185135D01*
G37*
G36*
G01X307941Y188215D02*
X308125Y187833D01*
X307828Y187536D01*
X307446Y187720D01*
X307304Y187861D01*
X307799Y188356D01*
X307941Y188215D01*
G37*
G36*
G01X306739Y187013D02*
X306923Y186631D01*
X306626Y186334D01*
X306244Y186518D01*
X306102Y186659D01*
X306597Y187154D01*
X306739Y187013D01*
G37*
G36*
G01X305360Y186200D02*
X305176Y186582D01*
X305473Y186879D01*
X305855Y186695D01*
X305996Y186553D01*
X305501Y186058D01*
X305360Y186200D01*
G37*
G36*
G01X305537Y185811D02*
X305721Y185429D01*
X305424Y185132D01*
X305042Y185316D01*
X304900Y185457D01*
X305395Y185952D01*
X305537Y185811D01*
G37*
G36*
G01X304732Y185135D02*
X304592Y184735D01*
X304172D01*
X304032Y185135D01*
Y185335D01*
X304732D01*
Y185135D01*
G37*
G36*
G01X298082Y185535D02*
X298222Y185935D01*
X298642D01*
X298782Y185535D01*
Y185335D01*
X298082D01*
Y185535D01*
G37*
G36*
G01X299782D02*
X299922Y185935D01*
X300342D01*
X300482Y185535D01*
Y185335D01*
X299782D01*
Y185535D01*
G37*
G36*
G01X301482D02*
X301622Y185935D01*
X302042D01*
X302182Y185535D01*
Y185335D01*
X301482D01*
Y185535D01*
G37*
G36*
G01X303182D02*
X303322Y185935D01*
X303742D01*
X303882Y185535D01*
Y185335D01*
X303182D01*
Y185535D01*
G37*
G36*
G01X297932Y185135D02*
X297792Y184735D01*
X297372D01*
X297232Y185135D01*
Y185335D01*
X297932D01*
Y185135D01*
G37*
G36*
G01X299632D02*
X299492Y184735D01*
X299072D01*
X298932Y185135D01*
Y185335D01*
X299632D01*
Y185135D01*
G37*
G36*
G01X301332D02*
X301192Y184735D01*
X300772D01*
X300632Y185135D01*
Y185335D01*
X301332D01*
Y185135D01*
G37*
G36*
G01X303032D02*
X302892Y184735D01*
X302472D01*
X302332Y185135D01*
Y185335D01*
X303032D01*
Y185135D01*
G37*
G36*
G01X296382Y185535D02*
X296522Y185935D01*
X296942D01*
X297082Y185535D01*
Y185335D01*
X296382D01*
Y185535D01*
G37*
G36*
G01X294682D02*
X294822Y185935D01*
X295242D01*
X295382Y185535D01*
Y185335D01*
X294682D01*
Y185535D01*
G37*
G36*
G01X296232Y185135D02*
X296092Y184735D01*
X295672D01*
X295532Y185135D01*
Y185335D01*
X296232D01*
Y185135D01*
G37*
G36*
G01X306562Y187402D02*
X306378Y187784D01*
X306675Y188081D01*
X307057Y187897D01*
X307198Y187755D01*
X306703Y187260D01*
X306562Y187402D01*
G37*
G36*
G01X309992Y188568D02*
X310176Y188186D01*
X309879Y187889D01*
X309497Y188073D01*
X309356Y188215D01*
X309851Y188710D01*
X309992Y188568D01*
G37*
G36*
G01X311194Y189770D02*
X311378Y189388D01*
X311081Y189091D01*
X310699Y189275D01*
X310558Y189417D01*
X311053Y189912D01*
X311194Y189770D01*
G37*
G36*
G01X309815Y188957D02*
X309631Y189339D01*
X309928Y189636D01*
X310310Y189452D01*
X310452Y189311D01*
X309957Y188816D01*
X309815Y188957D01*
G37*
G36*
G01X311017Y190159D02*
X310833Y190541D01*
X311130Y190838D01*
X311512Y190654D01*
X311654Y190513D01*
X311159Y190018D01*
X311017Y190159D01*
G37*
G36*
G01X312396Y190972D02*
X312580Y190590D01*
X312283Y190293D01*
X311901Y190477D01*
X311760Y190619D01*
X312255Y191114D01*
X312396Y190972D01*
G37*
G36*
G01X313598Y192174D02*
X313782Y191793D01*
X313485Y191496D01*
X313103Y191679D01*
X312962Y191821D01*
X313457Y192316D01*
X313598Y192174D01*
G37*
G36*
G01X314800Y193376D02*
X314984Y192995D01*
X314687Y192698D01*
X314305Y192881D01*
X314164Y193023D01*
X314659Y193518D01*
X314800Y193376D01*
G37*
G36*
G01X312219Y191361D02*
X312035Y191743D01*
X312332Y192040D01*
X312714Y191856D01*
X312856Y191715D01*
X312361Y191220D01*
X312219Y191361D01*
G37*
G36*
G01X313421Y192563D02*
X313238Y192945D01*
X313535Y193242D01*
X313916Y193058D01*
X314058Y192917D01*
X313563Y192422D01*
X313421Y192563D01*
G37*
G36*
G01X314623Y193765D02*
X314440Y194147D01*
X314737Y194444D01*
X315118Y194260D01*
X315260Y194119D01*
X314765Y193624D01*
X314623Y193765D01*
G37*
G36*
G01X294532Y183935D02*
X294392Y183535D01*
X293972D01*
X293832Y183935D01*
Y184135D01*
X294532D01*
Y183935D01*
G37*
G36*
G01X292982Y184335D02*
X293122Y184735D01*
X293542D01*
X293682Y184335D01*
Y184135D01*
X292982D01*
Y184335D01*
G37*
G36*
G01X308790Y187366D02*
X308974Y186984D01*
X308677Y186687D01*
X308295Y186871D01*
X308153Y187012D01*
X308648Y187507D01*
X308790Y187366D01*
G37*
G36*
G01X307588Y186164D02*
X307772Y185782D01*
X307475Y185485D01*
X307093Y185669D01*
X306951Y185810D01*
X307446Y186305D01*
X307588Y186164D01*
G37*
G36*
G01X306386Y184962D02*
X306570Y184580D01*
X306273Y184283D01*
X305891Y184467D01*
X305749Y184608D01*
X306244Y185103D01*
X306386Y184962D01*
G37*
G36*
G01X308613Y187755D02*
X308429Y188137D01*
X308726Y188434D01*
X309108Y188250D01*
X309249Y188108D01*
X308755Y187614D01*
X308613Y187755D01*
G37*
G36*
G01X307411Y186553D02*
X307227Y186935D01*
X307524Y187232D01*
X307906Y187048D01*
X308047Y186906D01*
X307552Y186411D01*
X307411Y186553D01*
G37*
G36*
G01X306209Y185351D02*
X306025Y185733D01*
X306322Y186030D01*
X306704Y185846D01*
X306845Y185704D01*
X306350Y185209D01*
X306209Y185351D01*
G37*
G36*
G01X297932Y183935D02*
X297792Y183535D01*
X297372D01*
X297232Y183935D01*
Y184135D01*
X297932D01*
Y183935D01*
G37*
G36*
G01X299632D02*
X299492Y183535D01*
X299072D01*
X298932Y183935D01*
Y184135D01*
X299632D01*
Y183935D01*
G37*
G36*
G01X301332D02*
X301192Y183535D01*
X300772D01*
X300632Y183935D01*
Y184135D01*
X301332D01*
Y183935D01*
G37*
G36*
G01X303032D02*
X302892Y183535D01*
X302472D01*
X302332Y183935D01*
Y184135D01*
X303032D01*
Y183935D01*
G37*
G36*
G01X304732D02*
X304592Y183535D01*
X304172D01*
X304032Y183935D01*
Y184135D01*
X304732D01*
Y183935D01*
G37*
G36*
G01X298082Y184335D02*
X298222Y184735D01*
X298642D01*
X298782Y184335D01*
Y184135D01*
X298082D01*
Y184335D01*
G37*
G36*
G01X299782D02*
X299922Y184735D01*
X300342D01*
X300482Y184335D01*
Y184135D01*
X299782D01*
Y184335D01*
G37*
G36*
G01X301482D02*
X301622Y184735D01*
X302042D01*
X302182Y184335D01*
Y184135D01*
X301482D01*
Y184335D01*
G37*
G36*
G01X303182D02*
X303322Y184735D01*
X303742D01*
X303882Y184335D01*
Y184135D01*
X303182D01*
Y184335D01*
G37*
G36*
G01X296382D02*
X296522Y184735D01*
X296942D01*
X297082Y184335D01*
Y184135D01*
X296382D01*
Y184335D01*
G37*
G36*
G01X296232Y183935D02*
X296092Y183535D01*
X295672D01*
X295532Y183935D01*
Y184135D01*
X296232D01*
Y183935D01*
G37*
G36*
G01X294682Y184335D02*
X294822Y184735D01*
X295242D01*
X295382Y184335D01*
Y184135D01*
X294682D01*
Y184335D01*
G37*
G36*
G01X306596Y191964D02*
X306780Y191582D01*
X306483Y191285D01*
X306101Y191469D01*
X305960Y191611D01*
X306455Y192106D01*
X306596Y191964D01*
G37*
G36*
G01X307798Y193166D02*
X307982Y192784D01*
X307685Y192487D01*
X307303Y192671D01*
X307162Y192813D01*
X307657Y193308D01*
X307798Y193166D01*
G37*
G36*
G01X306419Y192353D02*
X306235Y192735D01*
X306532Y193032D01*
X306914Y192848D01*
X307056Y192707D01*
X306561Y192212D01*
X306419Y192353D01*
G37*
G36*
G01X301482Y189135D02*
X301622Y189535D01*
X302042D01*
X302182Y189135D01*
Y188935D01*
X301482D01*
Y189135D01*
G37*
G36*
G01X301332Y188735D02*
X301192Y188335D01*
X300772D01*
X300632Y188735D01*
Y188935D01*
X301332D01*
Y188735D01*
G37*
G36*
G01X305394Y190762D02*
X305578Y190380D01*
X305281Y190083D01*
X304899Y190267D01*
X304757Y190408D01*
X305252Y190903D01*
X305394Y190762D01*
G37*
G36*
G01X304015Y189949D02*
X303831Y190331D01*
X304128Y190628D01*
X304510Y190444D01*
X304651Y190302D01*
X304156Y189807D01*
X304015Y189949D01*
G37*
G36*
G01X305217Y191151D02*
X305033Y191533D01*
X305330Y191830D01*
X305712Y191646D01*
X305853Y191504D01*
X305359Y191010D01*
X305217Y191151D01*
G37*
G36*
G01X304192Y189560D02*
X304376Y189178D01*
X304079Y188881D01*
X303697Y189065D01*
X303555Y189206D01*
X304050Y189701D01*
X304192Y189560D01*
G37*
G36*
G01X303032Y188735D02*
X302892Y188335D01*
X302472D01*
X302332Y188735D01*
Y188935D01*
X303032D01*
Y188735D01*
G37*
G36*
G01X294532D02*
X294392Y188335D01*
X293972D01*
X293832Y188735D01*
Y188935D01*
X294532D01*
Y188735D01*
G37*
G36*
G01X292982Y189135D02*
X293122Y189535D01*
X293542D01*
X293682Y189135D01*
Y188935D01*
X292982D01*
Y189135D01*
G37*
G36*
G01X296232Y188735D02*
X296092Y188335D01*
X295672D01*
X295532Y188735D01*
Y188935D01*
X296232D01*
Y188735D01*
G37*
G36*
G01X298082Y189135D02*
X298222Y189535D01*
X298642D01*
X298782Y189135D01*
Y188935D01*
X298082D01*
Y189135D01*
G37*
G36*
G01X299782D02*
X299922Y189535D01*
X300342D01*
X300482Y189135D01*
Y188935D01*
X299782D01*
Y189135D01*
G37*
G36*
G01X297932Y188735D02*
X297792Y188335D01*
X297372D01*
X297232Y188735D01*
Y188935D01*
X297932D01*
Y188735D01*
G37*
G36*
G01X299632D02*
X299492Y188335D01*
X299072D01*
X298932Y188735D01*
Y188935D01*
X299632D01*
Y188735D01*
G37*
G36*
G01X296382Y189135D02*
X296522Y189535D01*
X296942D01*
X297082Y189135D01*
Y188935D01*
X296382D01*
Y189135D01*
G37*
G36*
G01X294682D02*
X294822Y189535D01*
X295242D01*
X295382Y189135D01*
Y188935D01*
X294682D01*
Y189135D01*
G37*
G36*
G01X327929Y192048D02*
X328329Y191908D01*
Y191487D01*
X327929Y191348D01*
X327729D01*
Y192048D01*
X327929D01*
G37*
G36*
G01Y193748D02*
X328329Y193608D01*
Y193187D01*
X327929Y193048D01*
X327729D01*
Y193748D01*
X327929D01*
G37*
G36*
G01X327529Y192198D02*
X327129Y192337D01*
Y192758D01*
X327529Y192898D01*
X327729D01*
Y192198D01*
X327529D01*
G37*
G36*
G01Y193898D02*
X327129Y194037D01*
Y194458D01*
X327529Y194598D01*
X327729D01*
Y193898D01*
X327529D01*
G37*
G36*
G01Y190498D02*
X327129Y190637D01*
Y191058D01*
X327529Y191198D01*
X327729D01*
Y190498D01*
X327529D01*
G37*
G36*
G01X327929Y190348D02*
X328329Y190208D01*
Y189787D01*
X327929Y189648D01*
X327729D01*
Y190348D01*
X327929D01*
G37*
G36*
G01X327295Y188745D02*
X327479Y188363D01*
X327182Y188066D01*
X326800Y188250D01*
X326658Y188391D01*
X327153Y188886D01*
X327295Y188745D01*
G37*
G36*
G01X327929Y195448D02*
X328329Y195308D01*
Y194887D01*
X327929Y194748D01*
X327729D01*
Y195448D01*
X327929D01*
G37*
G36*
G01X327529Y195598D02*
X327129Y195737D01*
Y196158D01*
X327529Y196298D01*
X327729D01*
Y195598D01*
X327529D01*
G37*
G36*
G01X307181Y171450D02*
X307676Y170884D01*
X307393Y170602D01*
X306827Y171097D01*
X306686Y171238D01*
X307040Y171592D01*
X307181Y171450D01*
G37*
G36*
G01X302940Y170392D02*
X302990Y171142D01*
X303390D01*
X303440Y170392D01*
Y170192D01*
X302940D01*
Y170392D01*
G37*
G36*
G01X305625Y170460D02*
X305130Y171026D01*
X305413Y171309D01*
X305979Y170814D01*
X306120Y170672D01*
X305767Y170319D01*
X305625Y170460D01*
G37*
G36*
G01X304740Y169992D02*
X304690Y169242D01*
X304290D01*
X304240Y169992D01*
Y170192D01*
X304740D01*
Y169992D01*
G37*
G36*
G01X302140D02*
X302090Y169242D01*
X301690D01*
X301640Y169992D01*
Y170192D01*
X302140D01*
Y169992D01*
G37*
G36*
G01X300240Y170392D02*
X300290Y171142D01*
X300690D01*
X300740Y170392D01*
Y170192D01*
X300240D01*
Y170392D01*
G37*
G36*
G01X307464Y172299D02*
X306969Y172864D01*
X307252Y173147D01*
X307817Y172652D01*
X307959Y172511D01*
X307605Y172157D01*
X307464Y172299D01*
G37*
G36*
G01X311030Y173191D02*
X310890Y172791D01*
X310470D01*
X310330Y173191D01*
Y173391D01*
X311030D01*
Y173191D01*
G37*
G36*
G01X309480Y173591D02*
X309620Y173991D01*
X310040D01*
X310180Y173591D01*
Y173391D01*
X309480D01*
Y173591D01*
G37*
G36*
G01X315097Y177113D02*
X314913Y177495D01*
X315210Y177792D01*
X315592Y177608D01*
X315734Y177467D01*
X315239Y176972D01*
X315097Y177113D01*
G37*
G36*
G01X313895Y175911D02*
X313711Y176293D01*
X314008Y176590D01*
X314390Y176406D01*
X314532Y176265D01*
X314037Y175770D01*
X313895Y175911D01*
G37*
G36*
G01X312693Y174709D02*
X312509Y175091D01*
X312806Y175388D01*
X313188Y175204D01*
X313330Y175063D01*
X312835Y174568D01*
X312693Y174709D01*
G37*
G36*
G01X315274Y176724D02*
X315458Y176342D01*
X315161Y176045D01*
X314779Y176229D01*
X314638Y176371D01*
X315133Y176866D01*
X315274Y176724D01*
G37*
G36*
G01X312870Y174320D02*
X313054Y173938D01*
X312757Y173641D01*
X312375Y173825D01*
X312234Y173967D01*
X312729Y174462D01*
X312870Y174320D01*
G37*
G36*
G01X314072Y175522D02*
X314256Y175140D01*
X313959Y174843D01*
X313577Y175027D01*
X313436Y175169D01*
X313931Y175664D01*
X314072Y175522D01*
G37*
G36*
G01X317678Y179128D02*
X317862Y178747D01*
X317565Y178450D01*
X317183Y178633D01*
X317042Y178775D01*
X317537Y179270D01*
X317678Y179128D01*
G37*
G36*
G01X316299Y178315D02*
X316116Y178697D01*
X316413Y178994D01*
X316794Y178810D01*
X316936Y178669D01*
X316441Y178174D01*
X316299Y178315D01*
G37*
G36*
G01X316476Y177926D02*
X316660Y177544D01*
X316363Y177247D01*
X315981Y177431D01*
X315840Y177573D01*
X316335Y178068D01*
X316476Y177926D01*
G37*
G36*
G01X317501Y179517D02*
X317318Y179899D01*
X317615Y180196D01*
X317996Y180012D01*
X318138Y179871D01*
X317643Y179376D01*
X317501Y179517D01*
G37*
G36*
G01X318704Y180719D02*
X318520Y181101D01*
X318817Y181398D01*
X319199Y181214D01*
X319340Y181073D01*
X318845Y180578D01*
X318704Y180719D01*
G37*
G36*
G01X318880Y180330D02*
X319064Y179949D01*
X318767Y179652D01*
X318385Y179836D01*
X318244Y179977D01*
X318739Y180472D01*
X318880Y180330D01*
G37*
G36*
G01X320082Y181533D02*
X320266Y181151D01*
X319969Y180854D01*
X319587Y181038D01*
X319446Y181179D01*
X319941Y181674D01*
X320082Y181533D01*
G37*
G36*
G01X319906Y181921D02*
X319722Y182303D01*
X320019Y182600D01*
X320401Y182416D01*
X320542Y182275D01*
X320047Y181780D01*
X319906Y181921D01*
G37*
G36*
G01X321108Y183124D02*
X320924Y183505D01*
X321221Y183802D01*
X321603Y183619D01*
X321744Y183477D01*
X321249Y182982D01*
X321108Y183124D01*
G37*
G36*
G01X321284Y182735D02*
X321468Y182353D01*
X321171Y182056D01*
X320790Y182240D01*
X320648Y182381D01*
X321143Y182876D01*
X321284Y182735D01*
G37*
G36*
G01X322310Y184326D02*
X322126Y184707D01*
X322423Y185004D01*
X322805Y184821D01*
X322946Y184679D01*
X322451Y184184D01*
X322310Y184326D01*
G37*
G36*
G01X323689Y185139D02*
X323873Y184757D01*
X323576Y184460D01*
X323194Y184644D01*
X323052Y184785D01*
X323547Y185280D01*
X323689Y185139D01*
G37*
G36*
G01X323512Y185528D02*
X323328Y185910D01*
X323625Y186207D01*
X324007Y186023D01*
X324148Y185881D01*
X323653Y185386D01*
X323512Y185528D01*
G37*
G36*
G01X324891Y186341D02*
X325075Y185959D01*
X324778Y185662D01*
X324396Y185846D01*
X324254Y185987D01*
X324749Y186482D01*
X324891Y186341D01*
G37*
G36*
G01X322487Y183937D02*
X322670Y183555D01*
X322373Y183258D01*
X321992Y183442D01*
X321850Y183583D01*
X322345Y184078D01*
X322487Y183937D01*
G37*
G36*
G01X324714Y186730D02*
X324530Y187112D01*
X324827Y187409D01*
X325209Y187225D01*
X325350Y187083D01*
X324855Y186588D01*
X324714Y186730D01*
G37*
G36*
G01X325916Y187932D02*
X325732Y188314D01*
X326029Y188611D01*
X326411Y188427D01*
X326552Y188285D01*
X326057Y187790D01*
X325916Y187932D01*
G37*
G36*
G01X326093Y187543D02*
X326277Y187161D01*
X325980Y186864D01*
X325598Y187048D01*
X325456Y187189D01*
X325951Y187684D01*
X326093Y187543D01*
G37*
G36*
G01X308647Y192317D02*
X308831Y191935D01*
X308534Y191638D01*
X308152Y191822D01*
X308011Y191964D01*
X308506Y192459D01*
X308647Y192317D01*
G37*
G36*
G01X308470Y192706D02*
X308286Y193088D01*
X308583Y193385D01*
X308965Y193201D01*
X309107Y193060D01*
X308612Y192565D01*
X308470Y192706D01*
G37*
G36*
G01X307445Y191115D02*
X307629Y190733D01*
X307332Y190436D01*
X306950Y190620D01*
X306809Y190762D01*
X307304Y191257D01*
X307445Y191115D01*
G37*
G36*
G01X306243Y189913D02*
X306427Y189531D01*
X306130Y189234D01*
X305748Y189418D01*
X305606Y189559D01*
X306101Y190054D01*
X306243Y189913D01*
G37*
G36*
G01X307268Y191504D02*
X307084Y191886D01*
X307381Y192183D01*
X307763Y191999D01*
X307905Y191858D01*
X307410Y191363D01*
X307268Y191504D01*
G37*
G36*
G01X306066Y190302D02*
X305882Y190684D01*
X306179Y190981D01*
X306561Y190797D01*
X306702Y190655D01*
X306208Y190161D01*
X306066Y190302D01*
G37*
G36*
G01X305041Y188711D02*
X305225Y188329D01*
X304928Y188032D01*
X304546Y188216D01*
X304404Y188357D01*
X304899Y188852D01*
X305041Y188711D01*
G37*
G36*
G01X304864Y189100D02*
X304680Y189482D01*
X304977Y189779D01*
X305359Y189595D01*
X305500Y189453D01*
X305005Y188958D01*
X304864Y189100D01*
G37*
G36*
G01X308246Y204291D02*
X307548Y204581D01*
X307472Y205448D01*
X308109Y205855D01*
X308284Y205870D01*
X308420Y204306D01*
X308246Y204291D01*
G37*
G36*
G01X294532Y187535D02*
X294392Y187135D01*
X293972D01*
X293832Y187535D01*
Y187735D01*
X294532D01*
Y187535D01*
G37*
G36*
G01X292982Y187935D02*
X293122Y188335D01*
X293542D01*
X293682Y187935D01*
Y187735D01*
X292982D01*
Y187935D01*
G37*
G36*
G01X298082D02*
X298222Y188335D01*
X298642D01*
X298782Y187935D01*
Y187735D01*
X298082D01*
Y187935D01*
G37*
G36*
G01X299782D02*
X299922Y188335D01*
X300342D01*
X300482Y187935D01*
Y187735D01*
X299782D01*
Y187935D01*
G37*
G36*
G01X301482D02*
X301622Y188335D01*
X302042D01*
X302182Y187935D01*
Y187735D01*
X301482D01*
Y187935D01*
G37*
G36*
G01X297932Y187535D02*
X297792Y187135D01*
X297372D01*
X297232Y187535D01*
Y187735D01*
X297932D01*
Y187535D01*
G37*
G36*
G01X299632D02*
X299492Y187135D01*
X299072D01*
X298932Y187535D01*
Y187735D01*
X299632D01*
Y187535D01*
G37*
G36*
G01X301332D02*
X301192Y187135D01*
X300772D01*
X300632Y187535D01*
Y187735D01*
X301332D01*
Y187535D01*
G37*
G36*
G01X303032D02*
X302892Y187135D01*
X302472D01*
X302332Y187535D01*
Y187735D01*
X303032D01*
Y187535D01*
G37*
G36*
G01X296382Y187935D02*
X296522Y188335D01*
X296942D01*
X297082Y187935D01*
Y187735D01*
X296382D01*
Y187935D01*
G37*
G36*
G01X294682D02*
X294822Y188335D01*
X295242D01*
X295382Y187935D01*
Y187735D01*
X294682D01*
Y187935D01*
G37*
G36*
G01X296232Y187535D02*
X296092Y187135D01*
X295672D01*
X295532Y187535D01*
Y187735D01*
X296232D01*
Y187535D01*
G37*
G36*
G01X325068Y214234D02*
X324398Y214583D01*
X324397Y215453D01*
X325066Y215804D01*
X325242D01*
X325243Y214234D01*
X325068D01*
G37*
G36*
G01X328446Y208324D02*
X327776Y208674D01*
Y209544D01*
X328446Y209894D01*
X328621D01*
Y208324D01*
X328446D01*
G37*
G36*
G01X328729Y193898D02*
X328329Y194037D01*
Y194458D01*
X328729Y194598D01*
X328929D01*
Y193898D01*
X328729D01*
G37*
G36*
G01X329129Y193748D02*
X329529Y193608D01*
Y193187D01*
X329129Y193048D01*
X328929D01*
Y193748D01*
X329129D01*
G37*
G36*
G01X328729Y192198D02*
X328329Y192337D01*
Y192758D01*
X328729Y192898D01*
X328929D01*
Y192198D01*
X328729D01*
G37*
G36*
G01X329129Y192048D02*
X329529Y191908D01*
Y191487D01*
X329129Y191348D01*
X328929D01*
Y192048D01*
X329129D01*
G37*
G36*
G01X328729Y190498D02*
X328329Y190637D01*
Y191058D01*
X328729Y191198D01*
X328929D01*
Y190498D01*
X328729D01*
G37*
G36*
G01X329129Y190348D02*
X329529Y190208D01*
Y189787D01*
X329129Y189648D01*
X328929D01*
Y190348D01*
X329129D01*
G37*
G36*
G01X327967Y188285D02*
X327783Y188667D01*
X328080Y188964D01*
X328462Y188780D01*
X328603Y188638D01*
X328108Y188143D01*
X327967Y188285D01*
G37*
G36*
G01X328729Y195598D02*
X328329Y195737D01*
Y196158D01*
X328729Y196298D01*
X328929D01*
Y195598D01*
X328729D01*
G37*
G36*
G01X329129Y195448D02*
X329529Y195308D01*
Y194887D01*
X329129Y194748D01*
X328929D01*
Y195448D01*
X329129D01*
G37*
G36*
G01X308277Y170354D02*
X308772Y169788D01*
X308489Y169506D01*
X307923Y170001D01*
X307782Y170142D01*
X308136Y170496D01*
X308277Y170354D01*
G37*
G36*
G01X304740Y168442D02*
X304690Y167692D01*
X304290D01*
X304240Y168442D01*
Y168642D01*
X304740D01*
Y168442D01*
G37*
G36*
G01X302940Y168842D02*
X302990Y169592D01*
X303390D01*
X303440Y168842D01*
Y168642D01*
X302940D01*
Y168842D01*
G37*
G36*
G01X306721Y169364D02*
X306226Y169930D01*
X306509Y170213D01*
X307075Y169718D01*
X307216Y169576D01*
X306863Y169223D01*
X306721Y169364D01*
G37*
G36*
G01X305540Y168842D02*
X305590Y169592D01*
X305990D01*
X306040Y168842D01*
Y168642D01*
X305540D01*
Y168842D01*
G37*
G36*
G01X302140Y168442D02*
X302090Y167692D01*
X301690D01*
X301640Y168442D01*
Y168642D01*
X302140D01*
Y168442D01*
G37*
G36*
G01X308560Y171203D02*
X308065Y171768D01*
X308348Y172051D01*
X308913Y171556D01*
X309055Y171415D01*
X308701Y171061D01*
X308560Y171203D01*
G37*
G36*
G01X311180Y172391D02*
X311320Y172791D01*
X311740D01*
X311880Y172391D01*
Y172191D01*
X311180D01*
Y172391D01*
G37*
G36*
G01X311030Y171991D02*
X310890Y171591D01*
X310470D01*
X310330Y171991D01*
Y172191D01*
X311030D01*
Y171991D01*
G37*
G36*
G01X313719Y173471D02*
X313903Y173089D01*
X313606Y172792D01*
X313224Y172976D01*
X313083Y173118D01*
X313577Y173612D01*
X313719Y173471D01*
G37*
G36*
G01X312340Y172658D02*
X312156Y173040D01*
X312453Y173337D01*
X312835Y173153D01*
X312977Y173012D01*
X312482Y172517D01*
X312340Y172658D01*
G37*
G36*
G01X314744Y175062D02*
X314560Y175444D01*
X314857Y175741D01*
X315239Y175557D01*
X315381Y175416D01*
X314886Y174921D01*
X314744Y175062D01*
G37*
G36*
G01X314921Y174673D02*
X315105Y174291D01*
X314808Y173994D01*
X314426Y174178D01*
X314285Y174320D01*
X314780Y174815D01*
X314921Y174673D01*
G37*
G36*
G01X313542Y173860D02*
X313358Y174242D01*
X313655Y174539D01*
X314037Y174355D01*
X314179Y174214D01*
X313684Y173719D01*
X313542Y173860D01*
G37*
G36*
G01X316123Y175875D02*
X316307Y175493D01*
X316010Y175196D01*
X315628Y175380D01*
X315487Y175522D01*
X315982Y176017D01*
X316123Y175875D01*
G37*
G36*
G01X318350Y178668D02*
X318167Y179050D01*
X318464Y179347D01*
X318845Y179163D01*
X318987Y179022D01*
X318492Y178527D01*
X318350Y178668D01*
G37*
G36*
G01X318527Y178279D02*
X318711Y177898D01*
X318414Y177601D01*
X318032Y177784D01*
X317891Y177926D01*
X318386Y178421D01*
X318527Y178279D01*
G37*
G36*
G01X317148Y177466D02*
X316965Y177848D01*
X317262Y178145D01*
X317643Y177961D01*
X317785Y177820D01*
X317290Y177325D01*
X317148Y177466D01*
G37*
G36*
G01X317325Y177077D02*
X317509Y176695D01*
X317212Y176398D01*
X316830Y176582D01*
X316689Y176724D01*
X317184Y177219D01*
X317325Y177077D01*
G37*
G36*
G01X315946Y176264D02*
X315762Y176646D01*
X316059Y176943D01*
X316441Y176759D01*
X316583Y176618D01*
X316088Y176123D01*
X315946Y176264D01*
G37*
G36*
G01X320931Y180684D02*
X321115Y180302D01*
X320818Y180005D01*
X320436Y180189D01*
X320295Y180330D01*
X320790Y180825D01*
X320931Y180684D01*
G37*
G36*
G01X319553Y179870D02*
X319369Y180252D01*
X319666Y180549D01*
X320048Y180365D01*
X320189Y180224D01*
X319694Y179729D01*
X319553Y179870D01*
G37*
G36*
G01X319729Y179481D02*
X319913Y179100D01*
X319616Y178803D01*
X319234Y178987D01*
X319093Y179128D01*
X319588Y179623D01*
X319729Y179481D01*
G37*
G36*
G01X320755Y181072D02*
X320571Y181454D01*
X320868Y181751D01*
X321250Y181567D01*
X321391Y181426D01*
X320896Y180931D01*
X320755Y181072D01*
G37*
G36*
G01X325563Y185881D02*
X325379Y186263D01*
X325676Y186560D01*
X326058Y186376D01*
X326199Y186234D01*
X325704Y185739D01*
X325563Y185881D01*
G37*
G36*
G01X325740Y185492D02*
X325924Y185110D01*
X325627Y184813D01*
X325245Y184997D01*
X325103Y185138D01*
X325598Y185633D01*
X325740Y185492D01*
G37*
G36*
G01X324361Y184679D02*
X324177Y185061D01*
X324474Y185358D01*
X324856Y185174D01*
X324997Y185032D01*
X324502Y184537D01*
X324361Y184679D01*
G37*
G36*
G01X321957Y182275D02*
X321773Y182656D01*
X322070Y182953D01*
X322452Y182770D01*
X322593Y182628D01*
X322098Y182133D01*
X321957Y182275D01*
G37*
G36*
G01X324538Y184290D02*
X324722Y183908D01*
X324425Y183611D01*
X324043Y183795D01*
X323901Y183936D01*
X324396Y184431D01*
X324538Y184290D01*
G37*
G36*
G01X323159Y183477D02*
X322975Y183858D01*
X323272Y184155D01*
X323654Y183972D01*
X323795Y183830D01*
X323300Y183335D01*
X323159Y183477D01*
G37*
G36*
G01X323336Y183088D02*
X323519Y182706D01*
X323222Y182409D01*
X322841Y182593D01*
X322699Y182734D01*
X323194Y183229D01*
X323336Y183088D01*
G37*
G36*
G01X322133Y181886D02*
X322317Y181504D01*
X322020Y181207D01*
X321639Y181391D01*
X321497Y181532D01*
X321992Y182027D01*
X322133Y181886D01*
G37*
G36*
G01X328144Y187896D02*
X328328Y187514D01*
X328031Y187217D01*
X327649Y187401D01*
X327508Y187543D01*
X328002Y188037D01*
X328144Y187896D01*
G37*
G36*
G01X326765Y187083D02*
X326581Y187465D01*
X326878Y187762D01*
X327260Y187578D01*
X327401Y187436D01*
X326906Y186941D01*
X326765Y187083D01*
G37*
G36*
G01X326942Y186694D02*
X327126Y186312D01*
X326829Y186015D01*
X326447Y186199D01*
X326305Y186340D01*
X326800Y186835D01*
X326942Y186694D01*
G37*
G36*
G01X306949Y194015D02*
X307133Y193633D01*
X306836Y193336D01*
X306454Y193520D01*
X306313Y193662D01*
X306808Y194157D01*
X306949Y194015D01*
G37*
G36*
G01X301482Y190335D02*
X301622Y190735D01*
X302042D01*
X302182Y190335D01*
Y190135D01*
X301482D01*
Y190335D01*
G37*
G36*
G01X301332Y189935D02*
X301192Y189535D01*
X300772D01*
X300632Y189935D01*
Y190135D01*
X301332D01*
Y189935D01*
G37*
G36*
G01X304545Y191611D02*
X304729Y191229D01*
X304432Y190932D01*
X304050Y191116D01*
X303908Y191257D01*
X304403Y191752D01*
X304545Y191611D01*
G37*
G36*
G01X305747Y192813D02*
X305931Y192431D01*
X305634Y192134D01*
X305252Y192318D01*
X305111Y192460D01*
X305606Y192955D01*
X305747Y192813D01*
G37*
G36*
G01X304368Y192000D02*
X304184Y192382D01*
X304481Y192679D01*
X304863Y192495D01*
X305004Y192353D01*
X304510Y191859D01*
X304368Y192000D01*
G37*
G36*
G01X305570Y193202D02*
X305386Y193584D01*
X305683Y193881D01*
X306065Y193697D01*
X306207Y193556D01*
X305712Y193061D01*
X305570Y193202D01*
G37*
G36*
G01X303166Y190798D02*
X302982Y191180D01*
X303279Y191477D01*
X303661Y191293D01*
X303802Y191151D01*
X303308Y190657D01*
X303166Y190798D01*
G37*
G36*
G01X292982Y190335D02*
X293122Y190735D01*
X293542D01*
X293682Y190335D01*
Y190135D01*
X292982D01*
Y190335D01*
G37*
G36*
G01X294532Y189935D02*
X294392Y189535D01*
X293972D01*
X293832Y189935D01*
Y190135D01*
X294532D01*
Y189935D01*
G37*
G36*
G01X298082Y190335D02*
X298222Y190735D01*
X298642D01*
X298782Y190335D01*
Y190135D01*
X298082D01*
Y190335D01*
G37*
G36*
G01X299782D02*
X299922Y190735D01*
X300342D01*
X300482Y190335D01*
Y190135D01*
X299782D01*
Y190335D01*
G37*
G36*
G01X297932Y189935D02*
X297792Y189535D01*
X297372D01*
X297232Y189935D01*
Y190135D01*
X297932D01*
Y189935D01*
G37*
G36*
G01X299632D02*
X299492Y189535D01*
X299072D01*
X298932Y189935D01*
Y190135D01*
X299632D01*
Y189935D01*
G37*
G36*
G01X296382Y190335D02*
X296522Y190735D01*
X296942D01*
X297082Y190335D01*
Y190135D01*
X296382D01*
Y190335D01*
G37*
G36*
G01X294682D02*
X294822Y190735D01*
X295242D01*
X295382Y190335D01*
Y190135D01*
X294682D01*
Y190335D01*
G37*
G36*
G01X296232Y189935D02*
X296092Y189535D01*
X295672D01*
X295532Y189935D01*
Y190135D01*
X296232D01*
Y189935D01*
G37*
G36*
G01X303343Y190409D02*
X303527Y190027D01*
X303230Y189730D01*
X302848Y189914D01*
X302706Y190055D01*
X303201Y190550D01*
X303343Y190409D01*
G37*
G36*
G01X325067Y188781D02*
X324883Y189163D01*
X325180Y189460D01*
X325562Y189276D01*
X325703Y189134D01*
X325208Y188639D01*
X325067Y188781D01*
G37*
G36*
G01X326729Y193748D02*
X327129Y193608D01*
Y193187D01*
X326729Y193048D01*
X326529D01*
Y193748D01*
X326729D01*
G37*
G36*
G01Y192048D02*
X327129Y191908D01*
Y191487D01*
X326729Y191348D01*
X326529D01*
Y192048D01*
X326729D01*
G37*
G36*
G01X326329Y192198D02*
X325929Y192337D01*
Y192758D01*
X326329Y192898D01*
X326529D01*
Y192198D01*
X326329D01*
G37*
G36*
G01Y193898D02*
X325929Y194037D01*
Y194458D01*
X326329Y194598D01*
X326529D01*
Y193898D01*
X326329D01*
G37*
G36*
G01Y190498D02*
X325929Y190637D01*
Y191058D01*
X326329Y191198D01*
X326529D01*
Y190498D01*
X326329D01*
G37*
G36*
G01X326446Y189594D02*
X326630Y189212D01*
X326333Y188915D01*
X325951Y189099D01*
X325809Y189240D01*
X326304Y189735D01*
X326446Y189594D01*
G37*
G36*
G01X326729Y195448D02*
X327129Y195308D01*
Y194887D01*
X326729Y194748D01*
X326529D01*
Y195448D01*
X326729D01*
G37*
G36*
G01X326329Y195598D02*
X325929Y195737D01*
Y196158D01*
X326329Y196298D01*
X326529D01*
Y195598D01*
X326329D01*
G37*
G36*
G01X306084Y172547D02*
X306579Y171981D01*
X306296Y171699D01*
X305730Y172194D01*
X305589Y172335D01*
X305943Y172689D01*
X306084Y172547D01*
G37*
G36*
G01X302940Y171942D02*
X302990Y172692D01*
X303390D01*
X303440Y171942D01*
Y171742D01*
X302940D01*
Y171942D01*
G37*
G36*
G01X300340D02*
X300390Y172692D01*
X300790D01*
X300840Y171942D01*
Y171742D01*
X300340D01*
Y171942D01*
G37*
G36*
G01X302140Y171542D02*
X302090Y170792D01*
X301690D01*
X301640Y171542D01*
Y171742D01*
X302140D01*
Y171542D01*
G37*
G36*
G01X304740D02*
X304690Y170792D01*
X304290D01*
X304240Y171542D01*
Y171742D01*
X304740D01*
Y171542D01*
G37*
G36*
G01X306367Y173395D02*
X305872Y173961D01*
X306155Y174244D01*
X306721Y173749D01*
X306862Y173607D01*
X306509Y173254D01*
X306367Y173395D01*
G37*
G36*
G01X309330Y174391D02*
X309190Y173991D01*
X308770D01*
X308630Y174391D01*
Y174591D01*
X309330D01*
Y174391D01*
G37*
G36*
G01X309480Y174791D02*
X309620Y175191D01*
X310040D01*
X310180Y174791D01*
Y174591D01*
X309480D01*
Y174791D01*
G37*
G36*
G01X311030Y174391D02*
X310890Y173991D01*
X310470D01*
X310330Y174391D01*
Y174591D01*
X311030D01*
Y174391D01*
G37*
G36*
G01X314248Y177962D02*
X314064Y178344D01*
X314361Y178641D01*
X314743Y178457D01*
X314885Y178316D01*
X314390Y177821D01*
X314248Y177962D01*
G37*
G36*
G01X315627Y178775D02*
X315811Y178393D01*
X315514Y178096D01*
X315132Y178280D01*
X314991Y178422D01*
X315486Y178917D01*
X315627Y178775D01*
G37*
G36*
G01X313046Y176760D02*
X312862Y177142D01*
X313159Y177439D01*
X313541Y177255D01*
X313683Y177114D01*
X313188Y176619D01*
X313046Y176760D01*
G37*
G36*
G01X314425Y177573D02*
X314609Y177191D01*
X314312Y176894D01*
X313930Y177078D01*
X313789Y177220D01*
X314284Y177715D01*
X314425Y177573D01*
G37*
G36*
G01X313223Y176371D02*
X313407Y175989D01*
X313110Y175692D01*
X312728Y175876D01*
X312587Y176018D01*
X313082Y176513D01*
X313223Y176371D01*
G37*
G36*
G01X311844Y175558D02*
X311660Y175940D01*
X311957Y176237D01*
X312339Y176053D01*
X312481Y175912D01*
X311986Y175417D01*
X311844Y175558D01*
G37*
G36*
G01X315450Y179164D02*
X315267Y179546D01*
X315564Y179843D01*
X315945Y179659D01*
X316087Y179518D01*
X315592Y179023D01*
X315450Y179164D01*
G37*
G36*
G01X316652Y180366D02*
X316469Y180748D01*
X316766Y181045D01*
X317147Y180861D01*
X317289Y180720D01*
X316794Y180225D01*
X316652Y180366D01*
G37*
G36*
G01X317855Y181568D02*
X317671Y181950D01*
X317968Y182247D01*
X318350Y182063D01*
X318491Y181922D01*
X317996Y181427D01*
X317855Y181568D01*
G37*
G36*
G01X318031Y181179D02*
X318215Y180798D01*
X317918Y180501D01*
X317536Y180685D01*
X317395Y180826D01*
X317890Y181321D01*
X318031Y181179D01*
G37*
G36*
G01X316829Y179977D02*
X317013Y179596D01*
X316716Y179299D01*
X316334Y179482D01*
X316193Y179624D01*
X316688Y180119D01*
X316829Y179977D01*
G37*
G36*
G01X320259Y183973D02*
X320075Y184354D01*
X320372Y184651D01*
X320754Y184468D01*
X320895Y184326D01*
X320400Y183831D01*
X320259Y183973D01*
G37*
G36*
G01X319057Y182770D02*
X318873Y183152D01*
X319170Y183449D01*
X319552Y183265D01*
X319693Y183124D01*
X319198Y182629D01*
X319057Y182770D01*
G37*
G36*
G01X320435Y183584D02*
X320619Y183202D01*
X320322Y182905D01*
X319941Y183089D01*
X319799Y183230D01*
X320294Y183725D01*
X320435Y183584D01*
G37*
G36*
G01X321461Y185175D02*
X321277Y185556D01*
X321574Y185853D01*
X321956Y185670D01*
X322097Y185528D01*
X321602Y185033D01*
X321461Y185175D01*
G37*
G36*
G01X321638Y184786D02*
X321821Y184404D01*
X321524Y184107D01*
X321143Y184291D01*
X321001Y184432D01*
X321496Y184927D01*
X321638Y184786D01*
G37*
G36*
G01X319233Y182382D02*
X319417Y182000D01*
X319120Y181703D01*
X318738Y181887D01*
X318597Y182028D01*
X319092Y182523D01*
X319233Y182382D01*
G37*
G36*
G01X322840Y185988D02*
X323024Y185606D01*
X322727Y185309D01*
X322345Y185493D01*
X322203Y185634D01*
X322698Y186129D01*
X322840Y185988D01*
G37*
G36*
G01X322663Y186377D02*
X322479Y186759D01*
X322776Y187056D01*
X323158Y186872D01*
X323299Y186730D01*
X322804Y186235D01*
X322663Y186377D01*
G37*
G36*
G01X323865Y187579D02*
X323681Y187961D01*
X323978Y188258D01*
X324360Y188074D01*
X324501Y187932D01*
X324006Y187437D01*
X323865Y187579D01*
G37*
G36*
G01X324042Y187190D02*
X324226Y186808D01*
X323929Y186511D01*
X323547Y186695D01*
X323405Y186836D01*
X323900Y187331D01*
X324042Y187190D01*
G37*
G36*
G01X325244Y188392D02*
X325428Y188010D01*
X325131Y187713D01*
X324749Y187897D01*
X324607Y188038D01*
X325102Y188533D01*
X325244Y188392D01*
G37*
G36*
G01X307780Y174791D02*
X307920Y175191D01*
X308340D01*
X308480Y174791D01*
Y174591D01*
X307780D01*
Y174791D01*
G37*
G36*
G01X307092Y189064D02*
X307276Y188682D01*
X306979Y188385D01*
X306597Y188569D01*
X306455Y188710D01*
X306950Y189205D01*
X307092Y189064D01*
G37*
G36*
G01X308117Y190655D02*
X307933Y191037D01*
X308230Y191334D01*
X308612Y191150D01*
X308754Y191009D01*
X308259Y190514D01*
X308117Y190655D01*
G37*
G36*
G01X308294Y190266D02*
X308478Y189884D01*
X308181Y189587D01*
X307799Y189771D01*
X307658Y189913D01*
X308153Y190408D01*
X308294Y190266D01*
G37*
G36*
G01X306915Y189453D02*
X306731Y189835D01*
X307028Y190132D01*
X307410Y189948D01*
X307551Y189806D01*
X307057Y189312D01*
X306915Y189453D01*
G37*
G36*
G01X305713Y188251D02*
X305529Y188633D01*
X305826Y188930D01*
X306208Y188746D01*
X306349Y188604D01*
X305854Y188109D01*
X305713Y188251D01*
G37*
G36*
G01X309496Y191468D02*
X309680Y191086D01*
X309383Y190789D01*
X309001Y190973D01*
X308860Y191115D01*
X309355Y191610D01*
X309496Y191468D01*
G37*
G36*
G01X309319Y191857D02*
X309135Y192239D01*
X309432Y192536D01*
X309814Y192352D01*
X309956Y192211D01*
X309461Y191716D01*
X309319Y191857D01*
G37*
G36*
G01X313172Y202089D02*
X313841Y201738D01*
X313840Y200868D01*
X313169Y200519D01*
X312995D01*
X312998Y202089D01*
X313172D01*
G37*
G36*
G01X292982Y186735D02*
X293122Y187135D01*
X293542D01*
X293682Y186735D01*
Y186535D01*
X292982D01*
Y186735D01*
G37*
G36*
G01X294532Y186335D02*
X294392Y185935D01*
X293972D01*
X293832Y186335D01*
Y186535D01*
X294532D01*
Y186335D01*
G37*
G36*
G01X296232D02*
X296092Y185935D01*
X295672D01*
X295532Y186335D01*
Y186535D01*
X296232D01*
Y186335D01*
G37*
G36*
G01X294682Y186735D02*
X294822Y187135D01*
X295242D01*
X295382Y186735D01*
Y186535D01*
X294682D01*
Y186735D01*
G37*
G36*
G01X304511Y187049D02*
X304327Y187431D01*
X304624Y187728D01*
X305006Y187544D01*
X305147Y187402D01*
X304652Y186907D01*
X304511Y187049D01*
G37*
G36*
G01X303182Y186735D02*
X303322Y187135D01*
X303742D01*
X303882Y186735D01*
Y186535D01*
X303182D01*
Y186735D01*
G37*
G36*
G01X296382D02*
X296522Y187135D01*
X296942D01*
X297082Y186735D01*
Y186535D01*
X296382D01*
Y186735D01*
G37*
G36*
G01X298082D02*
X298222Y187135D01*
X298642D01*
X298782Y186735D01*
Y186535D01*
X298082D01*
Y186735D01*
G37*
G36*
G01X299782D02*
X299922Y187135D01*
X300342D01*
X300482Y186735D01*
Y186535D01*
X299782D01*
Y186735D01*
G37*
G36*
G01X301482D02*
X301622Y187135D01*
X302042D01*
X302182Y186735D01*
Y186535D01*
X301482D01*
Y186735D01*
G37*
G36*
G01X297932Y186335D02*
X297792Y185935D01*
X297372D01*
X297232Y186335D01*
Y186535D01*
X297932D01*
Y186335D01*
G37*
G36*
G01X299632D02*
X299492Y185935D01*
X299072D01*
X298932Y186335D01*
Y186535D01*
X299632D01*
Y186335D01*
G37*
G36*
G01X301332D02*
X301192Y185935D01*
X300772D01*
X300632Y186335D01*
Y186535D01*
X301332D01*
Y186335D01*
G37*
G36*
G01X303032D02*
X302892Y185935D01*
X302472D01*
X302332Y186335D01*
Y186535D01*
X303032D01*
Y186335D01*
G37*
G36*
G01X305890Y187862D02*
X306074Y187480D01*
X305777Y187183D01*
X305395Y187367D01*
X305253Y187508D01*
X305748Y188003D01*
X305890Y187862D01*
G37*
G36*
G01X330070Y207969D02*
X330740Y207619D01*
Y206749D01*
X330070Y206399D01*
X329895D01*
Y207969D01*
X330070D01*
G37*
G36*
G01Y211869D02*
X330740Y211519D01*
Y210649D01*
X330070Y210299D01*
X329895D01*
Y211869D01*
X330070D01*
G37*
G36*
G01X330329Y192048D02*
X330729Y191908D01*
Y191487D01*
X330329Y191348D01*
X330129D01*
Y192048D01*
X330329D01*
G37*
G36*
G01Y190348D02*
X330729Y190208D01*
Y189787D01*
X330329Y189648D01*
X330129D01*
Y190348D01*
X330329D01*
G37*
G36*
G01Y193748D02*
X330729Y193608D01*
Y193187D01*
X330329Y193048D01*
X330129D01*
Y193748D01*
X330329D01*
G37*
G36*
G01X329929Y190498D02*
X329529Y190637D01*
Y191058D01*
X329929Y191198D01*
X330129D01*
Y190498D01*
X329929D01*
G37*
G36*
G01Y192198D02*
X329529Y192337D01*
Y192758D01*
X329929Y192898D01*
X330129D01*
Y192198D01*
X329929D01*
G37*
G36*
G01Y193898D02*
X329529Y194037D01*
Y194458D01*
X329929Y194598D01*
X330129D01*
Y193898D01*
X329929D01*
G37*
G36*
G01Y188798D02*
X329529Y188937D01*
Y189358D01*
X329929Y189498D01*
X330129D01*
Y188798D01*
X329929D01*
G37*
G36*
G01X330329Y195448D02*
X330729Y195308D01*
Y194887D01*
X330329Y194748D01*
X330129D01*
Y195448D01*
X330329D01*
G37*
G36*
G01X329929Y195598D02*
X329529Y195737D01*
Y196158D01*
X329929Y196298D01*
X330129D01*
Y195598D01*
X329929D01*
G37*
G36*
G01X304740Y166892D02*
X304690Y166142D01*
X304290D01*
X304240Y166892D01*
Y167092D01*
X304740D01*
Y166892D01*
G37*
G36*
G01X307818Y168268D02*
X307323Y168833D01*
X307606Y169116D01*
X308171Y168621D01*
X308313Y168480D01*
X307959Y168126D01*
X307818Y168268D01*
G37*
G36*
G01X307533Y167418D02*
X308028Y166852D01*
X307746Y166569D01*
X307180Y167064D01*
X307038Y167205D01*
X307392Y167559D01*
X307533Y167418D01*
G37*
G36*
G01X302940Y167292D02*
X302990Y168042D01*
X303390D01*
X303440Y167292D01*
Y167092D01*
X302940D01*
Y167292D01*
G37*
G36*
G01X305540D02*
X305590Y168042D01*
X305990D01*
X306040Y167292D01*
Y167092D01*
X305540D01*
Y167292D01*
G37*
G36*
G01X309373Y169258D02*
X309868Y168692D01*
X309586Y168409D01*
X309020Y168904D01*
X308878Y169045D01*
X309232Y169399D01*
X309373Y169258D01*
G37*
G36*
G01X311180Y171191D02*
X311320Y171591D01*
X311740D01*
X311880Y171191D01*
Y170991D01*
X311180D01*
Y171191D01*
G37*
G36*
G01X309658Y170108D02*
X309163Y170673D01*
X309446Y170956D01*
X310011Y170461D01*
X310153Y170320D01*
X309799Y169966D01*
X309658Y170108D01*
G37*
G36*
G01X314391Y173011D02*
X314207Y173393D01*
X314504Y173690D01*
X314886Y173506D01*
X315028Y173365D01*
X314533Y172870D01*
X314391Y173011D01*
G37*
G36*
G01X313189Y171809D02*
X313005Y172191D01*
X313302Y172488D01*
X313684Y172304D01*
X313825Y172162D01*
X313330Y171667D01*
X313189Y171809D01*
G37*
G36*
G01X314568Y172622D02*
X314752Y172240D01*
X314455Y171943D01*
X314073Y172127D01*
X313932Y172269D01*
X314426Y172763D01*
X314568Y172622D01*
G37*
G36*
G01X313366Y171420D02*
X313550Y171038D01*
X313253Y170741D01*
X312871Y170925D01*
X312730Y171067D01*
X313224Y171561D01*
X313366Y171420D01*
G37*
G36*
G01X315770Y173824D02*
X315954Y173442D01*
X315657Y173145D01*
X315275Y173329D01*
X315134Y173471D01*
X315629Y173966D01*
X315770Y173824D01*
G37*
G36*
G01X315593Y174213D02*
X315409Y174595D01*
X315706Y174892D01*
X316088Y174708D01*
X316230Y174567D01*
X315735Y174072D01*
X315593Y174213D01*
G37*
G36*
G01X318174Y176228D02*
X318358Y175846D01*
X318061Y175549D01*
X317679Y175733D01*
X317538Y175875D01*
X318033Y176370D01*
X318174Y176228D01*
G37*
G36*
G01X316972Y175026D02*
X317156Y174644D01*
X316859Y174347D01*
X316477Y174531D01*
X316336Y174673D01*
X316831Y175168D01*
X316972Y175026D01*
G37*
G36*
G01X316795Y175415D02*
X316611Y175797D01*
X316908Y176094D01*
X317290Y175910D01*
X317432Y175769D01*
X316937Y175274D01*
X316795Y175415D01*
G37*
G36*
G01X317997Y176617D02*
X317814Y176999D01*
X318111Y177296D01*
X318492Y177112D01*
X318634Y176971D01*
X318139Y176476D01*
X317997Y176617D01*
G37*
G36*
G01X321780Y179835D02*
X321964Y179453D01*
X321667Y179156D01*
X321285Y179340D01*
X321144Y179481D01*
X321639Y179976D01*
X321780Y179835D01*
G37*
G36*
G01X320402Y179021D02*
X320218Y179403D01*
X320515Y179700D01*
X320897Y179516D01*
X321038Y179375D01*
X320543Y178880D01*
X320402Y179021D01*
G37*
G36*
G01X320578Y178632D02*
X320762Y178251D01*
X320465Y177954D01*
X320083Y178138D01*
X319942Y178279D01*
X320437Y178774D01*
X320578Y178632D01*
G37*
G36*
G01X319199Y177819D02*
X319016Y178201D01*
X319313Y178498D01*
X319694Y178314D01*
X319836Y178173D01*
X319341Y177678D01*
X319199Y177819D01*
G37*
G36*
G01X319376Y177430D02*
X319560Y177049D01*
X319263Y176752D01*
X318881Y176935D01*
X318740Y177077D01*
X319235Y177572D01*
X319376Y177430D01*
G37*
G36*
G01X321604Y180223D02*
X321420Y180605D01*
X321717Y180902D01*
X322099Y180718D01*
X322240Y180577D01*
X321745Y180082D01*
X321604Y180223D01*
G37*
G36*
G01X322982Y181037D02*
X323166Y180655D01*
X322869Y180358D01*
X322488Y180542D01*
X322346Y180683D01*
X322841Y181178D01*
X322982Y181037D01*
G37*
G36*
G01X322806Y181426D02*
X322622Y181807D01*
X322919Y182104D01*
X323301Y181921D01*
X323442Y181779D01*
X322947Y181284D01*
X322806Y181426D01*
G37*
G36*
G01X324185Y182239D02*
X324368Y181857D01*
X324071Y181560D01*
X323690Y181744D01*
X323548Y181885D01*
X324043Y182380D01*
X324185Y182239D01*
G37*
G36*
G01X325387Y183441D02*
X325571Y183059D01*
X325274Y182762D01*
X324892Y182946D01*
X324750Y183087D01*
X325245Y183582D01*
X325387Y183441D01*
G37*
G36*
G01X326589Y184643D02*
X326773Y184261D01*
X326476Y183964D01*
X326094Y184148D01*
X325952Y184289D01*
X326447Y184784D01*
X326589Y184643D01*
G37*
G36*
G01X326412Y185032D02*
X326228Y185414D01*
X326525Y185711D01*
X326907Y185527D01*
X327048Y185385D01*
X326553Y184890D01*
X326412Y185032D01*
G37*
G36*
G01X327791Y185845D02*
X327975Y185463D01*
X327678Y185166D01*
X327296Y185350D01*
X327154Y185491D01*
X327649Y185986D01*
X327791Y185845D01*
G37*
G36*
G01X324008Y182628D02*
X323824Y183009D01*
X324121Y183306D01*
X324503Y183123D01*
X324644Y182981D01*
X324149Y182486D01*
X324008Y182628D01*
G37*
G36*
G01X325210Y183830D02*
X325026Y184212D01*
X325323Y184509D01*
X325705Y184325D01*
X325846Y184183D01*
X325351Y183688D01*
X325210Y183830D01*
G37*
G36*
G01X327614Y186234D02*
X327430Y186616D01*
X327727Y186913D01*
X328109Y186729D01*
X328250Y186587D01*
X327755Y186092D01*
X327614Y186234D01*
G37*
G36*
G01X328816Y187436D02*
X328632Y187818D01*
X328929Y188115D01*
X329311Y187931D01*
X329453Y187790D01*
X328958Y187295D01*
X328816Y187436D01*
G37*
G36*
G01X328993Y187047D02*
X329177Y186665D01*
X328880Y186368D01*
X328498Y186552D01*
X328357Y186694D01*
X328851Y187188D01*
X328993Y187047D01*
G37*
G36*
G01X330195Y188249D02*
X330379Y187867D01*
X330082Y187570D01*
X329700Y187754D01*
X329559Y187896D01*
X330053Y188390D01*
X330195Y188249D01*
G37*
G36*
G01X320965Y188075D02*
X320781Y188457D01*
X321078Y188754D01*
X321460Y188570D01*
X321601Y188428D01*
X321106Y187933D01*
X320965Y188075D01*
G37*
G36*
G01X322167Y189277D02*
X321983Y189659D01*
X322280Y189956D01*
X322662Y189772D01*
X322803Y189630D01*
X322308Y189135D01*
X322167Y189277D01*
G37*
G36*
G01X322344Y188888D02*
X322528Y188506D01*
X322231Y188209D01*
X321849Y188393D01*
X321707Y188534D01*
X322202Y189029D01*
X322344Y188888D01*
G37*
G36*
G01X323546Y190090D02*
X323730Y189708D01*
X323433Y189411D01*
X323051Y189595D01*
X322909Y189736D01*
X323404Y190231D01*
X323546Y190090D01*
G37*
G36*
G01X324329Y193748D02*
X324729Y193608D01*
Y193187D01*
X324329Y193048D01*
X324129D01*
Y193748D01*
X324329D01*
G37*
G36*
G01X323929Y193898D02*
X323529Y194037D01*
Y194458D01*
X323929Y194598D01*
X324129D01*
Y193898D01*
X323929D01*
G37*
G36*
G01Y192198D02*
X323529Y192337D01*
Y192758D01*
X323929Y192898D01*
X324129D01*
Y192198D01*
X323929D01*
G37*
G36*
G01X324329Y192048D02*
X324729Y191908D01*
Y191487D01*
X324329Y191348D01*
X324129D01*
Y192048D01*
X324329D01*
G37*
G36*
G01Y195448D02*
X324729Y195308D01*
Y194887D01*
X324329Y194748D01*
X324129D01*
Y195448D01*
X324329D01*
G37*
G36*
G01X323929Y195598D02*
X323529Y195737D01*
Y196158D01*
X323929Y196298D01*
X324129D01*
Y195598D01*
X323929D01*
G37*
G36*
G01X311525Y178069D02*
X311709Y177687D01*
X311412Y177390D01*
X311030Y177574D01*
X310889Y177716D01*
X311384Y178211D01*
X311525Y178069D01*
G37*
G36*
G01X311348Y178458D02*
X311164Y178840D01*
X311461Y179137D01*
X311843Y178953D01*
X311985Y178812D01*
X311490Y178317D01*
X311348Y178458D01*
G37*
G36*
G01X313752Y180862D02*
X313569Y181244D01*
X313866Y181541D01*
X314247Y181357D01*
X314389Y181216D01*
X313894Y180721D01*
X313752Y180862D01*
G37*
G36*
G01X312550Y179660D02*
X312366Y180042D01*
X312663Y180339D01*
X313045Y180155D01*
X313187Y180014D01*
X312692Y179519D01*
X312550Y179660D01*
G37*
G36*
G01X313929Y180473D02*
X314113Y180091D01*
X313816Y179794D01*
X313434Y179978D01*
X313293Y180120D01*
X313788Y180615D01*
X313929Y180473D01*
G37*
G36*
G01X312727Y179271D02*
X312911Y178889D01*
X312614Y178592D01*
X312232Y178776D01*
X312091Y178918D01*
X312586Y179413D01*
X312727Y179271D01*
G37*
G36*
G01X296840Y174642D02*
X296790Y173892D01*
X296390D01*
X296340Y174642D01*
Y174842D01*
X296840D01*
Y174642D01*
G37*
G36*
G01X302940Y175042D02*
X302990Y175792D01*
X303390D01*
X303440Y175042D01*
Y174842D01*
X302940D01*
Y175042D01*
G37*
G36*
G01X305730Y176581D02*
X306225Y176015D01*
X305942Y175733D01*
X305376Y176228D01*
X305235Y176369D01*
X305589Y176723D01*
X305730Y176581D01*
G37*
G36*
G01X304173Y175589D02*
X303678Y176155D01*
X303961Y176438D01*
X304527Y175943D01*
X304668Y175801D01*
X304315Y175448D01*
X304173Y175589D01*
G37*
G36*
G01X309330Y176791D02*
X309190Y176391D01*
X308770D01*
X308630Y176791D01*
Y176991D01*
X309330D01*
Y176791D01*
G37*
G36*
G01X307780Y177191D02*
X307920Y177591D01*
X308340D01*
X308480Y177191D01*
Y176991D01*
X307780D01*
Y177191D01*
G37*
G36*
G01X307630Y176791D02*
X307490Y176391D01*
X307070D01*
X306930Y176791D01*
Y176991D01*
X307630D01*
Y176791D01*
G37*
G36*
G01X306080Y177191D02*
X306220Y177591D01*
X306640D01*
X306780Y177191D01*
Y176991D01*
X306080D01*
Y177191D01*
G37*
G36*
G01X297740Y175042D02*
X297790Y175792D01*
X298190D01*
X298240Y175042D01*
Y174842D01*
X297740D01*
Y175042D01*
G37*
G36*
G01X300340D02*
X300390Y175792D01*
X300790D01*
X300840Y175042D01*
Y174842D01*
X300340D01*
Y175042D01*
G37*
G36*
G01X299540Y174642D02*
X299490Y173892D01*
X299090D01*
X299040Y174642D01*
Y174842D01*
X299540D01*
Y174642D01*
G37*
G36*
G01X302140D02*
X302090Y173892D01*
X301690D01*
X301640Y174642D01*
Y174842D01*
X302140D01*
Y174642D01*
G37*
G36*
G01X315131Y181675D02*
X315315Y181294D01*
X315018Y180997D01*
X314636Y181180D01*
X314495Y181322D01*
X314990Y181817D01*
X315131Y181675D01*
G37*
G36*
G01X316333Y182877D02*
X316517Y182496D01*
X316220Y182199D01*
X315838Y182383D01*
X315697Y182524D01*
X316192Y183019D01*
X316333Y182877D01*
G37*
G36*
G01X314954Y182064D02*
X314771Y182446D01*
X315068Y182743D01*
X315449Y182559D01*
X315591Y182418D01*
X315096Y181923D01*
X314954Y182064D01*
G37*
G36*
G01X317535Y184080D02*
X317719Y183698D01*
X317422Y183401D01*
X317040Y183585D01*
X316899Y183726D01*
X317394Y184221D01*
X317535Y184080D01*
G37*
G36*
G01X316157Y183266D02*
X315973Y183648D01*
X316270Y183945D01*
X316652Y183761D01*
X316793Y183620D01*
X316298Y183125D01*
X316157Y183266D01*
G37*
G36*
G01X317359Y184468D02*
X317175Y184850D01*
X317472Y185147D01*
X317854Y184963D01*
X317995Y184822D01*
X317500Y184327D01*
X317359Y184468D01*
G37*
G36*
G01X318561Y185671D02*
X318377Y186052D01*
X318674Y186349D01*
X319056Y186166D01*
X319197Y186024D01*
X318702Y185529D01*
X318561Y185671D01*
G37*
G36*
G01X318737Y185282D02*
X318921Y184900D01*
X318624Y184603D01*
X318243Y184787D01*
X318101Y184928D01*
X318596Y185423D01*
X318737Y185282D01*
G37*
G36*
G01X319940Y186484D02*
X320123Y186102D01*
X319826Y185805D01*
X319445Y185989D01*
X319303Y186130D01*
X319798Y186625D01*
X319940Y186484D01*
G37*
G36*
G01X321142Y187686D02*
X321326Y187304D01*
X321029Y187007D01*
X320647Y187191D01*
X320505Y187332D01*
X321000Y187827D01*
X321142Y187686D01*
G37*
G36*
G01X319763Y186873D02*
X319579Y187254D01*
X319876Y187551D01*
X320258Y187368D01*
X320399Y187226D01*
X319904Y186731D01*
X319763Y186873D01*
G37*
G36*
G01X323365Y207931D02*
X324034Y207578D01*
X324031Y206709D01*
X323360Y206361D01*
X323184Y206362D01*
X323190Y207931D01*
X323365D01*
G37*
G36*
G01X325129Y192198D02*
X324729Y192337D01*
Y192758D01*
X325129Y192898D01*
X325329D01*
Y192198D01*
X325129D01*
G37*
G36*
G01Y193898D02*
X324729Y194037D01*
Y194458D01*
X325129Y194598D01*
X325329D01*
Y193898D01*
X325129D01*
G37*
G36*
G01Y190498D02*
X324729Y190637D01*
Y191058D01*
X325129Y191198D01*
X325329D01*
Y190498D01*
X325129D01*
G37*
G36*
G01X325529Y192048D02*
X325929Y191908D01*
Y191487D01*
X325529Y191348D01*
X325329D01*
Y192048D01*
X325529D01*
G37*
G36*
G01X324218Y189630D02*
X324034Y190012D01*
X324331Y190309D01*
X324713Y190125D01*
X324854Y189983D01*
X324359Y189488D01*
X324218Y189630D01*
G37*
G36*
G01X323016Y188428D02*
X322832Y188810D01*
X323129Y189107D01*
X323511Y188923D01*
X323652Y188781D01*
X323157Y188286D01*
X323016Y188428D01*
G37*
G36*
G01X324395Y189241D02*
X324579Y188859D01*
X324282Y188562D01*
X323900Y188746D01*
X323758Y188887D01*
X324253Y189382D01*
X324395Y189241D01*
G37*
G36*
G01X325529Y193748D02*
X325929Y193608D01*
Y193187D01*
X325529Y193048D01*
X325329D01*
Y193748D01*
X325529D01*
G37*
G36*
G01Y195448D02*
X325929Y195308D01*
Y194887D01*
X325529Y194748D01*
X325329D01*
Y195448D01*
X325529D01*
G37*
G36*
G01X325129Y195598D02*
X324729Y195737D01*
Y196158D01*
X325129Y196298D01*
X325329D01*
Y195598D01*
X325129D01*
G37*
G36*
G01X313399Y178811D02*
X313215Y179193D01*
X313512Y179490D01*
X313894Y179306D01*
X314036Y179165D01*
X313541Y178670D01*
X313399Y178811D01*
G37*
G36*
G01X313576Y178422D02*
X313760Y178040D01*
X313463Y177743D01*
X313081Y177927D01*
X312940Y178069D01*
X313435Y178564D01*
X313576Y178422D01*
G37*
G36*
G01X312197Y177609D02*
X312013Y177991D01*
X312310Y178288D01*
X312692Y178104D01*
X312834Y177963D01*
X312339Y177468D01*
X312197Y177609D01*
G37*
G36*
G01X299540Y173092D02*
X299490Y172342D01*
X299090D01*
X299040Y173092D01*
Y173292D01*
X299540D01*
Y173092D01*
G37*
G36*
G01X302140D02*
X302090Y172342D01*
X301690D01*
X301640Y173092D01*
Y173292D01*
X302140D01*
Y173092D01*
G37*
G36*
G01X304987Y173644D02*
X305482Y173078D01*
X305199Y172796D01*
X304633Y173291D01*
X304492Y173432D01*
X304846Y173786D01*
X304987Y173644D01*
G37*
G36*
G01X297640Y173492D02*
X297690Y174242D01*
X298090D01*
X298140Y173492D01*
Y173292D01*
X297640D01*
Y173492D01*
G37*
G36*
G01X306827Y175484D02*
X307322Y174918D01*
X307039Y174636D01*
X306473Y175131D01*
X306332Y175272D01*
X306686Y175626D01*
X306827Y175484D01*
G37*
G36*
G01X309330Y175591D02*
X309190Y175191D01*
X308770D01*
X308630Y175591D01*
Y175791D01*
X309330D01*
Y175591D01*
G37*
G36*
G01X307780Y175991D02*
X307920Y176391D01*
X308340D01*
X308480Y175991D01*
Y175791D01*
X307780D01*
Y175991D01*
G37*
G36*
G01X305270Y174492D02*
X304775Y175058D01*
X305058Y175341D01*
X305624Y174846D01*
X305765Y174704D01*
X305412Y174351D01*
X305270Y174492D01*
G37*
G36*
G01X302940Y173492D02*
X302990Y174242D01*
X303390D01*
X303440Y173492D01*
Y173292D01*
X302940D01*
Y173492D01*
G37*
G36*
G01X300340D02*
X300390Y174242D01*
X300790D01*
X300840Y173492D01*
Y173292D01*
X300340D01*
Y173492D01*
G37*
G36*
G01X309480Y175991D02*
X309620Y176391D01*
X310040D01*
X310180Y175991D01*
Y175791D01*
X309480D01*
Y175991D01*
G37*
G36*
G01X310995Y176407D02*
X310811Y176789D01*
X311108Y177086D01*
X311490Y176902D01*
X311632Y176761D01*
X311137Y176266D01*
X310995Y176407D01*
G37*
G36*
G01X314778Y179624D02*
X314962Y179242D01*
X314665Y178945D01*
X314283Y179129D01*
X314142Y179271D01*
X314637Y179766D01*
X314778Y179624D01*
G37*
G36*
G01X312374Y177220D02*
X312558Y176838D01*
X312261Y176541D01*
X311879Y176725D01*
X311738Y176867D01*
X312233Y177362D01*
X312374Y177220D01*
G37*
G36*
G01X314601Y180013D02*
X314418Y180395D01*
X314715Y180692D01*
X315096Y180508D01*
X315238Y180367D01*
X314743Y179872D01*
X314601Y180013D01*
G37*
G36*
G01X315980Y180826D02*
X316164Y180445D01*
X315867Y180148D01*
X315485Y180331D01*
X315344Y180473D01*
X315839Y180968D01*
X315980Y180826D01*
G37*
G36*
G01X315803Y181215D02*
X315620Y181597D01*
X315917Y181894D01*
X316298Y181710D01*
X316440Y181569D01*
X315945Y181074D01*
X315803Y181215D01*
G37*
G36*
G01X317182Y182028D02*
X317366Y181647D01*
X317069Y181350D01*
X316687Y181534D01*
X316546Y181675D01*
X317041Y182170D01*
X317182Y182028D01*
G37*
G36*
G01X317006Y182417D02*
X316822Y182799D01*
X317119Y183096D01*
X317501Y182912D01*
X317642Y182771D01*
X317147Y182276D01*
X317006Y182417D01*
G37*
G36*
G01X320789Y185635D02*
X320972Y185253D01*
X320675Y184956D01*
X320294Y185140D01*
X320152Y185281D01*
X320647Y185776D01*
X320789Y185635D01*
G37*
G36*
G01X318208Y183619D02*
X318024Y184001D01*
X318321Y184298D01*
X318703Y184114D01*
X318844Y183973D01*
X318349Y183478D01*
X318208Y183619D01*
G37*
G36*
G01X318384Y183231D02*
X318568Y182849D01*
X318271Y182552D01*
X317889Y182736D01*
X317748Y182877D01*
X318243Y183372D01*
X318384Y183231D01*
G37*
G36*
G01X319586Y184433D02*
X319770Y184051D01*
X319473Y183754D01*
X319092Y183938D01*
X318950Y184079D01*
X319445Y184574D01*
X319586Y184433D01*
G37*
G36*
G01X319410Y184822D02*
X319226Y185203D01*
X319523Y185500D01*
X319905Y185317D01*
X320046Y185175D01*
X319551Y184680D01*
X319410Y184822D01*
G37*
G36*
G01X320612Y186024D02*
X320428Y186405D01*
X320725Y186702D01*
X321107Y186519D01*
X321248Y186377D01*
X320753Y185882D01*
X320612Y186024D01*
G37*
G36*
G01X321991Y186837D02*
X322175Y186455D01*
X321878Y186158D01*
X321496Y186342D01*
X321354Y186483D01*
X321849Y186978D01*
X321991Y186837D01*
G37*
G36*
G01X321814Y187226D02*
X321630Y187608D01*
X321927Y187905D01*
X322309Y187721D01*
X322450Y187579D01*
X321955Y187084D01*
X321814Y187226D01*
G37*
G36*
G01X323193Y188039D02*
X323377Y187657D01*
X323080Y187360D01*
X322698Y187544D01*
X322556Y187685D01*
X323051Y188180D01*
X323193Y188039D01*
G37*
G36*
G01X311172Y176018D02*
X311356Y175636D01*
X311059Y175339D01*
X310677Y175523D01*
X310536Y175665D01*
X311031Y176160D01*
X311172Y176018D01*
G37*
G36*
G01X335206Y208324D02*
X334536Y208674D01*
Y209544D01*
X335206Y209894D01*
X335381D01*
Y208324D01*
X335206D01*
G37*
G36*
G01X333929Y190348D02*
X334329Y190208D01*
Y189787D01*
X333929Y189648D01*
X333729D01*
Y190348D01*
X333929D01*
G37*
G36*
G01Y192048D02*
X334329Y191908D01*
Y191487D01*
X333929Y191348D01*
X333729D01*
Y192048D01*
X333929D01*
G37*
G36*
G01Y193748D02*
X334329Y193608D01*
Y193187D01*
X333929Y193048D01*
X333729D01*
Y193748D01*
X333929D01*
G37*
G36*
G01X333529Y188798D02*
X333129Y188937D01*
Y189358D01*
X333529Y189498D01*
X333729D01*
Y188798D01*
X333529D01*
G37*
G36*
G01Y190498D02*
X333129Y190637D01*
Y191058D01*
X333529Y191198D01*
X333729D01*
Y190498D01*
X333529D01*
G37*
G36*
G01Y192198D02*
X333129Y192337D01*
Y192758D01*
X333529Y192898D01*
X333729D01*
Y192198D01*
X333529D01*
G37*
G36*
G01Y193898D02*
X333129Y194037D01*
Y194458D01*
X333529Y194598D01*
X333729D01*
Y193898D01*
X333529D01*
G37*
G36*
G01X308984Y162290D02*
X309479Y161724D01*
X309197Y161441D01*
X308631Y161936D01*
X308489Y162077D01*
X308843Y162431D01*
X308984Y162290D01*
G37*
G36*
G01X309267Y163138D02*
X308772Y163704D01*
X309055Y163987D01*
X309621Y163492D01*
X309762Y163350D01*
X309409Y162997D01*
X309267Y163138D01*
G37*
G36*
G01X310824Y164130D02*
X311319Y163564D01*
X311037Y163281D01*
X310471Y163776D01*
X310329Y163917D01*
X310683Y164271D01*
X310824Y164130D01*
G37*
G36*
G01X311107Y164978D02*
X310612Y165544D01*
X310895Y165827D01*
X311461Y165332D01*
X311602Y165190D01*
X311249Y164837D01*
X311107Y164978D01*
G37*
G36*
G01X312663Y165968D02*
X313158Y165402D01*
X312875Y165120D01*
X312309Y165615D01*
X312168Y165756D01*
X312522Y166110D01*
X312663Y165968D01*
G37*
G36*
G01X314534Y168060D02*
X314350Y168442D01*
X314647Y168739D01*
X315029Y168555D01*
X315170Y168413D01*
X314675Y167918D01*
X314534Y168060D01*
G37*
G36*
G01X312947Y166818D02*
X312452Y167384D01*
X312735Y167667D01*
X313301Y167172D01*
X313442Y167030D01*
X313089Y166677D01*
X312947Y166818D01*
G37*
G36*
G01X315736Y169262D02*
X315552Y169644D01*
X315849Y169941D01*
X316231Y169757D01*
X316372Y169615D01*
X315877Y169120D01*
X315736Y169262D01*
G37*
G36*
G01X315913Y168873D02*
X316097Y168491D01*
X315800Y168194D01*
X315418Y168378D01*
X315276Y168519D01*
X315771Y169014D01*
X315913Y168873D01*
G37*
G36*
G01X318140Y171666D02*
X317956Y172048D01*
X318253Y172345D01*
X318635Y172161D01*
X318777Y172020D01*
X318282Y171525D01*
X318140Y171666D01*
G37*
G36*
G01X316938Y170464D02*
X316754Y170846D01*
X317051Y171143D01*
X317433Y170959D01*
X317575Y170818D01*
X317080Y170323D01*
X316938Y170464D01*
G37*
G36*
G01X318317Y171277D02*
X318501Y170895D01*
X318204Y170598D01*
X317822Y170782D01*
X317681Y170924D01*
X318176Y171419D01*
X318317Y171277D01*
G37*
G36*
G01X317115Y170075D02*
X317299Y169693D01*
X317002Y169396D01*
X316620Y169580D01*
X316479Y169722D01*
X316973Y170216D01*
X317115Y170075D01*
G37*
G36*
G01X320544Y174070D02*
X320361Y174452D01*
X320658Y174749D01*
X321039Y174565D01*
X321181Y174424D01*
X320686Y173929D01*
X320544Y174070D01*
G37*
G36*
G01X321923Y174883D02*
X322107Y174502D01*
X321810Y174205D01*
X321428Y174388D01*
X321287Y174530D01*
X321782Y175025D01*
X321923Y174883D01*
G37*
G36*
G01X331363Y184889D02*
X331179Y185271D01*
X331476Y185568D01*
X331858Y185384D01*
X332000Y185243D01*
X331505Y184748D01*
X331363Y184889D01*
G37*
G36*
G01X332742Y185702D02*
X332926Y185320D01*
X332629Y185023D01*
X332247Y185207D01*
X332106Y185349D01*
X332601Y185844D01*
X332742Y185702D01*
G37*
G36*
G01X328959Y182485D02*
X328775Y182867D01*
X329072Y183164D01*
X329454Y182980D01*
X329595Y182838D01*
X329100Y182343D01*
X328959Y182485D01*
G37*
G36*
G01X330161Y183687D02*
X329977Y184069D01*
X330274Y184366D01*
X330656Y184182D01*
X330797Y184040D01*
X330302Y183545D01*
X330161Y183687D01*
G37*
G36*
G01X330338Y183298D02*
X330522Y182916D01*
X330225Y182619D01*
X329843Y182803D01*
X329701Y182944D01*
X330196Y183439D01*
X330338Y183298D01*
G37*
G36*
G01X331540Y184500D02*
X331724Y184118D01*
X331427Y183821D01*
X331045Y184005D01*
X330904Y184147D01*
X331398Y184641D01*
X331540Y184500D01*
G37*
G36*
G01X324151Y177676D02*
X323967Y178058D01*
X324264Y178355D01*
X324646Y178171D01*
X324787Y178030D01*
X324292Y177535D01*
X324151Y177676D01*
G37*
G36*
G01X325353Y178879D02*
X325169Y179260D01*
X325466Y179557D01*
X325848Y179374D01*
X325989Y179232D01*
X325494Y178737D01*
X325353Y178879D01*
G37*
G36*
G01X326555Y180081D02*
X326371Y180462D01*
X326668Y180759D01*
X327050Y180576D01*
X327191Y180434D01*
X326696Y179939D01*
X326555Y180081D01*
G37*
G36*
G01X327757Y181283D02*
X327573Y181665D01*
X327870Y181962D01*
X328252Y181778D01*
X328393Y181636D01*
X327898Y181141D01*
X327757Y181283D01*
G37*
G36*
G01X325529Y178490D02*
X325713Y178108D01*
X325416Y177811D01*
X325035Y177995D01*
X324893Y178136D01*
X325388Y178631D01*
X325529Y178490D01*
G37*
G36*
G01X326732Y179692D02*
X326915Y179310D01*
X326618Y179013D01*
X326237Y179197D01*
X326095Y179338D01*
X326590Y179833D01*
X326732Y179692D01*
G37*
G36*
G01X327934Y180894D02*
X328118Y180512D01*
X327821Y180215D01*
X327439Y180399D01*
X327297Y180540D01*
X327792Y181035D01*
X327934Y180894D01*
G37*
G36*
G01X329136Y182096D02*
X329320Y181714D01*
X329023Y181417D01*
X328641Y181601D01*
X328499Y181742D01*
X328994Y182237D01*
X329136Y182096D01*
G37*
G36*
G01X323125Y176085D02*
X323309Y175704D01*
X323012Y175407D01*
X322630Y175591D01*
X322489Y175732D01*
X322984Y176227D01*
X323125Y176085D01*
G37*
G36*
G01X322949Y176474D02*
X322765Y176856D01*
X323062Y177153D01*
X323444Y176969D01*
X323585Y176828D01*
X323090Y176333D01*
X322949Y176474D01*
G37*
G36*
G01X324327Y177288D02*
X324511Y176906D01*
X324214Y176609D01*
X323832Y176793D01*
X323691Y176934D01*
X324186Y177429D01*
X324327Y177288D01*
G37*
G36*
G01X321746Y175272D02*
X321563Y175654D01*
X321860Y175951D01*
X322241Y175767D01*
X322383Y175626D01*
X321888Y175131D01*
X321746Y175272D01*
G37*
G36*
G01X319342Y172868D02*
X319158Y173250D01*
X319455Y173547D01*
X319837Y173363D01*
X319979Y173222D01*
X319484Y172727D01*
X319342Y172868D01*
G37*
G36*
G01X319519Y172479D02*
X319703Y172097D01*
X319406Y171800D01*
X319024Y171984D01*
X318883Y172126D01*
X319378Y172621D01*
X319519Y172479D01*
G37*
G36*
G01X320721Y173681D02*
X320905Y173299D01*
X320608Y173002D01*
X320226Y173186D01*
X320085Y173328D01*
X320580Y173823D01*
X320721Y173681D01*
G37*
G36*
G01X332565Y186091D02*
X332381Y186473D01*
X332678Y186770D01*
X333060Y186586D01*
X333202Y186445D01*
X332707Y185950D01*
X332565Y186091D01*
G37*
G36*
G01X333929Y188648D02*
X334329Y188508D01*
Y188087D01*
X333929Y187948D01*
X333729D01*
Y188648D01*
X333929D01*
G37*
G36*
G01X333529Y187098D02*
X333129Y187237D01*
Y187658D01*
X333529Y187798D01*
X333729D01*
Y187098D01*
X333529D01*
G37*
G36*
G01X333944Y186904D02*
X334128Y186522D01*
X333831Y186225D01*
X333449Y186409D01*
X333308Y186551D01*
X333803Y187046D01*
X333944Y186904D01*
G37*
G36*
G01X334997Y213583D02*
X335647Y213968D01*
X336387Y213509D01*
X336331Y212755D01*
X336238Y212606D01*
X334904Y213434D01*
X334997Y213583D01*
G37*
G36*
G01X334729Y188798D02*
X334329Y188937D01*
Y189358D01*
X334729Y189498D01*
X334979D01*
Y188798D01*
X334729D01*
G37*
G36*
G01Y193898D02*
X334329Y194037D01*
Y194458D01*
X334729Y194598D01*
X334979D01*
Y193898D01*
X334729D01*
G37*
G36*
G01Y192198D02*
X334329Y192337D01*
Y192758D01*
X334729Y192898D01*
X334979D01*
Y192198D01*
X334729D01*
G37*
G36*
G01Y190498D02*
X334329Y190637D01*
Y191058D01*
X334729Y191198D01*
X334979D01*
Y190498D01*
X334729D01*
G37*
G36*
G01X310364Y162042D02*
X309869Y162607D01*
X310152Y162890D01*
X310718Y162395D01*
X310894Y162218D01*
X310541Y161865D01*
X310364Y162042D01*
G37*
G36*
G01X312204Y163882D02*
X311709Y164447D01*
X311992Y164730D01*
X312558Y164235D01*
X312734Y164058D01*
X312381Y163705D01*
X312204Y163882D01*
G37*
G36*
G01X314044Y165722D02*
X313549Y166287D01*
X313832Y166570D01*
X314398Y166075D01*
X314574Y165898D01*
X314221Y165545D01*
X314044Y165722D01*
G37*
G36*
G01X315383Y167211D02*
X315199Y167593D01*
X315496Y167890D01*
X315878Y167706D01*
X316054Y167529D01*
X315559Y167034D01*
X315383Y167211D01*
G37*
G36*
G01X317787Y169615D02*
X317603Y169997D01*
X317900Y170294D01*
X318282Y170110D01*
X318459Y169934D01*
X317964Y169439D01*
X317787Y169615D01*
G37*
G36*
G01X316585Y168413D02*
X316401Y168795D01*
X316698Y169092D01*
X317080Y168908D01*
X317256Y168731D01*
X316761Y168236D01*
X316585Y168413D01*
G37*
G36*
G01X326201Y178030D02*
X326018Y178412D01*
X326314Y178709D01*
X326696Y178525D01*
X326873Y178348D01*
X326378Y177853D01*
X326201Y178030D01*
G37*
G36*
G01X327403Y179232D02*
X327220Y179614D01*
X327517Y179911D01*
X327898Y179727D01*
X328075Y179550D01*
X327580Y179055D01*
X327403Y179232D01*
G37*
G36*
G01X328606Y180434D02*
X328422Y180816D01*
X328719Y181113D01*
X329100Y180929D01*
X329277Y180752D01*
X328782Y180257D01*
X328606Y180434D01*
G37*
G36*
G01X329808Y181636D02*
X329624Y182018D01*
X329921Y182315D01*
X330303Y182131D01*
X330479Y181954D01*
X329984Y181459D01*
X329808Y181636D01*
G37*
G36*
G01X331010Y182838D02*
X330826Y183220D01*
X331123Y183517D01*
X331505Y183333D01*
X331681Y183156D01*
X331186Y182661D01*
X331010Y182838D01*
G37*
G36*
G01X332212Y184040D02*
X332028Y184422D01*
X332325Y184719D01*
X332707Y184535D01*
X332884Y184359D01*
X332389Y183864D01*
X332212Y184040D01*
G37*
G36*
G01X333414Y185242D02*
X333230Y185624D01*
X333527Y185921D01*
X333909Y185737D01*
X334086Y185561D01*
X333591Y185066D01*
X333414Y185242D01*
G37*
G36*
G01X322595Y174424D02*
X322411Y174806D01*
X322708Y175102D01*
X323090Y174919D01*
X323267Y174742D01*
X322772Y174247D01*
X322595Y174424D01*
G37*
G36*
G01X324999Y176828D02*
X324815Y177210D01*
X325112Y177507D01*
X325494Y177323D01*
X325671Y177146D01*
X325176Y176651D01*
X324999Y176828D01*
G37*
G36*
G01X323797Y175626D02*
X323613Y176008D01*
X323910Y176305D01*
X324292Y176121D01*
X324469Y175944D01*
X323974Y175449D01*
X323797Y175626D01*
G37*
G36*
G01X320191Y172020D02*
X320007Y172401D01*
X320304Y172698D01*
X320686Y172514D01*
X320863Y172338D01*
X320368Y171843D01*
X320191Y172020D01*
G37*
G36*
G01X321393Y173222D02*
X321209Y173603D01*
X321506Y173900D01*
X321888Y173717D01*
X322065Y173540D01*
X321570Y173045D01*
X321393Y173222D01*
G37*
G36*
G01X318989Y170817D02*
X318805Y171199D01*
X319102Y171496D01*
X319484Y171312D01*
X319661Y171136D01*
X319166Y170641D01*
X318989Y170817D01*
G37*
G36*
G01X334729Y187098D02*
X334329Y187237D01*
Y187658D01*
X334729Y187798D01*
X334979D01*
Y187098D01*
X334729D01*
G37*
G36*
G01X319444Y189383D02*
X319628Y189002D01*
X319331Y188705D01*
X318949Y188888D01*
X318772Y189065D01*
X319267Y189560D01*
X319444Y189383D01*
G37*
G36*
G01X320646Y190586D02*
X320830Y190204D01*
X320533Y189907D01*
X320151Y190091D01*
X319974Y190267D01*
X320469Y190762D01*
X320646Y190586D01*
G37*
G36*
G01X321848Y191788D02*
X322032Y191406D01*
X321735Y191109D01*
X321353Y191293D01*
X321176Y191469D01*
X321671Y191964D01*
X321848Y191788D01*
G37*
G36*
G01X321929Y193748D02*
X322329Y193608D01*
Y193187D01*
X321929Y193048D01*
X321679D01*
Y193748D01*
X321929D01*
G37*
G36*
G01Y195448D02*
X322329Y195308D01*
Y194887D01*
X321929Y194748D01*
X321679D01*
Y195448D01*
X321929D01*
G37*
G36*
G01X307630Y179191D02*
X307490Y178791D01*
X307070D01*
X306930Y179191D01*
Y179441D01*
X307630D01*
Y179191D01*
G37*
G36*
G01X305930D02*
X305790Y178791D01*
X305370D01*
X305230Y179191D01*
Y179441D01*
X305930D01*
Y179191D01*
G37*
G36*
G01X303536Y178775D02*
X304031Y178209D01*
X303748Y177927D01*
X303182Y178422D01*
X303041Y178563D01*
X303395Y178917D01*
X303536Y178775D01*
G37*
G36*
G01X311029Y180969D02*
X311213Y180587D01*
X310916Y180290D01*
X310534Y180474D01*
X310358Y180651D01*
X310853Y181146D01*
X311029Y180969D01*
G37*
G36*
G01X309827Y179767D02*
X310011Y179385D01*
X309714Y179088D01*
X309332Y179272D01*
X309156Y179449D01*
X309651Y179944D01*
X309827Y179767D01*
G37*
G36*
G01X313434Y183373D02*
X313617Y182991D01*
X313320Y182694D01*
X312939Y182878D01*
X312762Y183055D01*
X313257Y183550D01*
X313434Y183373D01*
G37*
G36*
G01X312232Y182171D02*
X312415Y181789D01*
X312118Y181492D01*
X311737Y181676D01*
X311560Y181853D01*
X312055Y182348D01*
X312232Y182171D01*
G37*
G36*
G01X294240Y177742D02*
X294190Y176992D01*
X293790D01*
X293740Y177742D01*
Y177992D01*
X294240D01*
Y177742D01*
G37*
G36*
G01X299540D02*
X299490Y176992D01*
X299090D01*
X299040Y177742D01*
Y177992D01*
X299540D01*
Y177742D01*
G37*
G36*
G01X302140D02*
X302090Y176992D01*
X301690D01*
X301640Y177742D01*
Y177992D01*
X302140D01*
Y177742D01*
G37*
G36*
G01X296940D02*
X296890Y176992D01*
X296490D01*
X296440Y177742D01*
Y177992D01*
X296940D01*
Y177742D01*
G37*
G36*
G01X314636Y184575D02*
X314820Y184193D01*
X314523Y183896D01*
X314141Y184080D01*
X313964Y184257D01*
X314459Y184752D01*
X314636Y184575D01*
G37*
G36*
G01X315838Y185777D02*
X316022Y185395D01*
X315725Y185098D01*
X315343Y185282D01*
X315166Y185459D01*
X315661Y185954D01*
X315838Y185777D01*
G37*
G36*
G01X318242Y188181D02*
X318426Y187800D01*
X318129Y187503D01*
X317747Y187686D01*
X317570Y187863D01*
X318065Y188358D01*
X318242Y188181D01*
G37*
G36*
G01X317040Y186979D02*
X317224Y186597D01*
X316927Y186300D01*
X316545Y186484D01*
X316368Y186661D01*
X316863Y187156D01*
X317040Y186979D01*
G37*
G36*
G01X318306Y210250D02*
X317636Y210600D01*
Y211470D01*
X318306Y211820D01*
X318481D01*
Y210250D01*
X318306D01*
G37*
G36*
G01X322750Y214168D02*
X322283Y214763D01*
X322641Y215556D01*
X323396Y215599D01*
X323556Y215526D01*
X322908Y214096D01*
X322750Y214168D01*
G37*
G36*
G01X320116Y188924D02*
X319932Y189306D01*
X320229Y189603D01*
X320611Y189419D01*
X320752Y189277D01*
X320257Y188782D01*
X320116Y188924D01*
G37*
G36*
G01X321495Y189737D02*
X321679Y189355D01*
X321382Y189058D01*
X321000Y189242D01*
X320858Y189383D01*
X321353Y189878D01*
X321495Y189737D01*
G37*
G36*
G01X321318Y190126D02*
X321134Y190508D01*
X321431Y190805D01*
X321813Y190621D01*
X321954Y190479D01*
X321459Y189984D01*
X321318Y190126D01*
G37*
G36*
G01X322729Y193898D02*
X322329Y194037D01*
Y194458D01*
X322729Y194598D01*
X322929D01*
Y193898D01*
X322729D01*
G37*
G36*
G01Y192198D02*
X322329Y192337D01*
Y192758D01*
X322729Y192898D01*
X322929D01*
Y192198D01*
X322729D01*
G37*
G36*
G01X322697Y190939D02*
X322881Y190557D01*
X322584Y190260D01*
X322202Y190444D01*
X322060Y190585D01*
X322555Y191080D01*
X322697Y190939D01*
G37*
G36*
G01X323129Y193748D02*
X323529Y193608D01*
Y193187D01*
X323129Y193048D01*
X322929D01*
Y193748D01*
X323129D01*
G37*
G36*
G01X322729Y195598D02*
X322329Y195737D01*
Y196158D01*
X322729Y196298D01*
X322929D01*
Y195598D01*
X322729D01*
G37*
G36*
G01X323129Y195448D02*
X323529Y195308D01*
Y194887D01*
X323129Y194748D01*
X322929D01*
Y195448D01*
X323129D01*
G37*
G36*
G01X307630Y177991D02*
X307490Y177591D01*
X307070D01*
X306930Y177991D01*
Y178191D01*
X307630D01*
Y177991D01*
G37*
G36*
G01X307780Y178391D02*
X307920Y178791D01*
X308340D01*
X308480Y178391D01*
Y178191D01*
X307780D01*
Y178391D01*
G37*
G36*
G01X306080D02*
X306220Y178791D01*
X306640D01*
X306780Y178391D01*
Y178191D01*
X306080D01*
Y178391D01*
G37*
G36*
G01X309330Y177991D02*
X309190Y177591D01*
X308770D01*
X308630Y177991D01*
Y178191D01*
X309330D01*
Y177991D01*
G37*
G36*
G01X305930D02*
X305790Y177591D01*
X305370D01*
X305230Y177991D01*
Y178191D01*
X305930D01*
Y177991D01*
G37*
G36*
G01X310676Y178918D02*
X310860Y178536D01*
X310563Y178239D01*
X310181Y178423D01*
X310040Y178565D01*
X310535Y179060D01*
X310676Y178918D01*
G37*
G36*
G01X310499Y179307D02*
X310315Y179689D01*
X310612Y179986D01*
X310994Y179802D01*
X311136Y179661D01*
X310641Y179166D01*
X310499Y179307D01*
G37*
G36*
G01X311878Y180120D02*
X312062Y179738D01*
X311765Y179441D01*
X311383Y179625D01*
X311242Y179767D01*
X311737Y180262D01*
X311878Y180120D01*
G37*
G36*
G01X314282Y182524D02*
X314466Y182143D01*
X314169Y181846D01*
X313787Y182029D01*
X313646Y182171D01*
X314141Y182666D01*
X314282Y182524D01*
G37*
G36*
G01X313080Y181322D02*
X313264Y180940D01*
X312967Y180643D01*
X312585Y180827D01*
X312444Y180969D01*
X312939Y181464D01*
X313080Y181322D01*
G37*
G36*
G01X312903Y181711D02*
X312720Y182093D01*
X313017Y182390D01*
X313398Y182206D01*
X313540Y182065D01*
X313045Y181570D01*
X312903Y181711D01*
G37*
G36*
G01X311701Y180509D02*
X311517Y180891D01*
X311814Y181188D01*
X312196Y181004D01*
X312338Y180863D01*
X311843Y180368D01*
X311701Y180509D01*
G37*
G36*
G01X294240Y176192D02*
X294190Y175442D01*
X293790D01*
X293740Y176192D01*
Y176392D01*
X294240D01*
Y176192D01*
G37*
G36*
G01X300340Y176592D02*
X300390Y177342D01*
X300790D01*
X300840Y176592D01*
Y176392D01*
X300340D01*
Y176592D01*
G37*
G36*
G01X299540Y176192D02*
X299490Y175442D01*
X299090D01*
X299040Y176192D01*
Y176392D01*
X299540D01*
Y176192D01*
G37*
G36*
G01X295140Y176592D02*
X295190Y177342D01*
X295590D01*
X295640Y176592D01*
Y176392D01*
X295140D01*
Y176592D01*
G37*
G36*
G01X296940Y176192D02*
X296890Y175442D01*
X296490D01*
X296440Y176192D01*
Y176392D01*
X296940D01*
Y176192D01*
G37*
G36*
G01X304633Y177678D02*
X305128Y177112D01*
X304845Y176830D01*
X304279Y177325D01*
X304138Y177466D01*
X304492Y177820D01*
X304633Y177678D01*
G37*
G36*
G01X303076Y176686D02*
X302581Y177252D01*
X302864Y177535D01*
X303430Y177040D01*
X303571Y176898D01*
X303218Y176545D01*
X303076Y176686D01*
G37*
G36*
G01X302140Y176192D02*
X302090Y175442D01*
X301690D01*
X301640Y176192D01*
Y176392D01*
X302140D01*
Y176192D01*
G37*
G36*
G01X297740Y176592D02*
X297790Y177342D01*
X298190D01*
X298240Y176592D01*
Y176392D01*
X297740D01*
Y176592D01*
G37*
G36*
G01X315484Y183726D02*
X315668Y183345D01*
X315371Y183048D01*
X314989Y183232D01*
X314848Y183373D01*
X315343Y183868D01*
X315484Y183726D01*
G37*
G36*
G01X314105Y182913D02*
X313922Y183295D01*
X314219Y183592D01*
X314600Y183408D01*
X314742Y183267D01*
X314247Y182772D01*
X314105Y182913D01*
G37*
G36*
G01X315308Y184115D02*
X315124Y184497D01*
X315421Y184794D01*
X315803Y184610D01*
X315944Y184469D01*
X315449Y183974D01*
X315308Y184115D01*
G37*
G36*
G01X316510Y185317D02*
X316326Y185699D01*
X316623Y185996D01*
X317005Y185812D01*
X317146Y185671D01*
X316651Y185176D01*
X316510Y185317D01*
G37*
G36*
G01X316686Y184929D02*
X316870Y184547D01*
X316573Y184250D01*
X316191Y184434D01*
X316050Y184575D01*
X316545Y185070D01*
X316686Y184929D01*
G37*
G36*
G01X317888Y186131D02*
X318072Y185749D01*
X317775Y185452D01*
X317394Y185636D01*
X317252Y185777D01*
X317747Y186272D01*
X317888Y186131D01*
G37*
G36*
G01X320293Y188535D02*
X320477Y188153D01*
X320180Y187856D01*
X319798Y188040D01*
X319656Y188181D01*
X320151Y188676D01*
X320293Y188535D01*
G37*
G36*
G01X318914Y187722D02*
X318730Y188103D01*
X319027Y188400D01*
X319409Y188217D01*
X319550Y188075D01*
X319055Y187580D01*
X318914Y187722D01*
G37*
G36*
G01X319091Y187333D02*
X319274Y186951D01*
X318977Y186654D01*
X318596Y186838D01*
X318454Y186979D01*
X318949Y187474D01*
X319091Y187333D01*
G37*
G36*
G01X317712Y186520D02*
X317528Y186901D01*
X317825Y187198D01*
X318207Y187015D01*
X318348Y186873D01*
X317853Y186378D01*
X317712Y186520D01*
G37*
G36*
G01X323129Y192048D02*
X323529Y191908D01*
Y191487D01*
X323129Y191348D01*
X322929D01*
Y192048D01*
X323129D01*
G37*
G36*
G01X321366Y209143D02*
X320846Y208594D01*
X320009Y208831D01*
X319855Y209571D01*
X319904Y209740D01*
X321414Y209310D01*
X321366Y209143D01*
G37*
G36*
G01X331129Y193898D02*
X330729Y194037D01*
Y194458D01*
X331129Y194598D01*
X331329D01*
Y193898D01*
X331129D01*
G37*
G36*
G01Y188798D02*
X330729Y188937D01*
Y189358D01*
X331129Y189498D01*
X331329D01*
Y188798D01*
X331129D01*
G37*
G36*
G01X331529Y192048D02*
X331929Y191908D01*
Y191487D01*
X331529Y191348D01*
X331329D01*
Y192048D01*
X331529D01*
G37*
G36*
G01Y190348D02*
X331929Y190208D01*
Y189787D01*
X331529Y189648D01*
X331329D01*
Y190348D01*
X331529D01*
G37*
G36*
G01Y193748D02*
X331929Y193608D01*
Y193187D01*
X331529Y193048D01*
X331329D01*
Y193748D01*
X331529D01*
G37*
G36*
G01X331129Y192198D02*
X330729Y192337D01*
Y192758D01*
X331129Y192898D01*
X331329D01*
Y192198D01*
X331129D01*
G37*
G36*
G01Y190498D02*
X330729Y190637D01*
Y191058D01*
X331129Y191198D01*
X331329D01*
Y190498D01*
X331129D01*
G37*
G36*
G01Y195598D02*
X330729Y195737D01*
Y196158D01*
X331129Y196298D01*
X331329D01*
Y195598D01*
X331129D01*
G37*
G36*
G01X331529Y195448D02*
X331929Y195308D01*
Y194887D01*
X331529Y194748D01*
X331329D01*
Y195448D01*
X331529D01*
G37*
G36*
G01X308630Y166321D02*
X309125Y165755D01*
X308843Y165472D01*
X308277Y165967D01*
X308135Y166108D01*
X308489Y166462D01*
X308630Y166321D01*
G37*
G36*
G01X307310Y165342D02*
X307260Y164592D01*
X306860D01*
X306810Y165342D01*
Y165542D01*
X307310D01*
Y165342D01*
G37*
G36*
G01X305540Y165742D02*
X305590Y166492D01*
X305990D01*
X306040Y165742D01*
Y165542D01*
X305540D01*
Y165742D01*
G37*
G36*
G01X304740Y165342D02*
X304690Y164592D01*
X304290D01*
X304240Y165342D01*
Y165542D01*
X304740D01*
Y165342D01*
G37*
G36*
G01X308915Y167171D02*
X308420Y167736D01*
X308703Y168019D01*
X309268Y167524D01*
X309410Y167383D01*
X309056Y167029D01*
X308915Y167171D01*
G37*
G36*
G01X310470Y168161D02*
X310965Y167595D01*
X310683Y167312D01*
X310117Y167807D01*
X309975Y167948D01*
X310329Y168302D01*
X310470Y168161D01*
G37*
G36*
G01X310755Y169011D02*
X310260Y169576D01*
X310543Y169859D01*
X311108Y169364D01*
X311250Y169223D01*
X310896Y168869D01*
X310755Y169011D01*
G37*
G36*
G01X315240Y172162D02*
X315056Y172544D01*
X315353Y172841D01*
X315735Y172657D01*
X315877Y172516D01*
X315382Y172021D01*
X315240Y172162D01*
G37*
G36*
G01X314038Y170960D02*
X313854Y171342D01*
X314151Y171639D01*
X314533Y171455D01*
X314674Y171313D01*
X314179Y170818D01*
X314038Y170960D01*
G37*
G36*
G01X315417Y171773D02*
X315601Y171391D01*
X315304Y171094D01*
X314922Y171278D01*
X314781Y171420D01*
X315275Y171914D01*
X315417Y171773D01*
G37*
G36*
G01X314215Y170571D02*
X314399Y170189D01*
X314102Y169892D01*
X313720Y170076D01*
X313579Y170218D01*
X314073Y170712D01*
X314215Y170571D01*
G37*
G36*
G01X312730Y169591D02*
X312590Y169191D01*
X312170D01*
X312030Y169591D01*
Y169791D01*
X312730D01*
Y169591D01*
G37*
G36*
G01X316619Y172975D02*
X316803Y172593D01*
X316506Y172296D01*
X316124Y172480D01*
X315983Y172622D01*
X316478Y173117D01*
X316619Y172975D01*
G37*
G36*
G01X318846Y175768D02*
X318663Y176150D01*
X318960Y176447D01*
X319341Y176263D01*
X319483Y176122D01*
X318988Y175627D01*
X318846Y175768D01*
G37*
G36*
G01X317644Y174566D02*
X317460Y174948D01*
X317757Y175245D01*
X318139Y175061D01*
X318281Y174920D01*
X317786Y174425D01*
X317644Y174566D01*
G37*
G36*
G01X319023Y175379D02*
X319207Y174997D01*
X318910Y174700D01*
X318528Y174884D01*
X318387Y175026D01*
X318882Y175521D01*
X319023Y175379D01*
G37*
G36*
G01X316442Y173364D02*
X316258Y173746D01*
X316555Y174043D01*
X316937Y173859D01*
X317079Y173718D01*
X316584Y173223D01*
X316442Y173364D01*
G37*
G36*
G01X317821Y174177D02*
X318005Y173795D01*
X317708Y173498D01*
X317326Y173682D01*
X317185Y173824D01*
X317680Y174319D01*
X317821Y174177D01*
G37*
G36*
G01X320048Y176970D02*
X319865Y177352D01*
X320162Y177649D01*
X320543Y177465D01*
X320685Y177324D01*
X320190Y176829D01*
X320048Y176970D01*
G37*
G36*
G01X321251Y178172D02*
X321067Y178554D01*
X321364Y178851D01*
X321746Y178667D01*
X321887Y178526D01*
X321392Y178031D01*
X321251Y178172D01*
G37*
G36*
G01X321427Y177783D02*
X321611Y177402D01*
X321314Y177105D01*
X320932Y177289D01*
X320791Y177430D01*
X321286Y177925D01*
X321427Y177783D01*
G37*
G36*
G01X320225Y176581D02*
X320409Y176200D01*
X320112Y175903D01*
X319730Y176086D01*
X319589Y176228D01*
X320084Y176723D01*
X320225Y176581D01*
G37*
G36*
G01X326059Y182981D02*
X325875Y183363D01*
X326172Y183660D01*
X326554Y183476D01*
X326695Y183334D01*
X326200Y182839D01*
X326059Y182981D01*
G37*
G36*
G01X327438Y183794D02*
X327622Y183412D01*
X327325Y183115D01*
X326943Y183299D01*
X326801Y183440D01*
X327296Y183935D01*
X327438Y183794D01*
G37*
G36*
G01X327261Y184183D02*
X327077Y184565D01*
X327374Y184862D01*
X327756Y184678D01*
X327897Y184536D01*
X327402Y184041D01*
X327261Y184183D01*
G37*
G36*
G01X328640Y184996D02*
X328824Y184614D01*
X328527Y184317D01*
X328145Y184501D01*
X328003Y184642D01*
X328498Y185137D01*
X328640Y184996D01*
G37*
G36*
G01X322453Y179374D02*
X322269Y179756D01*
X322566Y180053D01*
X322948Y179869D01*
X323089Y179728D01*
X322594Y179233D01*
X322453Y179374D01*
G37*
G36*
G01X322629Y178986D02*
X322813Y178604D01*
X322516Y178307D01*
X322134Y178491D01*
X321993Y178632D01*
X322488Y179127D01*
X322629Y178986D01*
G37*
G36*
G01X323655Y180577D02*
X323471Y180958D01*
X323768Y181255D01*
X324150Y181072D01*
X324291Y180930D01*
X323796Y180435D01*
X323655Y180577D01*
G37*
G36*
G01X324857Y181779D02*
X324673Y182160D01*
X324970Y182457D01*
X325352Y182274D01*
X325493Y182132D01*
X324998Y181637D01*
X324857Y181779D01*
G37*
G36*
G01X323831Y180188D02*
X324015Y179806D01*
X323718Y179509D01*
X323337Y179693D01*
X323195Y179834D01*
X323690Y180329D01*
X323831Y180188D01*
G37*
G36*
G01X325034Y181390D02*
X325217Y181008D01*
X324920Y180711D01*
X324539Y180895D01*
X324397Y181036D01*
X324892Y181531D01*
X325034Y181390D01*
G37*
G36*
G01X326236Y182592D02*
X326420Y182210D01*
X326123Y181913D01*
X325741Y182097D01*
X325599Y182238D01*
X326094Y182733D01*
X326236Y182592D01*
G37*
G36*
G01X329842Y186198D02*
X330026Y185816D01*
X329729Y185519D01*
X329347Y185703D01*
X329206Y185845D01*
X329700Y186339D01*
X329842Y186198D01*
G37*
G36*
G01X328463Y185385D02*
X328279Y185767D01*
X328576Y186064D01*
X328958Y185880D01*
X329099Y185738D01*
X328604Y185243D01*
X328463Y185385D01*
G37*
G36*
G01X331044Y187400D02*
X331228Y187018D01*
X330931Y186721D01*
X330549Y186905D01*
X330408Y187047D01*
X330902Y187541D01*
X331044Y187400D01*
G37*
G36*
G01X329665Y186587D02*
X329481Y186969D01*
X329778Y187266D01*
X330160Y187082D01*
X330302Y186941D01*
X329807Y186446D01*
X329665Y186587D01*
G37*
G36*
G01X331529Y188648D02*
X331929Y188508D01*
Y188087D01*
X331529Y187948D01*
X331329D01*
Y188648D01*
X331529D01*
G37*
G36*
G01X331834Y206420D02*
X331164Y206772D01*
X331167Y207642D01*
X331838Y207990D01*
X332013Y207989D01*
X332009Y206420D01*
X331834D01*
G37*
G36*
G01X333450Y209894D02*
X334120Y209544D01*
Y208674D01*
X333450Y208324D01*
X333275D01*
Y209894D01*
X333450D01*
G37*
G36*
G01X332699Y213814D02*
X333369Y213464D01*
Y212594D01*
X332699Y212244D01*
X332524D01*
Y213814D01*
X332699D01*
G37*
G36*
G01X332729Y190348D02*
X333129Y190208D01*
Y189787D01*
X332729Y189648D01*
X332529D01*
Y190348D01*
X332729D01*
G37*
G36*
G01Y192048D02*
X333129Y191908D01*
Y191487D01*
X332729Y191348D01*
X332529D01*
Y192048D01*
X332729D01*
G37*
G36*
G01Y193748D02*
X333129Y193608D01*
Y193187D01*
X332729Y193048D01*
X332529D01*
Y193748D01*
X332729D01*
G37*
G36*
G01X332329Y190498D02*
X331929Y190637D01*
Y191058D01*
X332329Y191198D01*
X332529D01*
Y190498D01*
X332329D01*
G37*
G36*
G01Y188798D02*
X331929Y188937D01*
Y189358D01*
X332329Y189498D01*
X332529D01*
Y188798D01*
X332329D01*
G37*
G36*
G01Y192198D02*
X331929Y192337D01*
Y192758D01*
X332329Y192898D01*
X332529D01*
Y192198D01*
X332329D01*
G37*
G36*
G01Y193898D02*
X331929Y194037D01*
Y194458D01*
X332329Y194598D01*
X332529D01*
Y193898D01*
X332329D01*
G37*
G36*
G01X332729Y195448D02*
X333129Y195308D01*
Y194887D01*
X332729Y194748D01*
X332529D01*
Y195448D01*
X332729D01*
G37*
G36*
G01X332329Y195598D02*
X331929Y195737D01*
Y196158D01*
X332329Y196298D01*
X332529D01*
Y195598D01*
X332329D01*
G37*
G36*
G01X307340Y163792D02*
X307290Y163042D01*
X306890D01*
X306840Y163792D01*
Y163992D01*
X307340D01*
Y163792D01*
G37*
G36*
G01X308171Y164235D02*
X307676Y164800D01*
X307959Y165083D01*
X308524Y164588D01*
X308666Y164447D01*
X308312Y164093D01*
X308171Y164235D01*
G37*
G36*
G01X309728Y165226D02*
X310223Y164660D01*
X309940Y164378D01*
X309374Y164873D01*
X309233Y165014D01*
X309587Y165368D01*
X309728Y165226D01*
G37*
G36*
G01X310011Y166075D02*
X309516Y166640D01*
X309799Y166923D01*
X310364Y166428D01*
X310506Y166287D01*
X310152Y165933D01*
X310011Y166075D01*
G37*
G36*
G01X311566Y167065D02*
X312061Y166499D01*
X311779Y166216D01*
X311213Y166711D01*
X311071Y166852D01*
X311425Y167206D01*
X311566Y167065D01*
G37*
G36*
G01X314887Y170111D02*
X314703Y170493D01*
X315000Y170790D01*
X315382Y170606D01*
X315523Y170464D01*
X315028Y169969D01*
X314887Y170111D01*
G37*
G36*
G01X315064Y169722D02*
X315248Y169340D01*
X314951Y169043D01*
X314569Y169227D01*
X314427Y169368D01*
X314922Y169863D01*
X315064Y169722D01*
G37*
G36*
G01X312880Y168791D02*
X313020Y169191D01*
X313440D01*
X313580Y168791D01*
Y168591D01*
X312880D01*
Y168791D01*
G37*
G36*
G01X311851Y167915D02*
X311356Y168480D01*
X311639Y168763D01*
X312204Y168268D01*
X312346Y168127D01*
X311992Y167773D01*
X311851Y167915D01*
G37*
G36*
G01X316266Y170924D02*
X316450Y170542D01*
X316153Y170245D01*
X315771Y170429D01*
X315630Y170571D01*
X316124Y171065D01*
X316266Y170924D01*
G37*
G36*
G01X317291Y172515D02*
X317107Y172897D01*
X317404Y173194D01*
X317786Y173010D01*
X317928Y172869D01*
X317433Y172374D01*
X317291Y172515D01*
G37*
G36*
G01X318670Y173328D02*
X318854Y172946D01*
X318557Y172649D01*
X318175Y172833D01*
X318034Y172975D01*
X318529Y173470D01*
X318670Y173328D01*
G37*
G36*
G01X317468Y172126D02*
X317652Y171744D01*
X317355Y171447D01*
X316973Y171631D01*
X316832Y171773D01*
X317327Y172268D01*
X317468Y172126D01*
G37*
G36*
G01X316089Y171313D02*
X315905Y171695D01*
X316202Y171992D01*
X316584Y171808D01*
X316726Y171667D01*
X316231Y171172D01*
X316089Y171313D01*
G37*
G36*
G01X318493Y173717D02*
X318309Y174099D01*
X318606Y174396D01*
X318988Y174212D01*
X319130Y174071D01*
X318635Y173576D01*
X318493Y173717D01*
G37*
G36*
G01X319695Y174919D02*
X319512Y175301D01*
X319809Y175598D01*
X320190Y175414D01*
X320332Y175273D01*
X319837Y174778D01*
X319695Y174919D01*
G37*
G36*
G01X319872Y174530D02*
X320056Y174148D01*
X319759Y173851D01*
X319377Y174035D01*
X319236Y174177D01*
X319731Y174672D01*
X319872Y174530D01*
G37*
G36*
G01X321074Y175732D02*
X321258Y175351D01*
X320961Y175054D01*
X320579Y175237D01*
X320438Y175379D01*
X320933Y175874D01*
X321074Y175732D01*
G37*
G36*
G01X320897Y176121D02*
X320714Y176503D01*
X321011Y176800D01*
X321392Y176616D01*
X321534Y176475D01*
X321039Y175980D01*
X320897Y176121D01*
G37*
G36*
G01X329312Y184536D02*
X329128Y184918D01*
X329425Y185215D01*
X329807Y185031D01*
X329948Y184889D01*
X329453Y184394D01*
X329312Y184536D01*
G37*
G36*
G01X330691Y185349D02*
X330875Y184967D01*
X330578Y184670D01*
X330196Y184854D01*
X330055Y184996D01*
X330549Y185490D01*
X330691Y185349D01*
G37*
G36*
G01X330514Y185738D02*
X330330Y186120D01*
X330627Y186417D01*
X331009Y186233D01*
X331151Y186092D01*
X330656Y185597D01*
X330514Y185738D01*
G37*
G36*
G01X328287Y182945D02*
X328471Y182563D01*
X328174Y182266D01*
X327792Y182450D01*
X327650Y182591D01*
X328145Y183086D01*
X328287Y182945D01*
G37*
G36*
G01X329489Y184147D02*
X329673Y183765D01*
X329376Y183468D01*
X328994Y183652D01*
X328852Y183793D01*
X329347Y184288D01*
X329489Y184147D01*
G37*
G36*
G01X326908Y182132D02*
X326724Y182514D01*
X327021Y182811D01*
X327403Y182627D01*
X327544Y182485D01*
X327049Y181990D01*
X326908Y182132D01*
G37*
G36*
G01X328110Y183334D02*
X327926Y183716D01*
X328223Y184013D01*
X328605Y183829D01*
X328746Y183687D01*
X328251Y183192D01*
X328110Y183334D01*
G37*
G36*
G01X325883Y180541D02*
X326066Y180159D01*
X325769Y179862D01*
X325388Y180046D01*
X325246Y180187D01*
X325741Y180682D01*
X325883Y180541D01*
G37*
G36*
G01X327085Y181743D02*
X327269Y181361D01*
X326972Y181064D01*
X326590Y181248D01*
X326448Y181389D01*
X326943Y181884D01*
X327085Y181743D01*
G37*
G36*
G01X323302Y178525D02*
X323118Y178907D01*
X323415Y179204D01*
X323797Y179020D01*
X323938Y178879D01*
X323443Y178384D01*
X323302Y178525D01*
G37*
G36*
G01X324504Y179728D02*
X324320Y180109D01*
X324617Y180406D01*
X324999Y180223D01*
X325140Y180081D01*
X324645Y179586D01*
X324504Y179728D01*
G37*
G36*
G01X325706Y180930D02*
X325522Y181311D01*
X325819Y181608D01*
X326201Y181425D01*
X326342Y181283D01*
X325847Y180788D01*
X325706Y180930D01*
G37*
G36*
G01X323478Y178137D02*
X323662Y177755D01*
X323365Y177458D01*
X322983Y177642D01*
X322842Y177783D01*
X323337Y178278D01*
X323478Y178137D01*
G37*
G36*
G01X324680Y179339D02*
X324864Y178957D01*
X324567Y178660D01*
X324186Y178844D01*
X324044Y178985D01*
X324539Y179480D01*
X324680Y179339D01*
G37*
G36*
G01X322100Y177323D02*
X321916Y177705D01*
X322213Y178002D01*
X322595Y177818D01*
X322736Y177677D01*
X322241Y177182D01*
X322100Y177323D01*
G37*
G36*
G01X322276Y176934D02*
X322460Y176553D01*
X322163Y176256D01*
X321781Y176440D01*
X321640Y176581D01*
X322135Y177076D01*
X322276Y176934D01*
G37*
G36*
G01X331893Y186551D02*
X332077Y186169D01*
X331780Y185872D01*
X331398Y186056D01*
X331257Y186198D01*
X331752Y186693D01*
X331893Y186551D01*
G37*
G36*
G01X332729Y188648D02*
X333129Y188508D01*
Y188087D01*
X332729Y187948D01*
X332529D01*
Y188648D01*
X332729D01*
G37*
G36*
G01X331716Y186940D02*
X331532Y187322D01*
X331829Y187619D01*
X332211Y187435D01*
X332353Y187294D01*
X331858Y186799D01*
X331716Y186940D01*
G37*
G36*
G01X305540Y164192D02*
X305590Y164942D01*
X305990D01*
X306040Y164192D01*
Y163992D01*
X305540D01*
Y164192D01*
G37*
G36*
G01X304736Y402418D02*
X304354Y402234D01*
X304057Y402531D01*
X304241Y402913D01*
X304383Y403054D01*
X304878Y402559D01*
X304736Y402418D01*
G37*
G36*
G01X297063Y402651D02*
X297203Y403051D01*
X297623D01*
X297763Y402651D01*
Y402401D01*
X297063D01*
Y402651D01*
G37*
G36*
G01X295363D02*
X295503Y403051D01*
X295923D01*
X296063Y402651D01*
Y402401D01*
X295363D01*
Y402651D01*
G37*
G36*
G01X293663D02*
X293803Y403051D01*
X294223D01*
X294363Y402651D01*
Y402401D01*
X293663D01*
Y402651D01*
G37*
G36*
G01X329458Y402601D02*
X329058Y402741D01*
Y403161D01*
X329458Y403301D01*
X329658D01*
Y402601D01*
X329458D01*
G37*
G36*
G01X329858Y402451D02*
X330258Y402311D01*
Y401891D01*
X329858Y401751D01*
X329658D01*
Y402451D01*
X329858D01*
G37*
G36*
G01X329458Y400901D02*
X329058Y401041D01*
Y401461D01*
X329458Y401601D01*
X329658D01*
Y400901D01*
X329458D01*
G37*
G36*
G01Y399201D02*
X329058Y399341D01*
Y399761D01*
X329458Y399901D01*
X329658D01*
Y399201D01*
X329458D01*
G37*
G36*
G01Y397501D02*
X329058Y397641D01*
Y398061D01*
X329458Y398201D01*
X329658D01*
Y397501D01*
X329458D01*
G37*
G36*
G01X329858Y399051D02*
X330258Y398911D01*
Y398491D01*
X329858Y398351D01*
X329658D01*
Y399051D01*
X329858D01*
G37*
G36*
G01Y397351D02*
X330258Y397211D01*
Y396791D01*
X329858Y396651D01*
X329658D01*
Y397351D01*
X329858D01*
G37*
G36*
G01Y400751D02*
X330258Y400611D01*
Y400191D01*
X329858Y400051D01*
X329658D01*
Y400751D01*
X329858D01*
G37*
G36*
G01X329458Y395801D02*
X329058Y395941D01*
Y396361D01*
X329458Y396501D01*
X329658D01*
Y395801D01*
X329458D01*
G37*
G36*
G01X331058Y402451D02*
X331458Y402311D01*
Y401891D01*
X331058Y401751D01*
X330858D01*
Y402451D01*
X331058D01*
G37*
G36*
G01X330658Y402601D02*
X330258Y402741D01*
Y403161D01*
X330658Y403301D01*
X330858D01*
Y402601D01*
X330658D01*
G37*
G36*
G01Y399201D02*
X330258Y399341D01*
Y399761D01*
X330658Y399901D01*
X330858D01*
Y399201D01*
X330658D01*
G37*
G36*
G01Y397501D02*
X330258Y397641D01*
Y398061D01*
X330658Y398201D01*
X330858D01*
Y397501D01*
X330658D01*
G37*
G36*
G01X331058Y399051D02*
X331458Y398911D01*
Y398491D01*
X331058Y398351D01*
X330858D01*
Y399051D01*
X331058D01*
G37*
G36*
G01Y397351D02*
X331458Y397211D01*
Y396791D01*
X331058Y396651D01*
X330858D01*
Y397351D01*
X331058D01*
G37*
G36*
G01Y400751D02*
X331458Y400611D01*
Y400191D01*
X331058Y400051D01*
X330858D01*
Y400751D01*
X331058D01*
G37*
G36*
G01X330658Y395801D02*
X330258Y395941D01*
Y396361D01*
X330658Y396501D01*
X330858D01*
Y395801D01*
X330658D01*
G37*
G36*
G01Y400901D02*
X330258Y401041D01*
Y401461D01*
X330658Y401601D01*
X330858D01*
Y400901D01*
X330658D01*
G37*
G36*
G01X328658Y402451D02*
X329058Y402311D01*
Y401891D01*
X328658Y401751D01*
X328458D01*
Y402451D01*
X328658D01*
G37*
G36*
G01X328258Y402601D02*
X327858Y402741D01*
Y403161D01*
X328258Y403301D01*
X328458D01*
Y402601D01*
X328258D01*
G37*
G36*
G01Y400901D02*
X327858Y401041D01*
Y401461D01*
X328258Y401601D01*
X328458D01*
Y400901D01*
X328258D01*
G37*
G36*
G01X328658Y399051D02*
X329058Y398911D01*
Y398491D01*
X328658Y398351D01*
X328458D01*
Y399051D01*
X328658D01*
G37*
G36*
G01Y397351D02*
X329058Y397211D01*
Y396791D01*
X328658Y396651D01*
X328458D01*
Y397351D01*
X328658D01*
G37*
G36*
G01Y400751D02*
X329058Y400611D01*
Y400191D01*
X328658Y400051D01*
X328458D01*
Y400751D01*
X328658D01*
G37*
G36*
G01X328258Y395801D02*
X327858Y395941D01*
Y396361D01*
X328258Y396501D01*
X328458D01*
Y395801D01*
X328258D01*
G37*
G36*
G01Y399201D02*
X327858Y399341D01*
Y399761D01*
X328258Y399901D01*
X328458D01*
Y399201D01*
X328258D01*
G37*
G36*
G01Y397501D02*
X327858Y397641D01*
Y398061D01*
X328258Y398201D01*
X328458D01*
Y397501D01*
X328258D01*
G37*
G36*
G01X332258Y402451D02*
X332658Y402311D01*
Y401891D01*
X332258Y401751D01*
X332058D01*
Y402451D01*
X332258D01*
G37*
G36*
G01X331858Y402601D02*
X331458Y402741D01*
Y403161D01*
X331858Y403301D01*
X332058D01*
Y402601D01*
X331858D01*
G37*
G36*
G01Y399201D02*
X331458Y399341D01*
Y399761D01*
X331858Y399901D01*
X332058D01*
Y399201D01*
X331858D01*
G37*
G36*
G01Y397501D02*
X331458Y397641D01*
Y398061D01*
X331858Y398201D01*
X332058D01*
Y397501D01*
X331858D01*
G37*
G36*
G01X332258Y399051D02*
X332658Y398911D01*
Y398491D01*
X332258Y398351D01*
X332058D01*
Y399051D01*
X332258D01*
G37*
G36*
G01Y397351D02*
X332658Y397211D01*
Y396791D01*
X332258Y396651D01*
X332058D01*
Y397351D01*
X332258D01*
G37*
G36*
G01Y400751D02*
X332658Y400611D01*
Y400191D01*
X332258Y400051D01*
X332058D01*
Y400751D01*
X332258D01*
G37*
G36*
G01X331858Y395801D02*
X331458Y395941D01*
Y396361D01*
X331858Y396501D01*
X332058D01*
Y395801D01*
X331858D01*
G37*
G36*
G01Y400901D02*
X331458Y401041D01*
Y401461D01*
X331858Y401601D01*
X332058D01*
Y400901D01*
X331858D01*
G37*
G36*
G01X326258Y402451D02*
X326658Y402311D01*
Y401891D01*
X326258Y401751D01*
X326058D01*
Y402451D01*
X326258D01*
G37*
G36*
G01X325858Y402601D02*
X325458Y402741D01*
Y403161D01*
X325858Y403301D01*
X326058D01*
Y402601D01*
X325858D01*
G37*
G36*
G01Y400901D02*
X325458Y401041D01*
Y401461D01*
X325858Y401601D01*
X326058D01*
Y400901D01*
X325858D01*
G37*
G36*
G01X326258Y399051D02*
X326658Y398911D01*
Y398491D01*
X326258Y398351D01*
X326058D01*
Y399051D01*
X326258D01*
G37*
G36*
G01Y397351D02*
X326658Y397211D01*
Y396791D01*
X326258Y396651D01*
X326058D01*
Y397351D01*
X326258D01*
G37*
G36*
G01Y400751D02*
X326658Y400611D01*
Y400191D01*
X326258Y400051D01*
X326058D01*
Y400751D01*
X326258D01*
G37*
G36*
G01X325858Y397501D02*
X325458Y397641D01*
Y398061D01*
X325858Y398201D01*
X326058D01*
Y397501D01*
X325858D01*
G37*
G36*
G01X327058Y402601D02*
X326658Y402741D01*
Y403161D01*
X327058Y403301D01*
X327258D01*
Y402601D01*
X327058D01*
G37*
G36*
G01X327458Y402451D02*
X327858Y402311D01*
Y401891D01*
X327458Y401751D01*
X327258D01*
Y402451D01*
X327458D01*
G37*
G36*
G01X327058Y400901D02*
X326658Y401041D01*
Y401461D01*
X327058Y401601D01*
X327258D01*
Y400901D01*
X327058D01*
G37*
G36*
G01Y397501D02*
X326658Y397641D01*
Y398061D01*
X327058Y398201D01*
X327258D01*
Y397501D01*
X327058D01*
G37*
G36*
G01Y399201D02*
X326658Y399341D01*
Y399761D01*
X327058Y399901D01*
X327258D01*
Y399201D01*
X327058D01*
G37*
G36*
G01X327458Y399051D02*
X327858Y398911D01*
Y398491D01*
X327458Y398351D01*
X327258D01*
Y399051D01*
X327458D01*
G37*
G36*
G01Y397351D02*
X327858Y397211D01*
Y396791D01*
X327458Y396651D01*
X327258D01*
Y397351D01*
X327458D01*
G37*
G36*
G01Y400751D02*
X327858Y400611D01*
Y400191D01*
X327458Y400051D01*
X327258D01*
Y400751D01*
X327458D01*
G37*
G36*
G01X327058Y395801D02*
X326658Y395941D01*
Y396361D01*
X327058Y396501D01*
X327258D01*
Y395801D01*
X327058D01*
G37*
G36*
G01X335458Y402601D02*
X335058Y402741D01*
Y403161D01*
X335458Y403301D01*
X335658D01*
Y402601D01*
X335458D01*
G37*
G36*
G01X335858Y402451D02*
X336258Y402311D01*
Y401891D01*
X335858Y401751D01*
X335658D01*
Y402451D01*
X335858D01*
G37*
G36*
G01X335458Y400901D02*
X335058Y401041D01*
Y401461D01*
X335458Y401601D01*
X335658D01*
Y400901D01*
X335458D01*
G37*
G36*
G01Y399201D02*
X335058Y399341D01*
Y399761D01*
X335458Y399901D01*
X335658D01*
Y399201D01*
X335458D01*
G37*
G36*
G01Y397501D02*
X335058Y397641D01*
Y398061D01*
X335458Y398201D01*
X335658D01*
Y397501D01*
X335458D01*
G37*
G36*
G01X335858Y400751D02*
X336258Y400611D01*
Y400191D01*
X335858Y400051D01*
X335658D01*
Y400751D01*
X335858D01*
G37*
G36*
G01Y399051D02*
X336258Y398911D01*
Y398491D01*
X335858Y398351D01*
X335658D01*
Y399051D01*
X335858D01*
G37*
G36*
G01Y397351D02*
X336258Y397211D01*
Y396791D01*
X335858Y396651D01*
X335658D01*
Y397351D01*
X335858D01*
G37*
G36*
G01X335458Y395801D02*
X335058Y395941D01*
Y396361D01*
X335458Y396501D01*
X335658D01*
Y395801D01*
X335458D01*
G37*
G36*
G01X336658Y402601D02*
X336258Y402741D01*
Y403161D01*
X336658Y403301D01*
X336908D01*
Y402601D01*
X336658D01*
G37*
G36*
G01Y400901D02*
X336258Y401041D01*
Y401461D01*
X336658Y401601D01*
X336908D01*
Y400901D01*
X336658D01*
G37*
G36*
G01Y399201D02*
X336258Y399341D01*
Y399761D01*
X336658Y399901D01*
X336908D01*
Y399201D01*
X336658D01*
G37*
G36*
G01Y397501D02*
X336258Y397641D01*
Y398061D01*
X336658Y398201D01*
X336908D01*
Y397501D01*
X336658D01*
G37*
G36*
G01Y395801D02*
X336258Y395941D01*
Y396361D01*
X336658Y396501D01*
X336908D01*
Y395801D01*
X336658D01*
G37*
G36*
G01X321686Y387749D02*
X321016Y388099D01*
Y388969D01*
X321686Y389319D01*
X321861D01*
Y387749D01*
X321686D01*
G37*
G36*
G01X323973Y382712D02*
X323335Y382307D01*
X322582Y382742D01*
X322614Y383497D01*
X322701Y383649D01*
X324061Y382863D01*
X323973Y382712D01*
G37*
G36*
G01X333458Y402451D02*
X333858Y402311D01*
Y401891D01*
X333458Y401751D01*
X333258D01*
Y402451D01*
X333458D01*
G37*
G36*
G01X333058Y402601D02*
X332658Y402741D01*
Y403161D01*
X333058Y403301D01*
X333258D01*
Y402601D01*
X333058D01*
G37*
G36*
G01Y395801D02*
X332658Y395941D01*
Y396361D01*
X333058Y396501D01*
X333258D01*
Y395801D01*
X333058D01*
G37*
G36*
G01Y400901D02*
X332658Y401041D01*
Y401461D01*
X333058Y401601D01*
X333258D01*
Y400901D01*
X333058D01*
G37*
G36*
G01Y399201D02*
X332658Y399341D01*
Y399761D01*
X333058Y399901D01*
X333258D01*
Y399201D01*
X333058D01*
G37*
G36*
G01Y397501D02*
X332658Y397641D01*
Y398061D01*
X333058Y398201D01*
X333258D01*
Y397501D01*
X333058D01*
G37*
G36*
G01X333458Y400751D02*
X333858Y400611D01*
Y400191D01*
X333458Y400051D01*
X333258D01*
Y400751D01*
X333458D01*
G37*
G36*
G01Y399051D02*
X333858Y398911D01*
Y398491D01*
X333458Y398351D01*
X333258D01*
Y399051D01*
X333458D01*
G37*
G36*
G01Y397351D02*
X333858Y397211D01*
Y396791D01*
X333458Y396651D01*
X333258D01*
Y397351D01*
X333458D01*
G37*
G36*
G01X334258Y402601D02*
X333858Y402741D01*
Y403161D01*
X334258Y403301D01*
X334458D01*
Y402601D01*
X334258D01*
G37*
G36*
G01X334658Y402451D02*
X335058Y402311D01*
Y401891D01*
X334658Y401751D01*
X334458D01*
Y402451D01*
X334658D01*
G37*
G36*
G01X334258Y400901D02*
X333858Y401041D01*
Y401461D01*
X334258Y401601D01*
X334458D01*
Y400901D01*
X334258D01*
G37*
G36*
G01Y399201D02*
X333858Y399341D01*
Y399761D01*
X334258Y399901D01*
X334458D01*
Y399201D01*
X334258D01*
G37*
G36*
G01Y397501D02*
X333858Y397641D01*
Y398061D01*
X334258Y398201D01*
X334458D01*
Y397501D01*
X334258D01*
G37*
G36*
G01X334658Y400751D02*
X335058Y400611D01*
Y400191D01*
X334658Y400051D01*
X334458D01*
Y400751D01*
X334658D01*
G37*
G36*
G01Y399051D02*
X335058Y398911D01*
Y398491D01*
X334658Y398351D01*
X334458D01*
Y399051D01*
X334658D01*
G37*
G36*
G01Y397351D02*
X335058Y397211D01*
Y396791D01*
X334658Y396651D01*
X334458D01*
Y397351D01*
X334658D01*
G37*
G36*
G01X334258Y395801D02*
X333858Y395941D01*
Y396361D01*
X334258Y396501D01*
X334458D01*
Y395801D01*
X334258D01*
G37*
G36*
G01X295363Y405051D02*
X295503Y405451D01*
X295923D01*
X296063Y405051D01*
Y404851D01*
X295363D01*
Y405051D01*
G37*
G36*
G01X293663D02*
X293803Y405451D01*
X294223D01*
X294363Y405051D01*
Y404851D01*
X293663D01*
Y405051D01*
G37*
G36*
G01X297063D02*
X297203Y405451D01*
X297623D01*
X297763Y405051D01*
Y404851D01*
X297063D01*
Y405051D01*
G37*
G36*
G01X295213Y404651D02*
X295073Y404251D01*
X294653D01*
X294513Y404651D01*
Y404851D01*
X295213D01*
Y404651D01*
G37*
G36*
G01X293513D02*
X293373Y404251D01*
X292953D01*
X292813Y404651D01*
Y404851D01*
X293513D01*
Y404651D01*
G37*
G36*
G01X296913D02*
X296773Y404251D01*
X296353D01*
X296213Y404651D01*
Y404851D01*
X296913D01*
Y404651D01*
G37*
G36*
G01X298613D02*
X298473Y404251D01*
X298053D01*
X297913Y404651D01*
Y404851D01*
X298613D01*
Y404651D01*
G37*
G36*
G01X298763Y405051D02*
X298903Y405451D01*
X299323D01*
X299463Y405051D01*
Y404851D01*
X298763D01*
Y405051D01*
G37*
G36*
G01X300463D02*
X300603Y405451D01*
X301023D01*
X301163Y405051D01*
Y404851D01*
X300463D01*
Y405051D01*
G37*
G36*
G01X300313Y404651D02*
X300173Y404251D01*
X299753D01*
X299613Y404651D01*
Y404851D01*
X300313D01*
Y404651D01*
G37*
G36*
G01X302013D02*
X301873Y404251D01*
X301453D01*
X301313Y404651D01*
Y404851D01*
X302013D01*
Y404651D01*
G37*
G36*
G01X303923Y403797D02*
X304305Y403981D01*
X304602Y403684D01*
X304418Y403302D01*
X304276Y403161D01*
X303782Y403655D01*
X303923Y403797D01*
G37*
G36*
G01X302721Y404999D02*
X303103Y405183D01*
X303400Y404886D01*
X303216Y404504D01*
X303074Y404363D01*
X302580Y404857D01*
X302721Y404999D01*
G37*
G36*
G01X297063Y406251D02*
X297203Y406651D01*
X297623D01*
X297763Y406251D01*
Y406051D01*
X297063D01*
Y406251D01*
G37*
G36*
G01X295363D02*
X295503Y406651D01*
X295923D01*
X296063Y406251D01*
Y406051D01*
X295363D01*
Y406251D01*
G37*
G36*
G01X293663D02*
X293803Y406651D01*
X294223D01*
X294363Y406251D01*
Y406051D01*
X293663D01*
Y406251D01*
G37*
G36*
G01X298613Y405851D02*
X298473Y405451D01*
X298053D01*
X297913Y405851D01*
Y406051D01*
X298613D01*
Y405851D01*
G37*
G36*
G01X296913D02*
X296773Y405451D01*
X296353D01*
X296213Y405851D01*
Y406051D01*
X296913D01*
Y405851D01*
G37*
G36*
G01X295213D02*
X295073Y405451D01*
X294653D01*
X294513Y405851D01*
Y406051D01*
X295213D01*
Y405851D01*
G37*
G36*
G01X293513D02*
X293373Y405451D01*
X292953D01*
X292813Y405851D01*
Y406051D01*
X293513D01*
Y405851D01*
G37*
G36*
G01X298763Y406251D02*
X298903Y406651D01*
X299323D01*
X299463Y406251D01*
Y406051D01*
X298763D01*
Y406251D01*
G37*
G36*
G01X300463D02*
X300603Y406651D01*
X301023D01*
X301163Y406251D01*
Y406051D01*
X300463D01*
Y406251D01*
G37*
G36*
G01X300313Y405851D02*
X300173Y405451D01*
X299753D01*
X299613Y405851D01*
Y406051D01*
X300313D01*
Y405851D01*
G37*
G36*
G01X302013D02*
X301873Y405451D01*
X301453D01*
X301313Y405851D01*
Y406051D01*
X302013D01*
Y405851D01*
G37*
G36*
G01X305585Y403267D02*
X305203Y403083D01*
X304906Y403380D01*
X305090Y403762D01*
X305232Y403903D01*
X305727Y403408D01*
X305585Y403267D01*
G37*
G36*
G01X304383Y404469D02*
X304001Y404285D01*
X303704Y404582D01*
X303888Y404964D01*
X304029Y405106D01*
X304524Y404611D01*
X304383Y404469D01*
G37*
G36*
G01X304772Y404646D02*
X305154Y404830D01*
X305451Y404533D01*
X305267Y404151D01*
X305125Y404010D01*
X304631Y404504D01*
X304772Y404646D01*
G37*
G36*
G01X305974Y403444D02*
X306356Y403628D01*
X306653Y403331D01*
X306469Y402949D01*
X306328Y402807D01*
X305833Y403302D01*
X305974Y403444D01*
G37*
G36*
G01X303570Y405848D02*
X303952Y406032D01*
X304249Y405735D01*
X304065Y405353D01*
X303923Y405212D01*
X303429Y405706D01*
X303570Y405848D01*
G37*
G36*
G01X302163Y406251D02*
X302303Y406651D01*
X302723D01*
X302863Y406251D01*
Y406051D01*
X302163D01*
Y406251D01*
G37*
G36*
G01X297063Y414651D02*
X297203Y415051D01*
X297623D01*
X297763Y414651D01*
Y414451D01*
X297063D01*
Y414651D01*
G37*
G36*
G01X298613Y414251D02*
X298473Y413851D01*
X298053D01*
X297913Y414251D01*
Y414451D01*
X298613D01*
Y414251D01*
G37*
G36*
G01X294368Y415520D02*
X293986Y415336D01*
X293689Y415633D01*
X293873Y416015D01*
X294014Y416157D01*
X294509Y415662D01*
X294368Y415520D01*
G37*
G36*
G01X293555Y416899D02*
X293937Y417083D01*
X294234Y416786D01*
X294050Y416404D01*
X293908Y416263D01*
X293413Y416758D01*
X293555Y416899D01*
G37*
G36*
G01X294757Y415697D02*
X295139Y415881D01*
X295436Y415584D01*
X295252Y415202D01*
X295110Y415061D01*
X294615Y415556D01*
X294757Y415697D01*
G37*
G36*
G01X296913Y414251D02*
X296773Y413851D01*
X296353D01*
X296213Y414251D01*
Y414451D01*
X296913D01*
Y414251D01*
G37*
G36*
G01X298763Y414651D02*
X298903Y415051D01*
X299323D01*
X299463Y414651D01*
Y414451D01*
X298763D01*
Y414651D01*
G37*
G36*
G01X300463D02*
X300603Y415051D01*
X301023D01*
X301163Y414651D01*
Y414451D01*
X300463D01*
Y414651D01*
G37*
G36*
G01X300313Y414251D02*
X300173Y413851D01*
X299753D01*
X299613Y414251D01*
Y414451D01*
X300313D01*
Y414251D01*
G37*
G36*
G01X302013D02*
X301873Y413851D01*
X301453D01*
X301313Y414251D01*
Y414451D01*
X302013D01*
Y414251D01*
G37*
G36*
G01X303713D02*
X303573Y413851D01*
X303153D01*
X303013Y414251D01*
Y414451D01*
X303713D01*
Y414251D01*
G37*
G36*
G01X307922Y412816D02*
X307540Y412632D01*
X307243Y412929D01*
X307427Y413311D01*
X307568Y413453D01*
X308063Y412958D01*
X307922Y412816D01*
G37*
G36*
G01X307109Y414195D02*
X307491Y414379D01*
X307788Y414082D01*
X307604Y413700D01*
X307462Y413559D01*
X306967Y414054D01*
X307109Y414195D01*
G37*
G36*
G01X303863Y414651D02*
X304003Y415051D01*
X304423D01*
X304563Y414651D01*
Y414451D01*
X303863D01*
Y414651D01*
G37*
G36*
G01X305413Y414251D02*
X305273Y413851D01*
X304853D01*
X304713Y414251D01*
Y414451D01*
X305413D01*
Y414251D01*
G37*
G36*
G01X305563Y414651D02*
X305703Y415051D01*
X306123D01*
X306263Y414651D01*
Y414451D01*
X305563D01*
Y414651D01*
G37*
G36*
G01X309124Y411614D02*
X308742Y411430D01*
X308445Y411727D01*
X308629Y412109D01*
X308770Y412251D01*
X309265Y411756D01*
X309124Y411614D01*
G37*
G36*
G01X310326Y410412D02*
X309944Y410228D01*
X309647Y410525D01*
X309831Y410907D01*
X309972Y411049D01*
X310467Y410554D01*
X310326Y410412D01*
G37*
G36*
G01X311528Y409210D02*
X311146Y409026D01*
X310849Y409323D01*
X311033Y409705D01*
X311175Y409846D01*
X311670Y409351D01*
X311528Y409210D01*
G37*
G36*
G01X309513Y411791D02*
X309895Y411975D01*
X310192Y411678D01*
X310008Y411296D01*
X309866Y411155D01*
X309371Y411650D01*
X309513Y411791D01*
G37*
G36*
G01X308311Y412993D02*
X308693Y413177D01*
X308990Y412880D01*
X308806Y412498D01*
X308664Y412357D01*
X308169Y412852D01*
X308311Y412993D01*
G37*
G36*
G01X310715Y410589D02*
X311097Y410773D01*
X311394Y410476D01*
X311210Y410094D01*
X311068Y409953D01*
X310574Y410447D01*
X310715Y410589D01*
G37*
G36*
G01X312730Y408008D02*
X312348Y407824D01*
X312051Y408121D01*
X312235Y408503D01*
X312377Y408644D01*
X312872Y408149D01*
X312730Y408008D01*
G37*
G36*
G01X313932Y406806D02*
X313550Y406622D01*
X313253Y406919D01*
X313437Y407301D01*
X313579Y407442D01*
X314074Y406947D01*
X313932Y406806D01*
G37*
G36*
G01X311917Y409387D02*
X312299Y409571D01*
X312596Y409274D01*
X312412Y408892D01*
X312271Y408750D01*
X311776Y409245D01*
X311917Y409387D01*
G37*
G36*
G01X313119Y408185D02*
X313501Y408369D01*
X313798Y408072D01*
X313614Y407690D01*
X313473Y407548D01*
X312978Y408043D01*
X313119Y408185D01*
G37*
G36*
G01X302163Y414651D02*
X302303Y415051D01*
X302723D01*
X302863Y414651D01*
Y414451D01*
X302163D01*
Y414651D01*
G37*
G36*
G01X298613Y415451D02*
X298473Y415051D01*
X298053D01*
X297913Y415451D01*
Y415701D01*
X298613D01*
Y415451D01*
G37*
G36*
G01X295217Y416369D02*
X294835Y416185D01*
X294538Y416482D01*
X294722Y416864D01*
X294898Y417041D01*
X295393Y416546D01*
X295217Y416369D01*
G37*
G36*
G01X300313Y415451D02*
X300173Y415051D01*
X299753D01*
X299613Y415451D01*
Y415701D01*
X300313D01*
Y415451D01*
G37*
G36*
G01X302013D02*
X301873Y415051D01*
X301453D01*
X301313Y415451D01*
Y415701D01*
X302013D01*
Y415451D01*
G37*
G36*
G01X303713D02*
X303573Y415051D01*
X303153D01*
X303013Y415451D01*
Y415701D01*
X303713D01*
Y415451D01*
G37*
G36*
G01X305413D02*
X305273Y415051D01*
X304853D01*
X304713Y415451D01*
Y415701D01*
X305413D01*
Y415451D01*
G37*
G36*
G01X307569Y414867D02*
X307187Y414683D01*
X306890Y414980D01*
X307074Y415362D01*
X307250Y415539D01*
X307745Y415044D01*
X307569Y414867D01*
G37*
G36*
G01X294014Y417571D02*
X293633Y417387D01*
X293336Y417684D01*
X293519Y418066D01*
X293696Y418243D01*
X294191Y417748D01*
X294014Y417571D01*
G37*
G36*
G01X308771Y413665D02*
X308389Y413481D01*
X308092Y413778D01*
X308276Y414160D01*
X308452Y414337D01*
X308947Y413842D01*
X308771Y413665D01*
G37*
G36*
G01X309973Y412463D02*
X309591Y412279D01*
X309294Y412576D01*
X309478Y412958D01*
X309654Y413135D01*
X310149Y412640D01*
X309973Y412463D01*
G37*
G36*
G01X311175Y411261D02*
X310793Y411077D01*
X310496Y411374D01*
X310680Y411756D01*
X310856Y411933D01*
X311351Y411438D01*
X311175Y411261D01*
G37*
G36*
G01X312377Y410059D02*
X311995Y409875D01*
X311698Y410172D01*
X311882Y410554D01*
X312059Y410730D01*
X312554Y410235D01*
X312377Y410059D01*
G37*
G36*
G01X313579Y408857D02*
X313197Y408673D01*
X312900Y408970D01*
X313084Y409352D01*
X313261Y409528D01*
X313756Y409033D01*
X313579Y408857D01*
G37*
G36*
G01X314781Y407655D02*
X314399Y407471D01*
X314102Y407768D01*
X314286Y408150D01*
X314463Y408326D01*
X314958Y407831D01*
X314781Y407655D01*
G37*
G36*
G01X296913Y415451D02*
X296773Y415051D01*
X296353D01*
X296213Y415451D01*
Y415701D01*
X296913D01*
Y415451D01*
G37*
G36*
G01X295213Y403451D02*
X295073Y403051D01*
X294653D01*
X294513Y403451D01*
Y403651D01*
X295213D01*
Y403451D01*
G37*
G36*
G01X293513D02*
X293373Y403051D01*
X292953D01*
X292813Y403451D01*
Y403651D01*
X293513D01*
Y403451D01*
G37*
G36*
G01X296913D02*
X296773Y403051D01*
X296353D01*
X296213Y403451D01*
Y403651D01*
X296913D01*
Y403451D01*
G37*
G36*
G01X293663Y403851D02*
X293803Y404251D01*
X294223D01*
X294363Y403851D01*
Y403651D01*
X293663D01*
Y403851D01*
G37*
G36*
G01X295363D02*
X295503Y404251D01*
X295923D01*
X296063Y403851D01*
Y403651D01*
X295363D01*
Y403851D01*
G37*
G36*
G01X297063D02*
X297203Y404251D01*
X297623D01*
X297763Y403851D01*
Y403651D01*
X297063D01*
Y403851D01*
G37*
G36*
G01X298763D02*
X298903Y404251D01*
X299323D01*
X299463Y403851D01*
Y403651D01*
X298763D01*
Y403851D01*
G37*
G36*
G01X306224Y411118D02*
X305842Y410934D01*
X305545Y411231D01*
X305729Y411613D01*
X305870Y411755D01*
X306365Y411260D01*
X306224Y411118D01*
G37*
G36*
G01X307426Y409916D02*
X307044Y409732D01*
X306747Y410029D01*
X306931Y410411D01*
X307072Y410553D01*
X307567Y410058D01*
X307426Y409916D01*
G37*
G36*
G01X293872Y412620D02*
X293490Y412436D01*
X293193Y412733D01*
X293377Y413115D01*
X293518Y413257D01*
X294013Y412762D01*
X293872Y412620D01*
G37*
G36*
G01X293059Y413999D02*
X293441Y414183D01*
X293738Y413886D01*
X293554Y413504D01*
X293412Y413363D01*
X292917Y413858D01*
X293059Y413999D01*
G37*
G36*
G01X294261Y412797D02*
X294643Y412981D01*
X294940Y412684D01*
X294756Y412302D01*
X294614Y412161D01*
X294119Y412656D01*
X294261Y412797D01*
G37*
G36*
G01X297063Y412251D02*
X297203Y412651D01*
X297623D01*
X297763Y412251D01*
Y412051D01*
X297063D01*
Y412251D01*
G37*
G36*
G01X295363D02*
X295503Y412651D01*
X295923D01*
X296063Y412251D01*
Y412051D01*
X295363D01*
Y412251D01*
G37*
G36*
G01X298613Y411851D02*
X298473Y411451D01*
X298053D01*
X297913Y411851D01*
Y412051D01*
X298613D01*
Y411851D01*
G37*
G36*
G01X296913D02*
X296773Y411451D01*
X296353D01*
X296213Y411851D01*
Y412051D01*
X296913D01*
Y411851D01*
G37*
G36*
G01X300313D02*
X300173Y411451D01*
X299753D01*
X299613Y411851D01*
Y412051D01*
X300313D01*
Y411851D01*
G37*
G36*
G01X302013D02*
X301873Y411451D01*
X301453D01*
X301313Y411851D01*
Y412051D01*
X302013D01*
Y411851D01*
G37*
G36*
G01X303713D02*
X303573Y411451D01*
X303153D01*
X303013Y411851D01*
Y412051D01*
X303713D01*
Y411851D01*
G37*
G36*
G01X298763Y412251D02*
X298903Y412651D01*
X299323D01*
X299463Y412251D01*
Y412051D01*
X298763D01*
Y412251D01*
G37*
G36*
G01X300463D02*
X300603Y412651D01*
X301023D01*
X301163Y412251D01*
Y412051D01*
X300463D01*
Y412251D01*
G37*
G36*
G01X306613Y411295D02*
X306995Y411479D01*
X307292Y411182D01*
X307108Y410800D01*
X306966Y410659D01*
X306471Y411154D01*
X306613Y411295D01*
G37*
G36*
G01X303863Y412251D02*
X304003Y412651D01*
X304423D01*
X304563Y412251D01*
Y412051D01*
X303863D01*
Y412251D01*
G37*
G36*
G01X308628Y408714D02*
X308246Y408530D01*
X307949Y408827D01*
X308133Y409209D01*
X308274Y409351D01*
X308769Y408856D01*
X308628Y408714D01*
G37*
G36*
G01X309830Y407512D02*
X309448Y407328D01*
X309151Y407625D01*
X309335Y408007D01*
X309477Y408148D01*
X309972Y407653D01*
X309830Y407512D01*
G37*
G36*
G01X311032Y406310D02*
X310650Y406126D01*
X310353Y406423D01*
X310537Y406805D01*
X310679Y406946D01*
X311174Y406451D01*
X311032Y406310D01*
G37*
G36*
G01X307815Y410093D02*
X308197Y410277D01*
X308494Y409980D01*
X308310Y409598D01*
X308168Y409457D01*
X307673Y409952D01*
X307815Y410093D01*
G37*
G36*
G01X309017Y408891D02*
X309399Y409075D01*
X309696Y408778D01*
X309512Y408396D01*
X309370Y408255D01*
X308876Y408749D01*
X309017Y408891D01*
G37*
G36*
G01X310219Y407689D02*
X310601Y407873D01*
X310898Y407576D01*
X310714Y407194D01*
X310573Y407052D01*
X310078Y407547D01*
X310219Y407689D01*
G37*
G36*
G01X311421Y406487D02*
X311803Y406671D01*
X312100Y406374D01*
X311916Y405992D01*
X311775Y405850D01*
X311280Y406345D01*
X311421Y406487D01*
G37*
G36*
G01X302163Y412251D02*
X302303Y412651D01*
X302723D01*
X302863Y412251D01*
Y412051D01*
X302163D01*
Y412251D01*
G37*
G36*
G01X297063Y413451D02*
X297203Y413851D01*
X297623D01*
X297763Y413451D01*
Y413251D01*
X297063D01*
Y413451D01*
G37*
G36*
G01X298613Y413051D02*
X298473Y412651D01*
X298053D01*
X297913Y413051D01*
Y413251D01*
X298613D01*
Y413051D01*
G37*
G36*
G01X296913D02*
X296773Y412651D01*
X296353D01*
X296213Y413051D01*
Y413251D01*
X296913D01*
Y413051D01*
G37*
G36*
G01X293519Y414671D02*
X293137Y414487D01*
X292840Y414784D01*
X293024Y415166D01*
X293165Y415308D01*
X293660Y414813D01*
X293519Y414671D01*
G37*
G36*
G01X294721Y413469D02*
X294339Y413285D01*
X294042Y413582D01*
X294226Y413964D01*
X294367Y414106D01*
X294862Y413611D01*
X294721Y413469D01*
G37*
G36*
G01X293908Y414848D02*
X294290Y415032D01*
X294587Y414735D01*
X294403Y414353D01*
X294261Y414212D01*
X293766Y414707D01*
X293908Y414848D01*
G37*
G36*
G01X295363Y413451D02*
X295503Y413851D01*
X295923D01*
X296063Y413451D01*
Y413251D01*
X295363D01*
Y413451D01*
G37*
G36*
G01X300463D02*
X300603Y413851D01*
X301023D01*
X301163Y413451D01*
Y413251D01*
X300463D01*
Y413451D01*
G37*
G36*
G01X298763D02*
X298903Y413851D01*
X299323D01*
X299463Y413451D01*
Y413251D01*
X298763D01*
Y413451D01*
G37*
G36*
G01X303713Y413051D02*
X303573Y412651D01*
X303153D01*
X303013Y413051D01*
Y413251D01*
X303713D01*
Y413051D01*
G37*
G36*
G01X302013D02*
X301873Y412651D01*
X301453D01*
X301313Y413051D01*
Y413251D01*
X302013D01*
Y413051D01*
G37*
G36*
G01X300313D02*
X300173Y412651D01*
X299753D01*
X299613Y413051D01*
Y413251D01*
X300313D01*
Y413051D01*
G37*
G36*
G01X303863Y413451D02*
X304003Y413851D01*
X304423D01*
X304563Y413451D01*
Y413251D01*
X303863D01*
Y413451D01*
G37*
G36*
G01X305413Y413051D02*
X305273Y412651D01*
X304853D01*
X304713Y413051D01*
Y413251D01*
X305413D01*
Y413051D01*
G37*
G36*
G01X306260Y413346D02*
X306642Y413530D01*
X306939Y413233D01*
X306755Y412851D01*
X306613Y412710D01*
X306118Y413205D01*
X306260Y413346D01*
G37*
G36*
G01X307073Y411967D02*
X306691Y411783D01*
X306394Y412080D01*
X306578Y412462D01*
X306719Y412604D01*
X307214Y412109D01*
X307073Y411967D01*
G37*
G36*
G01X307462Y412144D02*
X307844Y412328D01*
X308141Y412031D01*
X307957Y411649D01*
X307815Y411508D01*
X307320Y412003D01*
X307462Y412144D01*
G37*
G36*
G01X310679Y408361D02*
X310297Y408177D01*
X310000Y408474D01*
X310184Y408856D01*
X310326Y408997D01*
X310821Y408502D01*
X310679Y408361D01*
G37*
G36*
G01X311881Y407159D02*
X311499Y406975D01*
X311202Y407272D01*
X311386Y407654D01*
X311528Y407795D01*
X312023Y407300D01*
X311881Y407159D01*
G37*
G36*
G01X309477Y409563D02*
X309095Y409379D01*
X308798Y409676D01*
X308982Y410058D01*
X309123Y410200D01*
X309618Y409705D01*
X309477Y409563D01*
G37*
G36*
G01X308275Y410765D02*
X307893Y410581D01*
X307596Y410878D01*
X307780Y411260D01*
X307921Y411402D01*
X308416Y410907D01*
X308275Y410765D01*
G37*
G36*
G01X311068Y408538D02*
X311450Y408722D01*
X311747Y408425D01*
X311563Y408043D01*
X311422Y407901D01*
X310927Y408396D01*
X311068Y408538D01*
G37*
G36*
G01X309866Y409740D02*
X310248Y409924D01*
X310545Y409627D01*
X310361Y409245D01*
X310219Y409104D01*
X309725Y409598D01*
X309866Y409740D01*
G37*
G36*
G01X308664Y410942D02*
X309046Y411126D01*
X309343Y410829D01*
X309159Y410447D01*
X309017Y410306D01*
X308522Y410801D01*
X308664Y410942D01*
G37*
G36*
G01X313083Y405957D02*
X312701Y405773D01*
X312404Y406070D01*
X312588Y406452D01*
X312730Y406593D01*
X313225Y406098D01*
X313083Y405957D01*
G37*
G36*
G01X312270Y407336D02*
X312652Y407520D01*
X312949Y407223D01*
X312765Y406841D01*
X312624Y406699D01*
X312129Y407194D01*
X312270Y407336D01*
G37*
G36*
G01X302163Y413451D02*
X302303Y413851D01*
X302723D01*
X302863Y413451D01*
Y413251D01*
X302163D01*
Y413451D01*
G37*
G36*
G01X306470Y406344D02*
X306852Y406528D01*
X307149Y406231D01*
X306965Y405849D01*
X306823Y405708D01*
X306329Y406202D01*
X306470Y406344D01*
G37*
G36*
G01X305268Y407546D02*
X305650Y407730D01*
X305947Y407433D01*
X305763Y407051D01*
X305621Y406910D01*
X305126Y407405D01*
X305268Y407546D01*
G37*
G36*
G01X297063Y408651D02*
X297203Y409051D01*
X297623D01*
X297763Y408651D01*
Y408451D01*
X297063D01*
Y408651D01*
G37*
G36*
G01X295363D02*
X295503Y409051D01*
X295923D01*
X296063Y408651D01*
Y408451D01*
X295363D01*
Y408651D01*
G37*
G36*
G01X298613Y408251D02*
X298473Y407851D01*
X298053D01*
X297913Y408251D01*
Y408451D01*
X298613D01*
Y408251D01*
G37*
G36*
G01X296913D02*
X296773Y407851D01*
X296353D01*
X296213Y408251D01*
Y408451D01*
X296913D01*
Y408251D01*
G37*
G36*
G01X295213D02*
X295073Y407851D01*
X294653D01*
X294513Y408251D01*
Y408451D01*
X295213D01*
Y408251D01*
G37*
G36*
G01X293663Y408651D02*
X293803Y409051D01*
X294223D01*
X294363Y408651D01*
Y408451D01*
X293663D01*
Y408651D01*
G37*
G36*
G01X298763D02*
X298903Y409051D01*
X299323D01*
X299463Y408651D01*
Y408451D01*
X298763D01*
Y408651D01*
G37*
G36*
G01X300463D02*
X300603Y409051D01*
X301023D01*
X301163Y408651D01*
Y408451D01*
X300463D01*
Y408651D01*
G37*
G36*
G01X300313Y408251D02*
X300173Y407851D01*
X299753D01*
X299613Y408251D01*
Y408451D01*
X300313D01*
Y408251D01*
G37*
G36*
G01X302013D02*
X301873Y407851D01*
X301453D01*
X301313Y408251D01*
Y408451D01*
X302013D01*
Y408251D01*
G37*
G36*
G01X303713D02*
X303573Y407851D01*
X303153D01*
X303013Y408251D01*
Y408451D01*
X303713D01*
Y408251D01*
G37*
G36*
G01X307283Y404965D02*
X306901Y404781D01*
X306604Y405078D01*
X306788Y405460D01*
X306930Y405601D01*
X307425Y405106D01*
X307283Y404965D01*
G37*
G36*
G01X306081Y406167D02*
X305699Y405983D01*
X305402Y406280D01*
X305586Y406662D01*
X305727Y406804D01*
X306222Y406309D01*
X306081Y406167D01*
G37*
G36*
G01X304879Y407369D02*
X304497Y407185D01*
X304200Y407482D01*
X304384Y407864D01*
X304525Y408006D01*
X305020Y407511D01*
X304879Y407369D01*
G37*
G36*
G01X307672Y405142D02*
X308054Y405326D01*
X308351Y405029D01*
X308167Y404647D01*
X308026Y404505D01*
X307531Y405000D01*
X307672Y405142D01*
G37*
G36*
G01X302163Y408651D02*
X302303Y409051D01*
X302723D01*
X302863Y408651D01*
Y408451D01*
X302163D01*
Y408651D01*
G37*
G36*
G01X319842Y417670D02*
X319276Y417175D01*
X318994Y417458D01*
X319489Y418024D01*
X319630Y418165D01*
X319984Y417811D01*
X319842Y417670D01*
G37*
G36*
G01X320691Y417387D02*
X321256Y417882D01*
X321539Y417599D01*
X321044Y417034D01*
X320903Y416892D01*
X320549Y417246D01*
X320691Y417387D01*
G37*
G36*
G01X321681Y415832D02*
X321115Y415337D01*
X320832Y415619D01*
X321327Y416185D01*
X321468Y416327D01*
X321822Y415973D01*
X321681Y415832D01*
G37*
G36*
G01X318852Y419226D02*
X319418Y419721D01*
X319701Y419438D01*
X319206Y418872D01*
X319064Y418731D01*
X318711Y419084D01*
X318852Y419226D01*
G37*
G36*
G01X318004Y419509D02*
X317438Y419014D01*
X317155Y419296D01*
X317650Y419862D01*
X317792Y420003D01*
X318145Y419650D01*
X318004Y419509D01*
G37*
G36*
G01X317014Y421064D02*
X317579Y421559D01*
X317862Y421276D01*
X317367Y420711D01*
X317226Y420569D01*
X316872Y420923D01*
X317014Y421064D01*
G37*
G36*
G01X308660Y426663D02*
X308710Y427413D01*
X309110D01*
X309160Y426663D01*
Y426463D01*
X308660D01*
Y426663D01*
G37*
G36*
G01X310460Y426264D02*
X310410Y425514D01*
X310010D01*
X309960Y426264D01*
Y426464D01*
X310460D01*
Y426264D01*
G37*
G36*
G01X316165Y421347D02*
X315599Y420852D01*
X315317Y421135D01*
X315812Y421701D01*
X315953Y421842D01*
X316307Y421488D01*
X316165Y421347D01*
G37*
G36*
G01X313337Y424741D02*
X313902Y425236D01*
X314185Y424953D01*
X313690Y424388D01*
X313549Y424246D01*
X313195Y424600D01*
X313337Y424741D01*
G37*
G36*
G01X312488Y425024D02*
X311923Y424529D01*
X311640Y424812D01*
X312135Y425378D01*
X312276Y425519D01*
X312630Y425165D01*
X312488Y425024D01*
G37*
G36*
G01X314327Y423185D02*
X313761Y422690D01*
X313478Y422973D01*
X313973Y423539D01*
X314115Y423680D01*
X314468Y423327D01*
X314327Y423185D01*
G37*
G36*
G01X315175Y422903D02*
X315741Y423398D01*
X316024Y423115D01*
X315529Y422549D01*
X315387Y422408D01*
X315034Y422761D01*
X315175Y422903D01*
G37*
G36*
G01X311497Y426581D02*
X312062Y427076D01*
X312345Y426793D01*
X311850Y426228D01*
X311709Y426086D01*
X311355Y426440D01*
X311497Y426581D01*
G37*
G36*
G01X322529Y415549D02*
X323095Y416044D01*
X323378Y415761D01*
X322883Y415195D01*
X322741Y415054D01*
X322388Y415407D01*
X322529Y415549D01*
G37*
G36*
G01X323519Y413993D02*
X322953Y413498D01*
X322671Y413781D01*
X323166Y414347D01*
X323307Y414488D01*
X323660Y414135D01*
X323519Y413993D01*
G37*
G36*
G01X324368Y413710D02*
X324933Y414205D01*
X325216Y413922D01*
X324721Y413357D01*
X324580Y413215D01*
X324226Y413569D01*
X324368Y413710D01*
G37*
G36*
G01X326206Y411872D02*
X326772Y412367D01*
X327055Y412084D01*
X326560Y411518D01*
X326418Y411377D01*
X326065Y411730D01*
X326206Y411872D01*
G37*
G36*
G01X325358Y412155D02*
X324792Y411660D01*
X324509Y411942D01*
X325004Y412508D01*
X325145Y412650D01*
X325499Y412296D01*
X325358Y412155D01*
G37*
G36*
G01X326748Y409861D02*
X326348Y410001D01*
Y410421D01*
X326748Y410561D01*
X326948D01*
Y409861D01*
X326748D01*
G37*
G36*
G01X328198Y407833D02*
X327816Y407649D01*
X327519Y407946D01*
X327703Y408328D01*
X327844Y408469D01*
X328339Y407974D01*
X328198Y407833D01*
G37*
G36*
G01X327384Y409211D02*
X327766Y409395D01*
X328063Y409098D01*
X327879Y408716D01*
X327738Y408575D01*
X327243Y409070D01*
X327384Y409211D01*
G37*
G36*
G01X328587Y408009D02*
X328968Y408193D01*
X329265Y407896D01*
X329081Y407514D01*
X328940Y407373D01*
X328445Y407868D01*
X328587Y408009D01*
G37*
G36*
G01X329458Y404301D02*
X329058Y404441D01*
Y404861D01*
X329458Y405001D01*
X329658D01*
Y404301D01*
X329458D01*
G37*
G36*
G01X329858Y404151D02*
X330258Y404011D01*
Y403591D01*
X329858Y403451D01*
X329658D01*
Y404151D01*
X329858D01*
G37*
G36*
G01Y405851D02*
X330258Y405711D01*
Y405291D01*
X329858Y405151D01*
X329658D01*
Y405851D01*
X329858D01*
G37*
G36*
G01X297063Y409851D02*
X297203Y410251D01*
X297623D01*
X297763Y409851D01*
Y409651D01*
X297063D01*
Y409851D01*
G37*
G36*
G01X295363D02*
X295503Y410251D01*
X295923D01*
X296063Y409851D01*
Y409651D01*
X295363D01*
Y409851D01*
G37*
G36*
G01X298613Y409451D02*
X298473Y409051D01*
X298053D01*
X297913Y409451D01*
Y409651D01*
X298613D01*
Y409451D01*
G37*
G36*
G01X296913D02*
X296773Y409051D01*
X296353D01*
X296213Y409451D01*
Y409651D01*
X296913D01*
Y409451D01*
G37*
G36*
G01X295213D02*
X295073Y409051D01*
X294653D01*
X294513Y409451D01*
Y409651D01*
X295213D01*
Y409451D01*
G37*
G36*
G01X300463Y409851D02*
X300603Y410251D01*
X301023D01*
X301163Y409851D01*
Y409651D01*
X300463D01*
Y409851D01*
G37*
G36*
G01X298763D02*
X298903Y410251D01*
X299323D01*
X299463Y409851D01*
Y409651D01*
X298763D01*
Y409851D01*
G37*
G36*
G01X302013Y409451D02*
X301873Y409051D01*
X301453D01*
X301313Y409451D01*
Y409651D01*
X302013D01*
Y409451D01*
G37*
G36*
G01X303713D02*
X303573Y409051D01*
X303153D01*
X303013Y409451D01*
Y409651D01*
X303713D01*
Y409451D01*
G37*
G36*
G01X300313D02*
X300173Y409051D01*
X299753D01*
X299613Y409451D01*
Y409651D01*
X300313D01*
Y409451D01*
G37*
G36*
G01X306930Y407016D02*
X306548Y406832D01*
X306251Y407129D01*
X306435Y407511D01*
X306576Y407653D01*
X307071Y407158D01*
X306930Y407016D01*
G37*
G36*
G01X305728Y408218D02*
X305346Y408034D01*
X305049Y408331D01*
X305233Y408713D01*
X305374Y408855D01*
X305869Y408360D01*
X305728Y408218D01*
G37*
G36*
G01X307319Y407193D02*
X307701Y407377D01*
X307998Y407080D01*
X307814Y406698D01*
X307672Y406557D01*
X307178Y407051D01*
X307319Y407193D01*
G37*
G36*
G01X306117Y408395D02*
X306499Y408579D01*
X306796Y408282D01*
X306612Y407900D01*
X306470Y407759D01*
X305975Y408254D01*
X306117Y408395D01*
G37*
G36*
G01X304915Y409597D02*
X305297Y409781D01*
X305594Y409484D01*
X305410Y409102D01*
X305268Y408961D01*
X304773Y409456D01*
X304915Y409597D01*
G37*
G36*
G01X303863Y409851D02*
X304003Y410251D01*
X304423D01*
X304563Y409851D01*
Y409651D01*
X303863D01*
Y409851D01*
G37*
G36*
G01X308132Y405814D02*
X307750Y405630D01*
X307453Y405927D01*
X307637Y406309D01*
X307779Y406450D01*
X308274Y405955D01*
X308132Y405814D01*
G37*
G36*
G01X309334Y404612D02*
X308952Y404428D01*
X308655Y404725D01*
X308839Y405107D01*
X308981Y405248D01*
X309476Y404753D01*
X309334Y404612D01*
G37*
G36*
G01X308521Y405991D02*
X308903Y406175D01*
X309200Y405878D01*
X309016Y405496D01*
X308875Y405354D01*
X308380Y405849D01*
X308521Y405991D01*
G37*
G36*
G01X309723Y404789D02*
X310105Y404973D01*
X310402Y404676D01*
X310218Y404294D01*
X310077Y404152D01*
X309582Y404647D01*
X309723Y404789D01*
G37*
G36*
G01X302163Y409851D02*
X302303Y410251D01*
X302723D01*
X302863Y409851D01*
Y409651D01*
X302163D01*
Y409851D01*
G37*
G36*
G01X327948Y409861D02*
X327548Y410001D01*
Y410421D01*
X327948Y410561D01*
X328148D01*
Y409861D01*
X327948D01*
G37*
G36*
G01X330638Y407656D02*
X331019Y407840D01*
X331316Y407543D01*
X331132Y407161D01*
X330991Y407020D01*
X330496Y407515D01*
X330638Y407656D01*
G37*
G36*
G01X320938Y418766D02*
X320372Y418271D01*
X320090Y418554D01*
X320585Y419120D01*
X320726Y419261D01*
X321080Y418907D01*
X320938Y418766D01*
G37*
G36*
G01X319948Y420322D02*
X320514Y420817D01*
X320797Y420534D01*
X320302Y419968D01*
X320160Y419827D01*
X319807Y420180D01*
X319948Y420322D01*
G37*
G36*
G01X319100Y420605D02*
X318534Y420110D01*
X318251Y420392D01*
X318746Y420958D01*
X318888Y421099D01*
X319241Y420746D01*
X319100Y420605D01*
G37*
G36*
G01X312594Y427676D02*
X313160Y428171D01*
X313443Y427888D01*
X312948Y427322D01*
X312806Y427181D01*
X312453Y427534D01*
X312594Y427676D01*
G37*
G36*
G01X313584Y426120D02*
X313019Y425625D01*
X312736Y425908D01*
X313231Y426474D01*
X313372Y426615D01*
X313726Y426261D01*
X313584Y426120D01*
G37*
G36*
G01X316271Y423999D02*
X316837Y424494D01*
X317120Y424211D01*
X316625Y423645D01*
X316483Y423504D01*
X316130Y423857D01*
X316271Y423999D01*
G37*
G36*
G01X314433Y425837D02*
X314998Y426332D01*
X315281Y426049D01*
X314786Y425484D01*
X314645Y425342D01*
X314291Y425696D01*
X314433Y425837D01*
G37*
G36*
G01X315423Y424281D02*
X314857Y423786D01*
X314574Y424069D01*
X315069Y424635D01*
X315211Y424776D01*
X315564Y424423D01*
X315423Y424281D01*
G37*
G36*
G01X318110Y422160D02*
X318675Y422655D01*
X318958Y422372D01*
X318463Y421807D01*
X318322Y421665D01*
X317968Y422019D01*
X318110Y422160D01*
G37*
G36*
G01X317261Y422443D02*
X316695Y421948D01*
X316413Y422231D01*
X316908Y422797D01*
X317049Y422938D01*
X317403Y422584D01*
X317261Y422443D01*
G37*
G36*
G01X331058Y404151D02*
X331458Y404011D01*
Y403591D01*
X331058Y403451D01*
X330858D01*
Y404151D01*
X331058D01*
G37*
G36*
G01Y405851D02*
X331458Y405711D01*
Y405291D01*
X331058Y405151D01*
X330858D01*
Y405851D01*
X331058D01*
G37*
G36*
G01X321787Y418483D02*
X322352Y418978D01*
X322635Y418695D01*
X322140Y418130D01*
X321999Y417988D01*
X321645Y418342D01*
X321787Y418483D01*
G37*
G36*
G01X330658Y404301D02*
X330258Y404441D01*
Y404861D01*
X330658Y405001D01*
X330858D01*
Y404301D01*
X330658D01*
G37*
G36*
G01X322777Y416928D02*
X322211Y416433D01*
X321928Y416715D01*
X322423Y417281D01*
X322564Y417423D01*
X322918Y417069D01*
X322777Y416928D01*
G37*
G36*
G01X323625Y416645D02*
X324191Y417140D01*
X324474Y416857D01*
X323979Y416291D01*
X323837Y416150D01*
X323484Y416503D01*
X323625Y416645D01*
G37*
G36*
G01X327302Y412968D02*
X327868Y413463D01*
X328151Y413180D01*
X327656Y412614D01*
X327514Y412473D01*
X327161Y412826D01*
X327302Y412968D01*
G37*
G36*
G01X325464Y414806D02*
X326029Y415301D01*
X326312Y415018D01*
X325817Y414453D01*
X325676Y414311D01*
X325322Y414665D01*
X325464Y414806D01*
G37*
G36*
G01X326454Y413251D02*
X325888Y412756D01*
X325605Y413038D01*
X326100Y413604D01*
X326241Y413746D01*
X326595Y413392D01*
X326454Y413251D01*
G37*
G36*
G01X324615Y415089D02*
X324049Y414594D01*
X323767Y414877D01*
X324262Y415443D01*
X324403Y415584D01*
X324756Y415231D01*
X324615Y415089D01*
G37*
G36*
G01X328348Y411411D02*
X328748Y411271D01*
Y410851D01*
X328348Y410711D01*
X328148D01*
Y411411D01*
X328348D01*
G37*
G36*
G01X329047Y408682D02*
X328665Y408498D01*
X328368Y408795D01*
X328552Y409177D01*
X328693Y409318D01*
X329188Y408823D01*
X329047Y408682D01*
G37*
G36*
G01X329436Y408858D02*
X329817Y409042D01*
X330114Y408745D01*
X329930Y408363D01*
X329789Y408222D01*
X329294Y408717D01*
X329436Y408858D01*
G37*
G36*
G01X330658Y406001D02*
X330258Y406141D01*
Y406561D01*
X330658Y406701D01*
X330858D01*
Y406001D01*
X330658D01*
G37*
G36*
G01X330249Y407480D02*
X329867Y407296D01*
X329570Y407593D01*
X329754Y407975D01*
X329895Y408116D01*
X330390Y407621D01*
X330249Y407480D01*
G37*
G36*
G01X297063Y407451D02*
X297203Y407851D01*
X297623D01*
X297763Y407451D01*
Y407251D01*
X297063D01*
Y407451D01*
G37*
G36*
G01X295363D02*
X295503Y407851D01*
X295923D01*
X296063Y407451D01*
Y407251D01*
X295363D01*
Y407451D01*
G37*
G36*
G01X293663D02*
X293803Y407851D01*
X294223D01*
X294363Y407451D01*
Y407251D01*
X293663D01*
Y407451D01*
G37*
G36*
G01X296913Y407051D02*
X296773Y406651D01*
X296353D01*
X296213Y407051D01*
Y407251D01*
X296913D01*
Y407051D01*
G37*
G36*
G01X295213D02*
X295073Y406651D01*
X294653D01*
X294513Y407051D01*
Y407251D01*
X295213D01*
Y407051D01*
G37*
G36*
G01X298613D02*
X298473Y406651D01*
X298053D01*
X297913Y407051D01*
Y407251D01*
X298613D01*
Y407051D01*
G37*
G36*
G01X293513D02*
X293373Y406651D01*
X292953D01*
X292813Y407051D01*
Y407251D01*
X293513D01*
Y407051D01*
G37*
G36*
G01X298763Y407451D02*
X298903Y407851D01*
X299323D01*
X299463Y407451D01*
Y407251D01*
X298763D01*
Y407451D01*
G37*
G36*
G01X300463D02*
X300603Y407851D01*
X301023D01*
X301163Y407451D01*
Y407251D01*
X300463D01*
Y407451D01*
G37*
G36*
G01X300313Y407051D02*
X300173Y406651D01*
X299753D01*
X299613Y407051D01*
Y407251D01*
X300313D01*
Y407051D01*
G37*
G36*
G01X302013D02*
X301873Y406651D01*
X301453D01*
X301313Y407051D01*
Y407251D01*
X302013D01*
Y407051D01*
G37*
G36*
G01X305232Y405318D02*
X304850Y405134D01*
X304553Y405431D01*
X304737Y405813D01*
X304878Y405955D01*
X305373Y405460D01*
X305232Y405318D01*
G37*
G36*
G01X306434Y404116D02*
X306052Y403932D01*
X305755Y404229D01*
X305939Y404611D01*
X306081Y404752D01*
X306576Y404257D01*
X306434Y404116D01*
G37*
G36*
G01X304419Y406697D02*
X304801Y406881D01*
X305098Y406584D01*
X304914Y406202D01*
X304772Y406061D01*
X304277Y406556D01*
X304419Y406697D01*
G37*
G36*
G01X305621Y405495D02*
X306003Y405679D01*
X306300Y405382D01*
X306116Y405000D01*
X305974Y404859D01*
X305480Y405353D01*
X305621Y405495D01*
G37*
G36*
G01X306823Y404293D02*
X307205Y404477D01*
X307502Y404180D01*
X307318Y403798D01*
X307177Y403656D01*
X306682Y404151D01*
X306823Y404293D01*
G37*
G36*
G01X304030Y406520D02*
X303648Y406336D01*
X303351Y406633D01*
X303535Y407015D01*
X303676Y407157D01*
X304171Y406662D01*
X304030Y406520D01*
G37*
G36*
G01X302163Y407451D02*
X302303Y407851D01*
X302723D01*
X302863Y407451D01*
Y407251D01*
X302163D01*
Y407451D01*
G37*
G36*
G01X319595Y416291D02*
X320160Y416786D01*
X320443Y416503D01*
X319948Y415938D01*
X319807Y415796D01*
X319453Y416150D01*
X319595Y416291D01*
G37*
G36*
G01X318746Y416574D02*
X318180Y416079D01*
X317898Y416362D01*
X318393Y416928D01*
X318534Y417069D01*
X318888Y416715D01*
X318746Y416574D01*
G37*
G36*
G01X320585Y414736D02*
X320019Y414241D01*
X319736Y414523D01*
X320231Y415089D01*
X320372Y415231D01*
X320726Y414877D01*
X320585Y414736D01*
G37*
G36*
G01X317756Y418130D02*
X318322Y418625D01*
X318605Y418342D01*
X318110Y417776D01*
X317968Y417635D01*
X317615Y417988D01*
X317756Y418130D01*
G37*
G36*
G01X316908Y418413D02*
X316342Y417918D01*
X316059Y418200D01*
X316554Y418766D01*
X316696Y418907D01*
X317049Y418554D01*
X316908Y418413D01*
G37*
G36*
G01X321433Y414453D02*
X321999Y414948D01*
X322282Y414665D01*
X321787Y414099D01*
X321645Y413958D01*
X321292Y414311D01*
X321433Y414453D01*
G37*
G36*
G01X315918Y419968D02*
X316483Y420463D01*
X316766Y420180D01*
X316271Y419615D01*
X316130Y419473D01*
X315776Y419827D01*
X315918Y419968D01*
G37*
G36*
G01X315069Y420251D02*
X314503Y419756D01*
X314221Y420039D01*
X314716Y420605D01*
X314857Y420746D01*
X315211Y420392D01*
X315069Y420251D01*
G37*
G36*
G01X308660Y425113D02*
X308710Y425863D01*
X309110D01*
X309160Y425113D01*
Y424913D01*
X308660D01*
Y425113D01*
G37*
G36*
G01X311392Y423928D02*
X310827Y423433D01*
X310544Y423716D01*
X311039Y424282D01*
X311180Y424423D01*
X311534Y424069D01*
X311392Y423928D01*
G37*
G36*
G01X312241Y423645D02*
X312806Y424140D01*
X313089Y423857D01*
X312594Y423292D01*
X312453Y423150D01*
X312099Y423504D01*
X312241Y423645D01*
G37*
G36*
G01X314079Y421807D02*
X314645Y422302D01*
X314928Y422019D01*
X314433Y421453D01*
X314291Y421312D01*
X313938Y421665D01*
X314079Y421807D01*
G37*
G36*
G01X313231Y422089D02*
X312665Y421594D01*
X312382Y421877D01*
X312877Y422443D01*
X313019Y422584D01*
X313372Y422231D01*
X313231Y422089D01*
G37*
G36*
G01X322423Y412897D02*
X321857Y412402D01*
X321575Y412685D01*
X322070Y413251D01*
X322211Y413392D01*
X322564Y413039D01*
X322423Y412897D01*
G37*
G36*
G01X323272Y412614D02*
X323837Y413109D01*
X324120Y412826D01*
X323625Y412261D01*
X323484Y412119D01*
X323130Y412473D01*
X323272Y412614D01*
G37*
G36*
G01X325110Y410776D02*
X325676Y411271D01*
X325959Y410988D01*
X325464Y410422D01*
X325322Y410281D01*
X324969Y410634D01*
X325110Y410776D01*
G37*
G36*
G01X324262Y411059D02*
X323696Y410564D01*
X323413Y410846D01*
X323908Y411412D01*
X324049Y411554D01*
X324403Y411200D01*
X324262Y411059D01*
G37*
G36*
G01X327349Y406984D02*
X326967Y406800D01*
X326670Y407097D01*
X326854Y407479D01*
X326995Y407620D01*
X327490Y407125D01*
X327349Y406984D01*
G37*
G36*
G01X326535Y408362D02*
X326917Y408546D01*
X327214Y408249D01*
X327030Y407867D01*
X326889Y407726D01*
X326394Y408221D01*
X326535Y408362D01*
G37*
G36*
G01X327738Y407160D02*
X328119Y407344D01*
X328416Y407047D01*
X328232Y406665D01*
X328091Y406524D01*
X327596Y407019D01*
X327738Y407160D01*
G37*
G36*
G01X326147Y408186D02*
X325765Y408002D01*
X325468Y408299D01*
X325652Y408681D01*
X325793Y408822D01*
X326288Y408327D01*
X326147Y408186D01*
G37*
G36*
G01X325948Y409711D02*
X326348Y409571D01*
Y409151D01*
X325948Y409011D01*
X325748D01*
Y409711D01*
X325948D01*
G37*
G36*
G01X328258Y404301D02*
X327858Y404441D01*
Y404861D01*
X328258Y405001D01*
X328458D01*
Y404301D01*
X328258D01*
G37*
G36*
G01X328658Y404151D02*
X329058Y404011D01*
Y403591D01*
X328658Y403451D01*
X328458D01*
Y404151D01*
X328658D01*
G37*
G36*
G01Y405851D02*
X329058Y405711D01*
Y405291D01*
X328658Y405151D01*
X328458D01*
Y405851D01*
X328658D01*
G37*
G36*
G01X297063Y411051D02*
X297203Y411451D01*
X297623D01*
X297763Y411051D01*
Y410851D01*
X297063D01*
Y411051D01*
G37*
G36*
G01X295363D02*
X295503Y411451D01*
X295923D01*
X296063Y411051D01*
Y410851D01*
X295363D01*
Y411051D01*
G37*
G36*
G01X298613Y410651D02*
X298473Y410251D01*
X298053D01*
X297913Y410651D01*
Y410851D01*
X298613D01*
Y410651D01*
G37*
G36*
G01X296913D02*
X296773Y410251D01*
X296353D01*
X296213Y410651D01*
Y410851D01*
X296913D01*
Y410651D01*
G37*
G36*
G01X293412Y411948D02*
X293794Y412132D01*
X294091Y411835D01*
X293907Y411453D01*
X293765Y411312D01*
X293270Y411807D01*
X293412Y411948D01*
G37*
G36*
G01X295213Y410651D02*
X295073Y410251D01*
X294653D01*
X294513Y410651D01*
Y410851D01*
X295213D01*
Y410651D01*
G37*
G36*
G01X298763Y411051D02*
X298903Y411451D01*
X299323D01*
X299463Y411051D01*
Y410851D01*
X298763D01*
Y411051D01*
G37*
G36*
G01X300463D02*
X300603Y411451D01*
X301023D01*
X301163Y411051D01*
Y410851D01*
X300463D01*
Y411051D01*
G37*
G36*
G01X300313Y410651D02*
X300173Y410251D01*
X299753D01*
X299613Y410651D01*
Y410851D01*
X300313D01*
Y410651D01*
G37*
G36*
G01X302013D02*
X301873Y410251D01*
X301453D01*
X301313Y410651D01*
Y410851D01*
X302013D01*
Y410651D01*
G37*
G36*
G01X303713D02*
X303573Y410251D01*
X303153D01*
X303013Y410651D01*
Y410851D01*
X303713D01*
Y410651D01*
G37*
G36*
G01X303863Y411051D02*
X304003Y411451D01*
X304423D01*
X304563Y411051D01*
Y410851D01*
X303863D01*
Y411051D01*
G37*
G36*
G01X307779Y407865D02*
X307397Y407681D01*
X307100Y407978D01*
X307284Y408360D01*
X307425Y408502D01*
X307920Y408007D01*
X307779Y407865D01*
G37*
G36*
G01X306577Y409067D02*
X306195Y408883D01*
X305898Y409180D01*
X306082Y409562D01*
X306223Y409704D01*
X306718Y409209D01*
X306577Y409067D01*
G37*
G36*
G01X306966Y409244D02*
X307348Y409428D01*
X307645Y409131D01*
X307461Y408749D01*
X307319Y408608D01*
X306824Y409103D01*
X306966Y409244D01*
G37*
G36*
G01X305764Y410446D02*
X306146Y410630D01*
X306443Y410333D01*
X306259Y409951D01*
X306117Y409810D01*
X305622Y410305D01*
X305764Y410446D01*
G37*
G36*
G01X310572Y405638D02*
X310954Y405822D01*
X311251Y405525D01*
X311067Y405143D01*
X310926Y405001D01*
X310431Y405496D01*
X310572Y405638D01*
G37*
G36*
G01X308981Y406663D02*
X308599Y406479D01*
X308302Y406776D01*
X308486Y407158D01*
X308628Y407299D01*
X309123Y406804D01*
X308981Y406663D01*
G37*
G36*
G01X310183Y405461D02*
X309801Y405277D01*
X309504Y405574D01*
X309688Y405956D01*
X309830Y406097D01*
X310325Y405602D01*
X310183Y405461D01*
G37*
G36*
G01X308168Y408042D02*
X308550Y408226D01*
X308847Y407929D01*
X308663Y407547D01*
X308521Y407406D01*
X308027Y407900D01*
X308168Y408042D01*
G37*
G36*
G01X309370Y406840D02*
X309752Y407024D01*
X310049Y406727D01*
X309865Y406345D01*
X309724Y406203D01*
X309229Y406698D01*
X309370Y406840D01*
G37*
G36*
G01X302163Y411051D02*
X302303Y411451D01*
X302723D01*
X302863Y411051D01*
Y410851D01*
X302163D01*
Y411051D01*
G37*
G36*
G01X322034Y419862D02*
X321468Y419367D01*
X321186Y419650D01*
X321681Y420216D01*
X321822Y420357D01*
X322176Y420003D01*
X322034Y419862D01*
G37*
G36*
G01X313690Y428772D02*
X314256Y429267D01*
X314539Y428984D01*
X314044Y428418D01*
X313902Y428277D01*
X313549Y428630D01*
X313690Y428772D01*
G37*
G36*
G01X314680Y427216D02*
X314115Y426721D01*
X313832Y427004D01*
X314327Y427570D01*
X314468Y427711D01*
X314822Y427357D01*
X314680Y427216D01*
G37*
G36*
G01X315529Y426933D02*
X316094Y427428D01*
X316377Y427145D01*
X315882Y426580D01*
X315741Y426438D01*
X315387Y426792D01*
X315529Y426933D01*
G37*
G36*
G01X316519Y425377D02*
X315953Y424882D01*
X315670Y425165D01*
X316165Y425731D01*
X316307Y425872D01*
X316660Y425519D01*
X316519Y425377D01*
G37*
G36*
G01X320196Y421701D02*
X319630Y421206D01*
X319347Y421488D01*
X319842Y422054D01*
X319984Y422195D01*
X320337Y421842D01*
X320196Y421701D01*
G37*
G36*
G01X317367Y425095D02*
X317933Y425590D01*
X318216Y425307D01*
X317721Y424741D01*
X317579Y424600D01*
X317226Y424953D01*
X317367Y425095D01*
G37*
G36*
G01X319206Y423256D02*
X319771Y423751D01*
X320054Y423468D01*
X319559Y422903D01*
X319418Y422761D01*
X319064Y423115D01*
X319206Y423256D01*
G37*
G36*
G01X318357Y423539D02*
X317791Y423044D01*
X317509Y423327D01*
X318004Y423893D01*
X318145Y424034D01*
X318499Y423680D01*
X318357Y423539D01*
G37*
G36*
G01X321044Y421418D02*
X321610Y421913D01*
X321893Y421630D01*
X321398Y421064D01*
X321256Y420923D01*
X320903Y421276D01*
X321044Y421418D01*
G37*
G36*
G01X312840Y429056D02*
X312275Y428561D01*
X311992Y428844D01*
X312487Y429410D01*
X312628Y429551D01*
X312982Y429197D01*
X312840Y429056D01*
G37*
G36*
G01X332258Y404151D02*
X332658Y404011D01*
Y403591D01*
X332258Y403451D01*
X332058D01*
Y404151D01*
X332258D01*
G37*
G36*
G01Y405851D02*
X332658Y405711D01*
Y405291D01*
X332258Y405151D01*
X332058D01*
Y405851D01*
X332258D01*
G37*
G36*
G01X323873Y418024D02*
X323307Y417529D01*
X323024Y417811D01*
X323519Y418377D01*
X323660Y418519D01*
X324014Y418165D01*
X323873Y418024D01*
G37*
G36*
G01X324721Y417741D02*
X325287Y418236D01*
X325570Y417953D01*
X325075Y417387D01*
X324933Y417246D01*
X324580Y417599D01*
X324721Y417741D01*
G37*
G36*
G01X326560Y415902D02*
X327125Y416397D01*
X327408Y416114D01*
X326913Y415549D01*
X326772Y415407D01*
X326418Y415761D01*
X326560Y415902D01*
G37*
G36*
G01X325711Y416185D02*
X325145Y415690D01*
X324863Y415973D01*
X325358Y416539D01*
X325499Y416680D01*
X325852Y416327D01*
X325711Y416185D01*
G37*
G36*
G01X328398Y414064D02*
X328964Y414559D01*
X329247Y414276D01*
X328752Y413710D01*
X328610Y413569D01*
X328257Y413922D01*
X328398Y414064D01*
G37*
G36*
G01X327550Y414347D02*
X326984Y413852D01*
X326701Y414134D01*
X327196Y414700D01*
X327337Y414842D01*
X327691Y414488D01*
X327550Y414347D01*
G37*
G36*
G01X332258Y407547D02*
X332658Y407407D01*
Y406987D01*
X332258Y406847D01*
X332058D01*
Y407547D01*
X332258D01*
G37*
G36*
G01X329548Y411411D02*
X329948Y411271D01*
Y410851D01*
X329548Y410711D01*
X329348D01*
Y411411D01*
X329548D01*
G37*
G36*
G01X329148Y411561D02*
X328748Y411701D01*
Y412121D01*
X329148Y412261D01*
X329348D01*
Y411561D01*
X329148D01*
G37*
G36*
G01X331858Y406001D02*
X331458Y406141D01*
Y406561D01*
X331858Y406701D01*
X332058D01*
Y406001D01*
X331858D01*
G37*
G36*
G01X331098Y408328D02*
X330716Y408145D01*
X330419Y408442D01*
X330603Y408823D01*
X330744Y408965D01*
X331239Y408470D01*
X331098Y408328D01*
G37*
G36*
G01X330285Y409707D02*
X330666Y409891D01*
X330963Y409594D01*
X330779Y409212D01*
X330638Y409071D01*
X330143Y409566D01*
X330285Y409707D01*
G37*
G36*
G01X331487Y408505D02*
X331868Y408689D01*
X332165Y408392D01*
X331981Y408010D01*
X331840Y407869D01*
X331345Y408364D01*
X331487Y408505D01*
G37*
G36*
G01X329896Y409530D02*
X329514Y409347D01*
X329217Y409644D01*
X329401Y410025D01*
X329542Y410167D01*
X330037Y409672D01*
X329896Y409530D01*
G37*
G36*
G01X331858Y404301D02*
X331458Y404441D01*
Y404861D01*
X331858Y405001D01*
X332058D01*
Y404301D01*
X331858D01*
G37*
G36*
G01X322883Y419579D02*
X323448Y420074D01*
X323731Y419791D01*
X323236Y419226D01*
X323095Y419084D01*
X322741Y419438D01*
X322883Y419579D01*
G37*
G36*
G01X311039Y419897D02*
X310473Y419402D01*
X310190Y419685D01*
X310685Y420251D01*
X310827Y420392D01*
X311180Y420039D01*
X311039Y419897D01*
G37*
G36*
G01X313726Y417776D02*
X314291Y418271D01*
X314574Y417988D01*
X314079Y417423D01*
X313938Y417281D01*
X313584Y417635D01*
X313726Y417776D01*
G37*
G36*
G01X315564Y415938D02*
X316130Y416433D01*
X316413Y416150D01*
X315918Y415584D01*
X315776Y415443D01*
X315423Y415796D01*
X315564Y415938D01*
G37*
G36*
G01X314716Y416221D02*
X314150Y415726D01*
X313867Y416008D01*
X314362Y416574D01*
X314504Y416715D01*
X314857Y416362D01*
X314716Y416221D01*
G37*
G36*
G01X316554Y414382D02*
X315988Y413887D01*
X315706Y414170D01*
X316201Y414736D01*
X316342Y414877D01*
X316696Y414523D01*
X316554Y414382D01*
G37*
G36*
G01X317403Y414099D02*
X317968Y414594D01*
X318251Y414311D01*
X317756Y413746D01*
X317615Y413604D01*
X317261Y413958D01*
X317403Y414099D01*
G37*
G36*
G01X319241Y412261D02*
X319807Y412756D01*
X320090Y412473D01*
X319595Y411907D01*
X319453Y411766D01*
X319100Y412119D01*
X319241Y412261D01*
G37*
G36*
G01X318393Y412544D02*
X317827Y412049D01*
X317544Y412331D01*
X318039Y412897D01*
X318180Y413039D01*
X318534Y412685D01*
X318393Y412544D01*
G37*
G36*
G01X320231Y410705D02*
X319665Y410210D01*
X319383Y410493D01*
X319878Y411059D01*
X320019Y411200D01*
X320372Y410847D01*
X320231Y410705D01*
G37*
G36*
G01X312877Y418059D02*
X312311Y417564D01*
X312029Y417847D01*
X312524Y418413D01*
X312665Y418554D01*
X313019Y418200D01*
X312877Y418059D01*
G37*
G36*
G01X321080Y410422D02*
X321645Y410917D01*
X321928Y410634D01*
X321433Y410069D01*
X321292Y409927D01*
X320938Y410281D01*
X321080Y410422D01*
G37*
G36*
G01X322070Y408867D02*
X321504Y408372D01*
X321221Y408654D01*
X321716Y409220D01*
X321857Y409362D01*
X322211Y409008D01*
X322070Y408867D01*
G37*
G36*
G01X311887Y419615D02*
X312453Y420110D01*
X312736Y419827D01*
X312241Y419261D01*
X312099Y419120D01*
X311746Y419473D01*
X311887Y419615D01*
G37*
G36*
G01X307860Y421615D02*
X307810Y420865D01*
X307410D01*
X307360Y421615D01*
Y421815D01*
X307860D01*
Y421615D01*
G37*
G36*
G01X305260D02*
X305210Y420865D01*
X304810D01*
X304760Y421615D01*
Y421815D01*
X305260D01*
Y421615D01*
G37*
G36*
G01X306060Y422015D02*
X306110Y422765D01*
X306510D01*
X306560Y422015D01*
Y421815D01*
X306060D01*
Y422015D01*
G37*
G36*
G01X303460D02*
X303510Y422765D01*
X303910D01*
X303960Y422015D01*
Y421815D01*
X303460D01*
Y422015D01*
G37*
G36*
G01X310049Y421453D02*
X310614Y421948D01*
X310897Y421665D01*
X310402Y421100D01*
X310261Y420958D01*
X309907Y421312D01*
X310049Y421453D01*
G37*
G36*
G01X308660Y422015D02*
X308710Y422765D01*
X309110D01*
X309160Y422015D01*
Y421815D01*
X308660D01*
Y422015D01*
G37*
G36*
G01X323635Y407867D02*
X324017Y408050D01*
X324314Y407753D01*
X324130Y407372D01*
X323989Y407230D01*
X323494Y407725D01*
X323635Y407867D01*
G37*
G36*
G01X322918Y408584D02*
X323484Y409079D01*
X323767Y408796D01*
X323272Y408230D01*
X323130Y408089D01*
X322777Y408442D01*
X322918Y408584D01*
G37*
G36*
G01X324837Y406664D02*
X325219Y406848D01*
X325516Y406551D01*
X325332Y406169D01*
X325191Y406028D01*
X324696Y406523D01*
X324837Y406664D01*
G37*
G36*
G01X324449Y406488D02*
X324067Y406304D01*
X323770Y406601D01*
X323954Y406983D01*
X324095Y407124D01*
X324590Y406629D01*
X324449Y406488D01*
G37*
G36*
G01X325651Y405286D02*
X325269Y405102D01*
X324972Y405399D01*
X325156Y405781D01*
X325297Y405922D01*
X325792Y405427D01*
X325651Y405286D01*
G37*
G36*
G01X326258Y404151D02*
X326658Y404011D01*
Y403591D01*
X326258Y403451D01*
X326058D01*
Y404151D01*
X326258D01*
G37*
G36*
G01X315812Y417317D02*
X315246Y416822D01*
X314963Y417104D01*
X315458Y417670D01*
X315600Y417811D01*
X315953Y417458D01*
X315812Y417317D01*
G37*
G36*
G01X316660Y417034D02*
X317226Y417529D01*
X317509Y417246D01*
X317014Y416680D01*
X316872Y416539D01*
X316519Y416892D01*
X316660Y417034D01*
G37*
G36*
G01X317650Y415478D02*
X317084Y414983D01*
X316802Y415266D01*
X317297Y415832D01*
X317438Y415973D01*
X317792Y415619D01*
X317650Y415478D01*
G37*
G36*
G01X318499Y415195D02*
X319064Y415690D01*
X319347Y415407D01*
X318852Y414842D01*
X318711Y414700D01*
X318357Y415054D01*
X318499Y415195D01*
G37*
G36*
G01X320337Y413357D02*
X320903Y413852D01*
X321186Y413569D01*
X320691Y413003D01*
X320549Y412862D01*
X320196Y413215D01*
X320337Y413357D01*
G37*
G36*
G01X319489Y413640D02*
X318923Y413145D01*
X318640Y413427D01*
X319135Y413993D01*
X319276Y414135D01*
X319630Y413781D01*
X319489Y413640D01*
G37*
G36*
G01X321327Y411801D02*
X320761Y411306D01*
X320479Y411589D01*
X320974Y412155D01*
X321115Y412296D01*
X321468Y411943D01*
X321327Y411801D01*
G37*
G36*
G01X313973Y419155D02*
X313407Y418660D01*
X313125Y418943D01*
X313620Y419509D01*
X313761Y419650D01*
X314115Y419296D01*
X313973Y419155D01*
G37*
G36*
G01X314822Y418872D02*
X315387Y419367D01*
X315670Y419084D01*
X315175Y418519D01*
X315034Y418377D01*
X314680Y418731D01*
X314822Y418872D01*
G37*
G36*
G01X312983Y420711D02*
X313549Y421206D01*
X313832Y420923D01*
X313337Y420357D01*
X313195Y420216D01*
X312842Y420569D01*
X312983Y420711D01*
G37*
G36*
G01X312135Y420993D02*
X311569Y420498D01*
X311286Y420781D01*
X311781Y421347D01*
X311923Y421488D01*
X312276Y421135D01*
X312135Y420993D01*
G37*
G36*
G01X306060Y423564D02*
X306110Y424314D01*
X306510D01*
X306560Y423564D01*
Y423364D01*
X306060D01*
Y423564D01*
G37*
G36*
G01X307860Y423164D02*
X307810Y422414D01*
X307410D01*
X307360Y423164D01*
Y423364D01*
X307860D01*
Y423164D01*
G37*
G36*
G01X308660Y423564D02*
X308710Y424314D01*
X309110D01*
X309160Y423564D01*
Y423364D01*
X308660D01*
Y423564D01*
G37*
G36*
G01X311145Y422549D02*
X311710Y423044D01*
X311993Y422761D01*
X311498Y422196D01*
X311357Y422054D01*
X311003Y422408D01*
X311145Y422549D01*
G37*
G36*
G01X322176Y411518D02*
X322741Y412013D01*
X323024Y411730D01*
X322529Y411165D01*
X322388Y411023D01*
X322034Y411377D01*
X322176Y411518D01*
G37*
G36*
G01X323166Y409963D02*
X322600Y409468D01*
X322317Y409750D01*
X322812Y410316D01*
X322953Y410458D01*
X323307Y410104D01*
X323166Y409963D01*
G37*
G36*
G01X325298Y407337D02*
X324916Y407153D01*
X324619Y407450D01*
X324803Y407832D01*
X324944Y407973D01*
X325439Y407478D01*
X325298Y407337D01*
G37*
G36*
G01X324016Y409678D02*
X324581Y410173D01*
X324864Y409890D01*
X324369Y409325D01*
X324228Y409183D01*
X323874Y409537D01*
X324016Y409678D01*
G37*
G36*
G01X325686Y407513D02*
X326068Y407697D01*
X326365Y407400D01*
X326181Y407018D01*
X326040Y406877D01*
X325545Y407372D01*
X325686Y407513D01*
G37*
G36*
G01X326500Y406135D02*
X326118Y405951D01*
X325821Y406248D01*
X326005Y406630D01*
X326146Y406771D01*
X326641Y406276D01*
X326500Y406135D01*
G37*
G36*
G01X326888Y406311D02*
X327270Y406495D01*
X327567Y406198D01*
X327383Y405816D01*
X327242Y405675D01*
X326747Y406170D01*
X326888Y406311D01*
G37*
G36*
G01X327058Y404301D02*
X326658Y404441D01*
Y404861D01*
X327058Y405001D01*
X327258D01*
Y404301D01*
X327058D01*
G37*
G36*
G01X327458Y404151D02*
X327858Y404011D01*
Y403591D01*
X327458Y403451D01*
X327258D01*
Y404151D01*
X327458D01*
G37*
G36*
G01X320655Y428383D02*
X321221Y428878D01*
X321504Y428595D01*
X321009Y428029D01*
X320867Y427888D01*
X320514Y428241D01*
X320655Y428383D01*
G37*
G36*
G01X321645Y426827D02*
X321079Y426332D01*
X320797Y426615D01*
X321292Y427181D01*
X321433Y427322D01*
X321787Y426968D01*
X321645Y426827D01*
G37*
G36*
G01X319807Y428665D02*
X319241Y428170D01*
X318958Y428453D01*
X319453Y429019D01*
X319595Y429160D01*
X319948Y428807D01*
X319807Y428665D01*
G37*
G36*
G01X331686Y417352D02*
X332252Y417847D01*
X332535Y417564D01*
X332040Y416998D01*
X331898Y416857D01*
X331545Y417210D01*
X331686Y417352D01*
G37*
G36*
G01X330838Y417635D02*
X330272Y417140D01*
X329989Y417422D01*
X330484Y417988D01*
X330625Y418130D01*
X330979Y417776D01*
X330838Y417635D01*
G37*
G36*
G01X332678Y415795D02*
X332112Y415300D01*
X331829Y415582D01*
X332324Y416148D01*
X332465Y416290D01*
X332819Y415936D01*
X332678Y415795D01*
G37*
G36*
G01X332748Y413261D02*
X332348Y413401D01*
Y413821D01*
X332748Y413961D01*
X332948D01*
Y413261D01*
X332748D01*
G37*
G36*
G01X333148Y414811D02*
X333548Y414671D01*
Y414251D01*
X333148Y414111D01*
X332948D01*
Y414811D01*
X333148D01*
G37*
G36*
G01X333645Y410875D02*
X333263Y410692D01*
X332966Y410989D01*
X333150Y411370D01*
X333291Y411512D01*
X333786Y411017D01*
X333645Y410875D01*
G37*
G36*
G01X334034Y411052D02*
X334415Y411236D01*
X334712Y410939D01*
X334529Y410557D01*
X334387Y410416D01*
X333892Y410911D01*
X334034Y411052D01*
G37*
G36*
G01X333148Y413111D02*
X333548Y412971D01*
Y412551D01*
X333148Y412411D01*
X332948D01*
Y413111D01*
X333148D01*
G37*
G36*
G01X334847Y409673D02*
X334465Y409490D01*
X334168Y409787D01*
X334352Y410168D01*
X334493Y410310D01*
X334988Y409815D01*
X334847Y409673D01*
G37*
G36*
G01X329848Y419190D02*
X330413Y419685D01*
X330696Y419402D01*
X330201Y418837D01*
X330060Y418695D01*
X329706Y419049D01*
X329848Y419190D01*
G37*
G36*
G01X328999Y419473D02*
X328433Y418978D01*
X328151Y419261D01*
X328646Y419827D01*
X328787Y419968D01*
X329140Y419615D01*
X328999Y419473D01*
G37*
G36*
G01X335458Y404301D02*
X335058Y404441D01*
Y404861D01*
X335458Y405001D01*
X335658D01*
Y404301D01*
X335458D01*
G37*
G36*
G01X335858Y404151D02*
X336258Y404011D01*
Y403591D01*
X335858Y403451D01*
X335658D01*
Y404151D01*
X335858D01*
G37*
G36*
G01X335458Y406001D02*
X335058Y406141D01*
Y406561D01*
X335458Y406701D01*
X335658D01*
Y406001D01*
X335458D01*
G37*
G36*
G01Y407701D02*
X335058Y407841D01*
Y408261D01*
X335458Y408401D01*
X335658D01*
Y407701D01*
X335458D01*
G37*
G36*
G01X335858Y407551D02*
X336258Y407411D01*
Y406991D01*
X335858Y406851D01*
X335658D01*
Y407551D01*
X335858D01*
G37*
G36*
G01X335236Y409850D02*
X335617Y410034D01*
X335914Y409737D01*
X335731Y409355D01*
X335589Y409214D01*
X335094Y409709D01*
X335236Y409850D01*
G37*
G36*
G01X335858Y405851D02*
X336258Y405711D01*
Y405291D01*
X335858Y405151D01*
X335658D01*
Y405851D01*
X335858D01*
G37*
G36*
G01X328009Y421029D02*
X328575Y421524D01*
X328858Y421241D01*
X328363Y420675D01*
X328221Y420534D01*
X327868Y420887D01*
X328009Y421029D01*
G37*
G36*
G01X322494Y426544D02*
X323059Y427039D01*
X323342Y426756D01*
X322847Y426191D01*
X322706Y426049D01*
X322352Y426403D01*
X322494Y426544D01*
G37*
G36*
G01X323484Y424989D02*
X322918Y424494D01*
X322635Y424776D01*
X323130Y425342D01*
X323272Y425483D01*
X323625Y425130D01*
X323484Y424989D01*
G37*
G36*
G01X324332Y424706D02*
X324898Y425201D01*
X325181Y424918D01*
X324686Y424352D01*
X324544Y424211D01*
X324191Y424564D01*
X324332Y424706D01*
G37*
G36*
G01X325322Y423150D02*
X324756Y422655D01*
X324474Y422938D01*
X324969Y423504D01*
X325110Y423645D01*
X325464Y423291D01*
X325322Y423150D01*
G37*
G36*
G01X327161Y421312D02*
X326595Y420817D01*
X326312Y421099D01*
X326807Y421665D01*
X326948Y421807D01*
X327302Y421453D01*
X327161Y421312D01*
G37*
G36*
G01X326171Y422867D02*
X326736Y423362D01*
X327019Y423079D01*
X326524Y422514D01*
X326383Y422372D01*
X326029Y422726D01*
X326171Y422867D01*
G37*
G36*
G01X316978Y432060D02*
X317544Y432555D01*
X317827Y432272D01*
X317332Y431706D01*
X317190Y431565D01*
X316837Y431918D01*
X316978Y432060D01*
G37*
G36*
G01X317968Y430504D02*
X317403Y430009D01*
X317120Y430292D01*
X317615Y430858D01*
X317756Y430999D01*
X318110Y430645D01*
X317968Y430504D01*
G37*
G36*
G01X316130Y432342D02*
X315564Y431847D01*
X315281Y432130D01*
X315776Y432696D01*
X315918Y432837D01*
X316271Y432484D01*
X316130Y432342D01*
G37*
G36*
G01X318817Y430221D02*
X319382Y430716D01*
X319665Y430433D01*
X319170Y429868D01*
X319029Y429726D01*
X318675Y430080D01*
X318817Y430221D01*
G37*
G36*
G01X333773Y416890D02*
X333208Y416395D01*
X332925Y416678D01*
X333420Y417244D01*
X333596Y417421D01*
X333950Y417067D01*
X333773Y416890D01*
G37*
G36*
G01X333948Y413261D02*
X333548Y413401D01*
Y413821D01*
X333948Y413961D01*
X334198D01*
Y413261D01*
X333948D01*
G37*
G36*
G01Y414961D02*
X333548Y415101D01*
Y415521D01*
X333948Y415661D01*
X334198D01*
Y414961D01*
X333948D01*
G37*
G36*
G01X331933Y418730D02*
X331368Y418235D01*
X331085Y418518D01*
X331580Y419084D01*
X331756Y419261D01*
X332110Y418907D01*
X331933Y418730D01*
G37*
G36*
G01X336658Y404301D02*
X336258Y404441D01*
Y404861D01*
X336658Y405001D01*
X336908D01*
Y404301D01*
X336658D01*
G37*
G36*
G01X335695Y410522D02*
X335314Y410338D01*
X335017Y410635D01*
X335200Y411017D01*
X335377Y411194D01*
X335872Y410699D01*
X335695Y410522D01*
G37*
G36*
G01X336658Y406001D02*
X336258Y406141D01*
Y406561D01*
X336658Y406701D01*
X336908D01*
Y406001D01*
X336658D01*
G37*
G36*
G01Y407701D02*
X336258Y407841D01*
Y408261D01*
X336658Y408401D01*
X336908D01*
Y407701D01*
X336658D01*
G37*
G36*
G01X330095Y420569D02*
X329529Y420074D01*
X329246Y420357D01*
X329741Y420922D01*
X329918Y421099D01*
X330271Y420746D01*
X330095Y420569D01*
G37*
G36*
G01X324579Y426084D02*
X324014Y425589D01*
X323731Y425872D01*
X324226Y426438D01*
X324403Y426614D01*
X324756Y426261D01*
X324579Y426084D01*
G37*
G36*
G01X322741Y427923D02*
X322175Y427428D01*
X321892Y427711D01*
X322387Y428276D01*
X322564Y428453D01*
X322918Y428099D01*
X322741Y427923D01*
G37*
G36*
G01X326418Y424246D02*
X325852Y423751D01*
X325569Y424034D01*
X326064Y424599D01*
X326241Y424776D01*
X326595Y424422D01*
X326418Y424246D01*
G37*
G36*
G01X328256Y422407D02*
X327691Y421912D01*
X327408Y422195D01*
X327903Y422761D01*
X328079Y422938D01*
X328433Y422584D01*
X328256Y422407D01*
G37*
G36*
G01X319064Y431599D02*
X318499Y431104D01*
X318216Y431387D01*
X318711Y431953D01*
X318888Y432129D01*
X319241Y431776D01*
X319064Y431599D01*
G37*
G36*
G01X317226Y433437D02*
X316661Y432942D01*
X316378Y433225D01*
X316873Y433791D01*
X317050Y433967D01*
X317403Y433614D01*
X317226Y433437D01*
G37*
G36*
G01X320902Y429761D02*
X320337Y429266D01*
X320054Y429549D01*
X320549Y430115D01*
X320726Y430291D01*
X321079Y429938D01*
X320902Y429761D01*
G37*
G36*
G01X334493Y411724D02*
X334112Y411540D01*
X333815Y411837D01*
X333998Y412219D01*
X334175Y412396D01*
X334670Y411901D01*
X334493Y411724D01*
G37*
G36*
G01X303460Y418916D02*
X303510Y419666D01*
X303910D01*
X303960Y418916D01*
Y418666D01*
X303460D01*
Y418916D01*
G37*
G36*
G01X306060D02*
X306110Y419666D01*
X306510D01*
X306560Y418916D01*
Y418666D01*
X306060D01*
Y418916D01*
G37*
G36*
G01X300860D02*
X300910Y419666D01*
X301310D01*
X301360Y418916D01*
Y418666D01*
X300860D01*
Y418916D01*
G37*
G36*
G01X309695Y417422D02*
X310260Y417917D01*
X310543Y417634D01*
X310048Y417068D01*
X309871Y416892D01*
X309518Y417245D01*
X309695Y417422D01*
G37*
G36*
G01X318887Y408230D02*
X319453Y408725D01*
X319735Y408442D01*
X319241Y407876D01*
X319064Y407699D01*
X318710Y408053D01*
X318887Y408230D01*
G37*
G36*
G01X317048Y410068D02*
X317614Y410563D01*
X317897Y410280D01*
X317402Y409715D01*
X317225Y409538D01*
X316872Y409891D01*
X317048Y410068D01*
G37*
G36*
G01X320725Y406391D02*
X321291Y406886D01*
X321574Y406603D01*
X321079Y406038D01*
X320902Y405861D01*
X320549Y406214D01*
X320725Y406391D01*
G37*
G36*
G01X311533Y415584D02*
X312099Y416078D01*
X312382Y415796D01*
X311887Y415230D01*
X311710Y415053D01*
X311356Y415407D01*
X311533Y415584D01*
G37*
G36*
G01X315210Y411907D02*
X315776Y412402D01*
X316059Y412119D01*
X315564Y411553D01*
X315387Y411376D01*
X315033Y411730D01*
X315210Y411907D01*
G37*
G36*
G01X313372Y413745D02*
X313937Y414240D01*
X314220Y413957D01*
X313725Y413391D01*
X313548Y413215D01*
X313195Y413568D01*
X313372Y413745D01*
G37*
G36*
G01X306060Y420466D02*
X306110Y421216D01*
X306510D01*
X306560Y420466D01*
Y420266D01*
X306060D01*
Y420466D01*
G37*
G36*
G01X303460D02*
X303510Y421216D01*
X303910D01*
X303960Y420466D01*
Y420266D01*
X303460D01*
Y420466D01*
G37*
G36*
G01X305260Y420066D02*
X305210Y419316D01*
X304810D01*
X304760Y420066D01*
Y420266D01*
X305260D01*
Y420066D01*
G37*
G36*
G01X307860D02*
X307810Y419316D01*
X307410D01*
X307360Y420066D01*
Y420266D01*
X307860D01*
Y420066D01*
G37*
G36*
G01X311781Y416962D02*
X311215Y416468D01*
X310932Y416750D01*
X311427Y417316D01*
X311569Y417457D01*
X311922Y417104D01*
X311781Y416962D01*
G37*
G36*
G01X310791Y418518D02*
X311356Y419013D01*
X311639Y418730D01*
X311144Y418165D01*
X311003Y418023D01*
X310649Y418377D01*
X310791Y418518D01*
G37*
G36*
G01X309942Y418801D02*
X309376Y418306D01*
X309094Y418589D01*
X309589Y419155D01*
X309730Y419296D01*
X310084Y418942D01*
X309942Y418801D01*
G37*
G36*
G01X312629Y416680D02*
X313195Y417175D01*
X313478Y416892D01*
X312983Y416326D01*
X312841Y416185D01*
X312488Y416538D01*
X312629Y416680D01*
G37*
G36*
G01X314468Y414841D02*
X315033Y415336D01*
X315316Y415053D01*
X314821Y414488D01*
X314680Y414346D01*
X314326Y414700D01*
X314468Y414841D01*
G37*
G36*
G01X315458Y413286D02*
X314892Y412791D01*
X314609Y413073D01*
X315104Y413639D01*
X315245Y413781D01*
X315599Y413427D01*
X315458Y413286D01*
G37*
G36*
G01X313619Y415124D02*
X313053Y414629D01*
X312771Y414912D01*
X313266Y415478D01*
X313407Y415619D01*
X313761Y415265D01*
X313619Y415124D01*
G37*
G36*
G01X316306Y413003D02*
X316872Y413498D01*
X317155Y413215D01*
X316660Y412649D01*
X316518Y412508D01*
X316165Y412861D01*
X316306Y413003D01*
G37*
G36*
G01X317296Y411447D02*
X316730Y410952D01*
X316448Y411235D01*
X316943Y411801D01*
X317084Y411942D01*
X317438Y411588D01*
X317296Y411447D01*
G37*
G36*
G01X319983Y409326D02*
X320549Y409821D01*
X320832Y409538D01*
X320337Y408972D01*
X320195Y408831D01*
X319842Y409184D01*
X319983Y409326D01*
G37*
G36*
G01X318145Y411164D02*
X318710Y411659D01*
X318993Y411376D01*
X318498Y410811D01*
X318357Y410669D01*
X318003Y411023D01*
X318145Y411164D01*
G37*
G36*
G01X320973Y407770D02*
X320407Y407275D01*
X320125Y407558D01*
X320619Y408124D01*
X320761Y408265D01*
X321114Y407912D01*
X320973Y407770D01*
G37*
G36*
G01X319135Y409609D02*
X318569Y409114D01*
X318286Y409396D01*
X318781Y409962D01*
X318922Y410104D01*
X319276Y409750D01*
X319135Y409609D01*
G37*
G36*
G01X308951Y420358D02*
X309516Y420853D01*
X309799Y420570D01*
X309304Y420005D01*
X309163Y419863D01*
X308809Y420217D01*
X308951Y420358D01*
G37*
G36*
G01X321822Y407487D02*
X322387Y407982D01*
X322670Y407699D01*
X322175Y407134D01*
X322034Y406992D01*
X321680Y407346D01*
X321822Y407487D01*
G37*
G36*
G01X322812Y405932D02*
X322246Y405437D01*
X321963Y405719D01*
X322458Y406285D01*
X322599Y406427D01*
X322953Y406073D01*
X322812Y405932D01*
G37*
G36*
G01X302660Y420066D02*
X302610Y419316D01*
X302210D01*
X302160Y420066D01*
Y420266D01*
X302660D01*
Y420066D01*
G37*
G36*
G01X317615Y426473D02*
X317049Y425978D01*
X316766Y426261D01*
X317261Y426827D01*
X317403Y426968D01*
X317756Y426615D01*
X317615Y426473D01*
G37*
G36*
G01X316625Y428029D02*
X317190Y428524D01*
X317473Y428241D01*
X316978Y427676D01*
X316837Y427534D01*
X316483Y427888D01*
X316625Y428029D01*
G37*
G36*
G01X315776Y428312D02*
X315211Y427817D01*
X314928Y428100D01*
X315423Y428666D01*
X315564Y428807D01*
X315918Y428453D01*
X315776Y428312D01*
G37*
G36*
G01X318463Y426191D02*
X319029Y426686D01*
X319312Y426403D01*
X318817Y425837D01*
X318675Y425696D01*
X318322Y426049D01*
X318463Y426191D01*
G37*
G36*
G01X320302Y424352D02*
X320867Y424847D01*
X321150Y424564D01*
X320655Y423999D01*
X320514Y423857D01*
X320160Y424211D01*
X320302Y424352D01*
G37*
G36*
G01X321292Y422797D02*
X320726Y422302D01*
X320443Y422584D01*
X320938Y423150D01*
X321080Y423291D01*
X321433Y422938D01*
X321292Y422797D01*
G37*
G36*
G01X319453Y424635D02*
X318887Y424140D01*
X318605Y424423D01*
X319100Y424989D01*
X319241Y425130D01*
X319595Y424776D01*
X319453Y424635D01*
G37*
G36*
G01X326807Y417281D02*
X326241Y416786D01*
X325959Y417069D01*
X326454Y417635D01*
X326595Y417776D01*
X326948Y417423D01*
X326807Y417281D01*
G37*
G36*
G01X327656Y416998D02*
X328221Y417493D01*
X328504Y417210D01*
X328009Y416645D01*
X327868Y416503D01*
X327514Y416857D01*
X327656Y416998D01*
G37*
G36*
G01X328646Y415443D02*
X328080Y414948D01*
X327797Y415230D01*
X328292Y415796D01*
X328433Y415938D01*
X328787Y415584D01*
X328646Y415443D01*
G37*
G36*
G01X329494Y415160D02*
X330060Y415655D01*
X330343Y415372D01*
X329848Y414806D01*
X329706Y414665D01*
X329353Y415018D01*
X329494Y415160D01*
G37*
G36*
G01X331134Y410556D02*
X331515Y410740D01*
X331812Y410443D01*
X331628Y410061D01*
X331487Y409920D01*
X330992Y410415D01*
X331134Y410556D01*
G37*
G36*
G01X330348Y411561D02*
X329948Y411701D01*
Y412121D01*
X330348Y412261D01*
X330548D01*
Y411561D01*
X330348D01*
G37*
G36*
G01X330748Y413111D02*
X331148Y412971D01*
Y412551D01*
X330748Y412411D01*
X330548D01*
Y413111D01*
X330748D01*
G37*
G36*
G01X333458Y407551D02*
X333858Y407411D01*
Y406991D01*
X333458Y406851D01*
X333258D01*
Y407551D01*
X333458D01*
G37*
G36*
G01X331947Y409177D02*
X331565Y408994D01*
X331268Y409291D01*
X331452Y409672D01*
X331593Y409814D01*
X332088Y409319D01*
X331947Y409177D01*
G37*
G36*
G01X332336Y409354D02*
X332717Y409538D01*
X333014Y409241D01*
X332831Y408859D01*
X332689Y408718D01*
X332194Y409213D01*
X332336Y409354D01*
G37*
G36*
G01X333058Y406001D02*
X332658Y406141D01*
Y406561D01*
X333058Y406701D01*
X333258D01*
Y406001D01*
X333058D01*
G37*
G36*
G01X333458Y404151D02*
X333858Y404011D01*
Y403591D01*
X333458Y403451D01*
X333258D01*
Y404151D01*
X333458D01*
G37*
G36*
G01Y405851D02*
X333858Y405711D01*
Y405291D01*
X333458Y405151D01*
X333258D01*
Y405851D01*
X333458D01*
G37*
G36*
G01X333058Y404301D02*
X332658Y404441D01*
Y404861D01*
X333058Y405001D01*
X333258D01*
Y404301D01*
X333058D01*
G37*
G36*
G01X324969Y419120D02*
X324403Y418625D01*
X324120Y418907D01*
X324615Y419473D01*
X324756Y419615D01*
X325110Y419261D01*
X324969Y419120D01*
G37*
G36*
G01X325817Y418837D02*
X326383Y419332D01*
X326666Y419049D01*
X326171Y418483D01*
X326029Y418342D01*
X325676Y418695D01*
X325817Y418837D01*
G37*
G36*
G01X323979Y420675D02*
X324544Y421170D01*
X324827Y420887D01*
X324332Y420322D01*
X324191Y420180D01*
X323837Y420534D01*
X323979Y420675D01*
G37*
G36*
G01X323130Y420958D02*
X322564Y420463D01*
X322282Y420746D01*
X322777Y421312D01*
X322918Y421453D01*
X323272Y421099D01*
X323130Y420958D01*
G37*
G36*
G01X322140Y422514D02*
X322706Y423009D01*
X322989Y422726D01*
X322494Y422160D01*
X322352Y422019D01*
X321999Y422372D01*
X322140Y422514D01*
G37*
G36*
G01X314786Y429868D02*
X315352Y430363D01*
X315635Y430080D01*
X315140Y429514D01*
X314998Y429373D01*
X314645Y429726D01*
X314786Y429868D01*
G37*
G36*
G01X313938Y430150D02*
X313372Y429655D01*
X313089Y429938D01*
X313584Y430504D01*
X313726Y430645D01*
X314079Y430292D01*
X313938Y430150D01*
G37*
G36*
G01X318711Y427569D02*
X318145Y427074D01*
X317862Y427357D01*
X318357Y427923D01*
X318499Y428064D01*
X318852Y427711D01*
X318711Y427569D01*
G37*
G36*
G01X320549Y425731D02*
X319983Y425236D01*
X319701Y425519D01*
X320196Y426085D01*
X320337Y426226D01*
X320691Y425872D01*
X320549Y425731D01*
G37*
G36*
G01X319559Y427287D02*
X320125Y427782D01*
X320408Y427499D01*
X319913Y426933D01*
X319771Y426792D01*
X319418Y427145D01*
X319559Y427287D01*
G37*
G36*
G01X321398Y425448D02*
X321963Y425943D01*
X322246Y425660D01*
X321751Y425095D01*
X321610Y424953D01*
X321256Y425307D01*
X321398Y425448D01*
G37*
G36*
G01X317721Y429125D02*
X318286Y429620D01*
X318569Y429337D01*
X318074Y428772D01*
X317933Y428630D01*
X317579Y428984D01*
X317721Y429125D01*
G37*
G36*
G01X316872Y429408D02*
X316307Y428913D01*
X316024Y429196D01*
X316519Y429762D01*
X316660Y429903D01*
X317014Y429549D01*
X316872Y429408D01*
G37*
G36*
G01X334258Y404301D02*
X333858Y404441D01*
Y404861D01*
X334258Y405001D01*
X334458D01*
Y404301D01*
X334258D01*
G37*
G36*
G01X334658Y404151D02*
X335058Y404011D01*
Y403591D01*
X334658Y403451D01*
X334458D01*
Y404151D01*
X334658D01*
G37*
G36*
G01Y405851D02*
X335058Y405711D01*
Y405291D01*
X334658Y405151D01*
X334458D01*
Y405851D01*
X334658D01*
G37*
G36*
G01X328752Y418094D02*
X329317Y418589D01*
X329600Y418306D01*
X329105Y417741D01*
X328964Y417599D01*
X328610Y417953D01*
X328752Y418094D01*
G37*
G36*
G01X327903Y418377D02*
X327337Y417882D01*
X327055Y418165D01*
X327550Y418731D01*
X327691Y418872D01*
X328044Y418519D01*
X327903Y418377D01*
G37*
G36*
G01X331948Y414811D02*
X332348Y414671D01*
Y414251D01*
X331948Y414111D01*
X331748D01*
Y414811D01*
X331948D01*
G37*
G36*
G01X331548Y413261D02*
X331148Y413401D01*
Y413821D01*
X331548Y413961D01*
X331748D01*
Y413261D01*
X331548D01*
G37*
G36*
G01X332796Y410026D02*
X332414Y409843D01*
X332117Y410140D01*
X332301Y410521D01*
X332442Y410663D01*
X332937Y410168D01*
X332796Y410026D01*
G37*
G36*
G01X331983Y411405D02*
X332364Y411589D01*
X332661Y411292D01*
X332477Y410910D01*
X332336Y410769D01*
X331841Y411264D01*
X331983Y411405D01*
G37*
G36*
G01X333185Y410203D02*
X333566Y410387D01*
X333863Y410090D01*
X333680Y409708D01*
X333538Y409567D01*
X333043Y410062D01*
X333185Y410203D01*
G37*
G36*
G01X331548Y411561D02*
X331148Y411701D01*
Y412121D01*
X331548Y412261D01*
X331748D01*
Y411561D01*
X331548D01*
G37*
G36*
G01X331948Y413111D02*
X332348Y412971D01*
Y412551D01*
X331948Y412411D01*
X331748D01*
Y413111D01*
X331948D01*
G37*
G36*
G01X334258Y406001D02*
X333858Y406141D01*
Y406561D01*
X334258Y406701D01*
X334458D01*
Y406001D01*
X334258D01*
G37*
G36*
G01X334658Y407551D02*
X335058Y407411D01*
Y406991D01*
X334658Y406851D01*
X334458D01*
Y407551D01*
X334658D01*
G37*
G36*
G01X334258Y407701D02*
X333858Y407841D01*
Y408261D01*
X334258Y408401D01*
X334458D01*
Y407701D01*
X334258D01*
G37*
G36*
G01X333998Y408824D02*
X333616Y408641D01*
X333319Y408938D01*
X333503Y409319D01*
X333644Y409461D01*
X334139Y408966D01*
X333998Y408824D01*
G37*
G36*
G01X329742Y416539D02*
X329176Y416044D01*
X328893Y416326D01*
X329388Y416892D01*
X329529Y417034D01*
X329883Y416680D01*
X329742Y416539D01*
G37*
G36*
G01X330590Y416256D02*
X331156Y416751D01*
X331439Y416468D01*
X330944Y415902D01*
X330802Y415761D01*
X330449Y416114D01*
X330590Y416256D01*
G37*
G36*
G01X326913Y419933D02*
X327479Y420428D01*
X327762Y420145D01*
X327267Y419579D01*
X327125Y419438D01*
X326772Y419791D01*
X326913Y419933D01*
G37*
G36*
G01X326065Y420216D02*
X325499Y419721D01*
X325216Y420003D01*
X325711Y420569D01*
X325852Y420711D01*
X326206Y420357D01*
X326065Y420216D01*
G37*
G36*
G01X322388Y423893D02*
X321822Y423398D01*
X321539Y423680D01*
X322034Y424246D01*
X322176Y424387D01*
X322529Y424034D01*
X322388Y423893D01*
G37*
G36*
G01X323236Y423610D02*
X323802Y424105D01*
X324085Y423822D01*
X323590Y423256D01*
X323448Y423115D01*
X323095Y423468D01*
X323236Y423610D01*
G37*
G36*
G01X325075Y421771D02*
X325640Y422266D01*
X325923Y421983D01*
X325428Y421418D01*
X325287Y421276D01*
X324933Y421630D01*
X325075Y421771D01*
G37*
G36*
G01X324226Y422054D02*
X323660Y421559D01*
X323378Y421842D01*
X323873Y422408D01*
X324014Y422549D01*
X324368Y422195D01*
X324226Y422054D01*
G37*
G36*
G01X314044Y432802D02*
X314609Y433297D01*
X314892Y433014D01*
X314397Y432449D01*
X314256Y432307D01*
X313902Y432661D01*
X314044Y432802D01*
G37*
G36*
G01X315034Y431246D02*
X314468Y430751D01*
X314185Y431034D01*
X314680Y431600D01*
X314822Y431741D01*
X315175Y431388D01*
X315034Y431246D01*
G37*
G36*
G01X315882Y430964D02*
X316448Y431459D01*
X316731Y431176D01*
X316236Y430610D01*
X316094Y430469D01*
X315741Y430822D01*
X315882Y430964D01*
G37*
G36*
G01X327397Y499714D02*
G03I-600J0D01*
G37*
G36*
G01X299514Y584603D02*
X299251Y584866D01*
Y589330D01*
X302571Y592650D01*
Y594091D01*
X302842Y594362D01*
X305899D01*
G02X306293Y593894I0J-400D01*
G03X308379Y592445I1382J-237D01*
G02X308980Y592099I201J-346D01*
G01Y585469D01*
X308114Y584603D01*
X299514D01*
G37*
G36*
G01X300347Y546803D02*
X299750Y547400D01*
Y549571D01*
X302229Y552050D01*
Y555037D01*
X302495Y555303D01*
Y556090D01*
X302967Y556562D01*
X305899D01*
G02X306293Y556094I0J-400D01*
G03X308379Y554645I1382J-237D01*
G02X308980Y554299I201J-346D01*
G01Y547669D01*
X308114Y546803D01*
X300347D01*
G37*
G36*
G01X357042Y530756D02*
X307144D01*
X306400Y531500D01*
Y542300D01*
X307000Y542900D01*
X308400D01*
X308774Y542526D01*
Y537274D01*
X309274Y536774D01*
Y536526D01*
X310700Y535100D01*
X359171D01*
X363475Y530796D01*
X364404D01*
X364800Y530400D01*
Y528456D01*
X364600Y528256D01*
X359723D01*
X359483Y528496D01*
Y529480D01*
X358412Y530551D01*
X357247D01*
X357042Y530756D01*
G37*
G36*
G01X310021Y566005D02*
X309981Y566045D01*
Y573073D01*
G02X310523Y573446I400J-1D01*
G03X312357Y575182I498J1311D01*
G01X312348Y575212D01*
Y575743D01*
X316150D01*
Y574757D01*
G03X319278I1564J0D01*
G01Y575743D01*
X323080D01*
Y575212D01*
X323071Y575182D01*
G03X325743I1336J-425D01*
G01X325734Y575212D01*
Y575743D01*
X326428D01*
Y575212D01*
X326418Y575182D01*
G03X329090I1336J-425D01*
G01X329080Y575212D01*
Y575743D01*
X333120D01*
Y575212D01*
X333111Y575182D01*
G03X335783I1336J-425D01*
G01X335774Y575212D01*
Y575743D01*
X336466D01*
Y575212D01*
X336457Y575182D01*
G03X339129I1336J-425D01*
G01X339120Y575212D01*
Y575743D01*
X343160D01*
Y575212D01*
X343150Y575182D01*
G03X345822I1336J-425D01*
G01X345812Y575212D01*
Y575743D01*
X346506D01*
Y575212D01*
X346497Y575182D01*
G03X349169I1336J-425D01*
G01X349160Y575212D01*
Y575743D01*
X353198D01*
Y575209D01*
X353189Y575180D01*
G03X355861Y575185I1337J-423D01*
G01X355852Y575215D01*
Y575743D01*
X359892D01*
Y575448D01*
X359871Y575406D01*
G03X362540Y574028I1347J-664D01*
G02X363243I352J-190D01*
G03X365912Y575406I1322J714D01*
G01X365892Y575448D01*
Y575743D01*
X368618D01*
X369246Y575116D01*
Y566696D01*
X368554Y566005D01*
X366422D01*
G02X366032Y566491I1J400D01*
G03X363243Y567528I-1467J324D01*
G02X362540I-351J190D01*
G03X359751Y566491I-1322J-713D01*
G02X359361Y566005I-391J-86D01*
G01X355852D01*
Y566367D01*
X355861Y566397D01*
G03X353189I-1336J425D01*
G01X353198Y566367D01*
Y566005D01*
X352506D01*
Y566367D01*
X352515Y566397D01*
G03X349843I-1336J425D01*
G01X349852Y566367D01*
Y566005D01*
X345812D01*
Y566367D01*
X345822Y566397D01*
G03X343150I-1336J425D01*
G01X343160Y566367D01*
Y566005D01*
X342466D01*
Y566367D01*
X342476Y566397D01*
G03X339804I-1336J425D01*
G01X339814Y566367D01*
Y566005D01*
X335774D01*
Y566362D01*
X335783Y566391D01*
G03Y567237I-1337J423D01*
G01X335774Y567266D01*
Y567362D01*
X335706Y567430D01*
X335691Y567458D01*
G03X333111Y566386I-1245J-645D01*
G01X333120Y566356D01*
Y566005D01*
X332426D01*
Y566359D01*
X332436Y566389D01*
G03X329764I-1336J425D01*
G01X329774Y566359D01*
Y566005D01*
X325734D01*
Y566359D01*
X325743Y566389D01*
G03X323071I-1336J425D01*
G01X323080Y566359D01*
Y566005D01*
X322388D01*
Y566359D01*
X322397Y566389D01*
G03X319725I-1336J425D01*
G01X319734Y566359D01*
Y566005D01*
X315694D01*
Y566359D01*
X315704Y566389D01*
G03X313032I-1336J425D01*
G01X313042Y566359D01*
Y566005D01*
X310021D01*
G37*
G36*
G01X339454Y546815D02*
G02X339082Y547361I0J400D01*
G03X338814Y548875I-1289J553D01*
G02X339106Y549548I292J273D01*
G01X339894D01*
Y550048D01*
X341394D01*
Y553952D01*
X339894D01*
Y554266D01*
G02X340481Y554619I400J0D01*
G03X342523Y556089I659J1238D01*
G02X342917Y556553I395J64D01*
G01X343163D01*
Y556321D01*
X343153Y556291D01*
G03X343640Y554739I1333J-434D01*
G03X345879Y556016I846J1118D01*
G03X345869Y556089I-1394J-154D01*
G02X346263Y556553I395J64D01*
G01X349402D01*
G02X349796Y556089I-1J-400D01*
G03X351065Y554460I1383J-232D01*
G02X351248Y554260I-17J-199D01*
G01Y553952D01*
X349748D01*
Y550048D01*
X351248D01*
Y549548D01*
X353205D01*
G02X353498Y548876I0J-400D01*
G03X353235Y547372I1027J-955D01*
G02X352868Y546815I-368J-157D01*
G01X349490D01*
G02X349123Y547372I1J400D01*
G03X346543I-1290J550D01*
G02X346176Y546815I-368J-157D01*
G01X346143D01*
G02X345776Y547372I1J400D01*
G03X343196I-1290J550D01*
G02X342829Y546815I-368J-157D01*
G01X339454D01*
G37*
G36*
G01X329415D02*
G02X329043Y547361I0J400D01*
G03X327396Y549269I-1289J553D01*
G02X326894Y549656I-102J387D01*
G01Y550048D01*
X328394D01*
Y553952D01*
X326894D01*
Y554452D01*
X325902D01*
G02X325570Y555075I0J400D01*
G03X325800Y556016I-1163J783D01*
G03X325790Y556089I-1394J-154D01*
G02X326184Y556553I395J64D01*
G01X329323D01*
G02X329717Y556089I-1J-400D01*
G03X332483I1383J-232D01*
G02X332877Y556553I395J64D01*
G01X333124D01*
Y556321D01*
X333114Y556291D01*
G03X333601Y554739I1333J-434D01*
G03X334870Y554520I846J1118D01*
G02X335390Y554139I120J-381D01*
G01Y553302D01*
X334937D01*
X334898Y553320D01*
G03Y550680I-606J-1320D01*
G01X334937Y550698D01*
X335390D01*
Y549548D01*
X336480D01*
G02X336772Y548875I0J-400D01*
G03X336504Y547361I1021J-961D01*
G02X336132Y546815I-372J-146D01*
G01X336107D01*
G02X335735Y547361I0J400D01*
G03X333157I-1289J553D01*
G02X332785Y546815I-372J-146D01*
G01X329415D01*
G37*
G36*
G01X312682D02*
G02X312310Y547361I0J400D01*
G03X312042Y548875I-1289J553D01*
G02X312334Y549548I292J273D01*
G01X314624D01*
Y549998D01*
X314694D01*
Y550048D01*
X316124D01*
Y550498D01*
X316194D01*
Y553502D01*
X316124D01*
Y553952D01*
X314694D01*
Y554002D01*
X314624D01*
Y554470D01*
X314767Y554513D01*
G03X315751Y556089I-399J1344D01*
G02X316145Y556553I395J64D01*
G01X319284D01*
G02X319678Y556089I-1J-400D01*
G03X322444I1383J-232D01*
G02X322838Y556553I395J64D01*
G01X323084D01*
Y556321D01*
X323074Y556291D01*
G03X323244Y555075I1333J-434D01*
G02X322912Y554452I-332J-223D01*
G01X322390D01*
Y553302D01*
X321768D01*
X321729Y553320D01*
G03Y550680I-606J-1320D01*
G01X321768Y550698D01*
X322390D01*
Y549548D01*
X323094D01*
G02X323386Y548875I0J-400D01*
G03X323118Y547361I1021J-961D01*
G02X322746Y546815I-372J-146D01*
G01X319375D01*
G02X319003Y547361I0J400D01*
G03X316425I-1289J553D01*
G02X316053Y546815I-372J-146D01*
G01X312682D01*
G37*
G36*
G01X335610Y555075D02*
G03X335840Y556016I-1163J783D01*
G03X335830Y556089I-1394J-154D01*
G02X336224Y556553I395J64D01*
G01X339363D01*
G02X339757Y556089I-1J-400D01*
G03X339977Y555075I1383J-231D01*
G02X339645Y554452I-332J-223D01*
G01X335942D01*
G02X335610Y555075I0J400D01*
G37*
G36*
G01X339454Y584615D02*
G02X339082Y585161I0J400D01*
G03X338814Y586675I-1289J553D01*
G02X339106Y587348I292J273D01*
G01X339894D01*
Y587848D01*
X341394D01*
Y591752D01*
X339894D01*
Y592066D01*
G02X340481Y592419I400J0D01*
G03X342523Y593889I659J1238D01*
G02X342917Y594353I395J64D01*
G01X343163D01*
Y594121D01*
X343153Y594091D01*
G03X343640Y592539I1333J-434D01*
G03X345879Y593816I846J1118D01*
G03X345869Y593889I-1394J-154D01*
G02X346263Y594353I395J64D01*
G01X348305D01*
X348335Y594323D01*
X349397D01*
G02X349792Y593864I0J-400D01*
G03X351065Y592259I1387J-207D01*
G02X351248Y592060I-17J-199D01*
G01Y591802D01*
Y591752D01*
X349748D01*
Y591302D01*
Y588298D01*
Y587848D01*
X351248D01*
Y587798D01*
Y587348D01*
X353262D01*
X353437Y587174D01*
G02X353458Y586632I-283J-282D01*
G03X353235Y585172I1067J-910D01*
G02X352868Y584615I-368J-157D01*
G01X349490D01*
G02X349123Y585172I1J400D01*
G03X346543I-1290J550D01*
G02X346176Y584615I-368J-157D01*
G01X346143D01*
G02X345776Y585172I1J400D01*
G03X343196I-1290J550D01*
G02X342829Y584615I-368J-157D01*
G01X339454D01*
G37*
G36*
G01X329415D02*
G02X329043Y585161I0J400D01*
G03X327396Y587069I-1289J553D01*
G02X326894Y587456I-102J387D01*
G01Y587848D01*
X328394D01*
Y591752D01*
X326894D01*
Y592252D01*
X325902D01*
G02X325570Y592875I0J400D01*
G03X325800Y593816I-1163J783D01*
G03X325790Y593889I-1394J-154D01*
G02X326184Y594353I395J64D01*
G01X329323D01*
G02X329717Y593889I-1J-400D01*
G03X332483I1383J-232D01*
G02X332877Y594353I395J64D01*
G01X333124D01*
Y594121D01*
X333114Y594091D01*
G03X333601Y592539I1333J-434D01*
G03X334870Y592320I846J1118D01*
G02X335390Y591939I120J-381D01*
G01Y591102D01*
X334937D01*
X334898Y591120D01*
G03Y588480I-606J-1320D01*
G01X334937Y588498D01*
X335390D01*
Y587348D01*
X336480D01*
G02X336772Y586675I0J-400D01*
G03X336504Y585161I1021J-961D01*
G02X336132Y584615I-372J-146D01*
G01X336107D01*
G02X335735Y585161I0J400D01*
G03X333157I-1289J553D01*
G02X332785Y584615I-372J-146D01*
G01X329415D01*
G37*
G36*
G01X312682D02*
G02X312310Y585161I0J400D01*
G03X312409Y585914I-1289J552D01*
G03X312042Y586675I-1388J-200D01*
G02X312334Y587348I292J273D01*
G01X314694D01*
Y587798D01*
Y587848D01*
X316194D01*
Y588298D01*
Y591302D01*
Y591752D01*
X314694D01*
Y591802D01*
Y592286D01*
X314828Y592333D01*
G03X315751Y593889I-460J1324D01*
G02X316145Y594353I395J64D01*
G01X319284D01*
G02X319678Y593889I-1J-400D01*
G03X322444I1383J-232D01*
G02X322838Y594353I395J64D01*
G01X323084D01*
Y594121D01*
X323074Y594091D01*
G03X323244Y592875I1333J-434D01*
G02X322912Y592252I-332J-223D01*
G01X322390D01*
Y591102D01*
X321837D01*
X321798Y591120D01*
G03Y588480I-606J-1320D01*
G01X321837Y588498D01*
X322390D01*
Y587348D01*
X323094D01*
G02X323386Y586675I0J-400D01*
G03X323118Y585161I1021J-961D01*
G02X322746Y584615I-372J-146D01*
G01X319375D01*
G02X319003Y585161I0J400D01*
G03X316425I-1289J553D01*
G02X316053Y584615I-372J-146D01*
G01X312682D01*
G37*
G36*
G01X358117Y603712D02*
X358024Y603805D01*
X355852D01*
Y606586D01*
X355873Y606628D01*
G03X353179I-1347J664D01*
G01X353200Y606586D01*
Y603805D01*
X352608D01*
Y604035D01*
X352617Y604064D01*
G03X352036Y605733I-1438J435D01*
G03X349695Y604267I-857J-1234D01*
G02X349300Y603805I-395J-62D01*
G01X346343D01*
G02X345953Y604291I1J400D01*
G03X345872Y605192I-1467J322D01*
G03X343416Y605668I-1386J-578D01*
G03X343083Y604077I1070J-1054D01*
G01X343096Y604042D01*
Y603805D01*
X342466D01*
Y606586D01*
X342487Y606628D01*
G03X339793I-1347J664D01*
G01X339814Y606586D01*
Y603805D01*
X335774D01*
Y606587D01*
X335795Y606629D01*
G03X333099I-1348J663D01*
G01X333120Y606587D01*
Y603805D01*
X332490D01*
Y604042D01*
X332503Y604077D01*
G03X332170Y605668I-1403J537D01*
G03X329714Y605193I-1070J-1054D01*
G03X329633Y604291I1386J-579D01*
G02X329243Y603805I-391J-86D01*
G01X326286D01*
G02X325891Y604267I0J400D01*
G03X323550Y605733I-1484J232D01*
G03X322969Y604064I857J-1234D01*
G01X322978Y604035D01*
Y603805D01*
X322388D01*
Y606587D01*
X322409Y606629D01*
G03X319713I-1348J663D01*
G01X319734Y606587D01*
Y603805D01*
X315694D01*
Y606586D01*
X315715Y606628D01*
G03X313021I-1347J664D01*
G01X313042Y606586D01*
Y603805D01*
X310021D01*
X309981Y603845D01*
Y608074D01*
G02X310498Y608456I400J-1D01*
G03X312369Y610527I523J1408D01*
G01X312348Y610569D01*
Y613543D01*
X316150D01*
Y609864D01*
G03X319278I1564J0D01*
G01Y613543D01*
X323080D01*
Y610569D01*
X323059Y610527D01*
G03X325755I1348J-663D01*
G01X325734Y610569D01*
Y613543D01*
X326428D01*
Y613163D01*
X326407Y613121D01*
G03X329101I1347J-664D01*
G01X329080Y613163D01*
Y613543D01*
X333120D01*
Y613162D01*
X333099Y613120D01*
G03X335795I1348J-663D01*
G01X335774Y613162D01*
Y613543D01*
X336466D01*
Y610569D01*
X336445Y610527D01*
G03X339141I1348J-663D01*
G01X339120Y610569D01*
Y613543D01*
X343160D01*
Y610570D01*
X343139Y610528D01*
G03X345833I1347J-664D01*
G01X345812Y610570D01*
Y613543D01*
X346506D01*
Y613062D01*
X346485Y613020D01*
G03X349181I1348J-663D01*
G01X349160Y613062D01*
Y613543D01*
X353198D01*
Y613063D01*
X353177Y613021D01*
G03X355873I1348J-663D01*
G01X355852Y613063D01*
Y613543D01*
X359892D01*
Y612948D01*
X359871Y612906D01*
G03X362540Y611528I1347J-664D01*
G02X363243I352J-190D01*
G03X365912Y612906I1322J714D01*
G01X365892Y612948D01*
Y613543D01*
X368075D01*
X369128Y612490D01*
Y604197D01*
X368643Y603712D01*
X366400D01*
G02X366014Y604218I0J400D01*
G03X363243Y605328I-1449J397D01*
G02X362540I-351J190D01*
G03X359769Y604218I-1322J-713D01*
G02X359383Y603712I-386J-106D01*
G01X358117D01*
G37*
G36*
G01X335610Y592875D02*
G03X335840Y593816I-1163J783D01*
G03X335830Y593889I-1394J-154D01*
G02X336224Y594353I395J64D01*
G01X339363D01*
G02X339757Y593889I-1J-400D01*
G03X339977Y592875I1383J-231D01*
G02X339645Y592252I-332J-223D01*
G01X335942D01*
G02X335610Y592875I0J400D01*
G37*
G36*
G01X379798Y15337D02*
Y6715D01*
X378910Y5826D01*
X375405D01*
X375020Y6212D01*
Y7215D01*
X374796Y7438D01*
Y8250D01*
X375500Y8954D01*
Y10576D01*
X376294D01*
Y15500D01*
X378113D01*
Y15598D01*
X379537D01*
X379798Y15337D01*
G37*
G36*
G01X442892Y-2200D02*
Y-9400D01*
X441592Y-10700D01*
X440018D01*
G02X439633Y-10192I0J400D01*
G03X436741I-1446J406D01*
G02X436356Y-10700I-385J-108D01*
G01X433354D01*
G02X432963Y-10216I0J400D01*
G03X430025I-1469J315D01*
G02X429634Y-10700I-391J-84D01*
G01X426632D01*
G02X426247Y-10192I0J400D01*
G03X423438Y-10416I-1446J406D01*
G01X423456Y-10456D01*
Y-10700D01*
X422780D01*
Y-7814D01*
X422801Y-7772D01*
G03X420107I-1347J664D01*
G01X420128Y-7814D01*
Y-10700D01*
X416088D01*
Y-7812D01*
X416109Y-7770D01*
G03X413415Y-7774I-1348J662D01*
G01X413436Y-7816D01*
Y-10700D01*
X409396D01*
Y-7812D01*
X409416Y-7770D01*
G03X406722Y-7774I-1348J662D01*
G01X406742Y-7816D01*
Y-10700D01*
X406115D01*
Y-10464D01*
X406128Y-10430D01*
G03X403253Y-10216I-1406J529D01*
G02X402862Y-10700I-391J-84D01*
G01X400092D01*
X399517Y-10125D01*
X399525Y-10032D01*
G03X397898Y-8405I-1496J131D01*
G01X397805Y-8413D01*
X397444Y-8052D01*
Y-7707D01*
X396192Y-6456D01*
Y-1900D01*
X396892Y-1200D01*
X399478D01*
G02X399877Y-1630I0J-400D01*
G03X402846Y-1440I1498J-113D01*
G01X402842Y-1420D01*
Y-1200D01*
X403396D01*
Y-3830D01*
X403375Y-3872D01*
G03X406069I1347J-664D01*
G01X406048Y-3830D01*
Y-1200D01*
X409850D01*
Y-4536D01*
G03X412980I1565J0D01*
G01Y-3050D01*
G02X413670Y-2775I400J0D01*
G03X416259Y-1630I1091J1032D01*
G02X416658Y-1200I399J30D01*
G01X419615D01*
G02X420012Y-1647I0J-400D01*
G03X422896I1442J-170D01*
G02X423293Y-1200I397J47D01*
G01X426250D01*
G02X426649Y-1630I0J-400D01*
G03X429645I1498J-113D01*
G02X430044Y-1200I399J30D01*
G01X432943D01*
G02X433342Y-1630I0J-400D01*
G03X436311Y-1440I1498J-113D01*
G01X436307Y-1420D01*
Y-1200D01*
X436860D01*
Y-3830D01*
X436840Y-3872D01*
G03X439534I1347J-664D01*
G01X439514Y-3830D01*
Y-1200D01*
X441892D01*
X442892Y-2200D01*
G37*
G36*
G01X399892Y27300D02*
X399501Y27691D01*
X399515Y27790D01*
G03X397812Y29493I-1486J217D01*
G01X397713Y29479D01*
X396492Y30700D01*
Y34800D01*
X396700Y35008D01*
Y41400D01*
X397500Y42200D01*
X398700D01*
X399300Y41600D01*
Y36700D01*
X399500Y36500D01*
X399581D01*
G02X399979Y36068I-1J-400D01*
G03X400040Y35534I1398J-111D01*
G01X400050Y35505D01*
Y35409D01*
X400117Y35341D01*
X400132Y35313D01*
G03X402746Y36257I1245J645D01*
G01X402742Y36278D01*
Y36500D01*
X403358D01*
Y36278D01*
X403354Y36257D01*
G03X406092I1369J-300D01*
G01X406088Y36278D01*
Y36500D01*
X406400D01*
X406800Y36900D01*
Y41500D01*
X407500Y42200D01*
X408800D01*
X409500Y41500D01*
Y36500D01*
X409850D01*
Y36058D01*
G03X412967Y35862I1565J0D01*
G02X413365Y35852I198J-25D01*
G03X413426Y35534I1398J103D01*
G01X413436Y35505D01*
Y35409D01*
X413503Y35341D01*
X413518Y35313D01*
G03X416132Y36257I1245J645D01*
G01X416128Y36278D01*
Y36500D01*
X416300D01*
X416900Y37100D01*
Y41700D01*
X417300Y42100D01*
X418900D01*
X419500Y41500D01*
Y36900D01*
X419900Y36500D01*
X422900D01*
X423400Y37000D01*
Y41300D01*
X424200Y42100D01*
X425500D01*
X426100Y41500D01*
Y37000D01*
X426600Y36500D01*
X426784D01*
Y36278D01*
X426780Y36257D01*
G03X426811Y35537I1369J-302D01*
G01X426820Y35508D01*
Y35410D01*
X426889Y35341D01*
X426904Y35313D01*
G03X429518Y36257I1245J645D01*
G01X429514Y36278D01*
Y36500D01*
X429700D01*
X430200Y37000D01*
Y41400D01*
X430900Y42100D01*
X432100D01*
X432800Y41400D01*
Y37000D01*
X433300Y36500D01*
X433477D01*
Y36278D01*
X433473Y36257D01*
G03X433504Y35537I1369J-302D01*
G01X433514Y35508D01*
Y35410D01*
X433582Y35341D01*
X433597Y35313D01*
G03X436211Y36257I1245J645D01*
G01X436207Y36278D01*
Y36500D01*
X436824D01*
Y36278D01*
X436820Y36257D01*
G03X439563Y36236I1369J-300D01*
G01X439542Y36342D01*
X440200Y37000D01*
Y41700D01*
X440600Y42100D01*
X442400D01*
X442800Y41700D01*
Y36500D01*
X443192Y36108D01*
Y28242D01*
X442250Y27300D01*
X439514D01*
Y27561D01*
X439523Y27591D01*
G03X436944Y28666I-1334J430D01*
G01X436929Y28638D01*
X436860Y28569D01*
Y28471D01*
X436851Y28442D01*
G03Y27602I1338J-420D01*
G01X436860Y27573D01*
Y27300D01*
X433371D01*
G02X432976Y27765I0J400D01*
G03X430012I-1482J242D01*
G02X429617Y27300I-395J-65D01*
G01X426678D01*
G02X426283Y27765I0J400D01*
G03X423367Y27560I-1482J242D01*
G01X423376Y27530D01*
Y27300D01*
X422782D01*
Y27564D01*
X422791Y27594D01*
G03X420211Y28666I-1335J427D01*
G01X420196Y28638D01*
X420128Y28570D01*
Y28474D01*
X420119Y28445D01*
G03Y27599I1337J-423D01*
G01X420128Y27570D01*
Y27300D01*
X416088D01*
Y27566D01*
X416098Y27596D01*
G03X413426I-1336J425D01*
G01X413436Y27566D01*
Y27300D01*
X409946D01*
G02X409551Y27765I0J400D01*
G03X406635Y27560I-1482J242D01*
G01X406644Y27530D01*
Y27300D01*
X406048D01*
Y27564D01*
X406058Y27594D01*
G03X403478Y28666I-1335J427D01*
G01X403463Y28638D01*
X403396Y28570D01*
Y28474D01*
X403386Y28445D01*
G03Y27599I1337J-423D01*
G01X403396Y27570D01*
Y27300D01*
X399892D01*
G37*
G36*
G01X397000Y-300D02*
X396800Y-100D01*
Y8965D01*
X398056Y10220D01*
Y13830D01*
X397592Y14293D01*
Y15216D01*
X397961Y15585D01*
X398678D01*
X399560Y16467D01*
Y18468D01*
X399900Y18808D01*
Y23400D01*
X400500Y24000D01*
X402200D01*
X402800Y23400D01*
Y19270D01*
X403204Y18866D01*
X409617D01*
X410100Y19349D01*
Y23400D01*
X410700Y24000D01*
X412400D01*
X413000Y23400D01*
Y19125D01*
X413253Y18872D01*
X413460D01*
X416276D01*
X416800Y19395D01*
Y23500D01*
X417300Y24000D01*
X419000D01*
X419500Y23500D01*
Y19253D01*
X419880Y18873D01*
X420153D01*
Y18871D01*
X426333D01*
X426700Y19238D01*
Y23400D01*
X427400Y24100D01*
X428900D01*
X429500Y23500D01*
Y19300D01*
X429944Y18856D01*
X433056D01*
X433500Y19300D01*
Y23300D01*
X434200Y24000D01*
X435500D01*
X436100Y23400D01*
Y19349D01*
X436578Y18871D01*
X439973D01*
X440300Y19198D01*
Y23500D01*
X440900Y24100D01*
X442300D01*
X443096Y23304D01*
Y18296D01*
X443649Y17743D01*
X443594Y17618D01*
G03X443840Y16118I1286J-559D01*
G01X443892Y16061D01*
Y15652D01*
X440256D01*
Y15152D01*
X438756D01*
Y11248D01*
X440256D01*
Y10748D01*
X443892D01*
Y10117D01*
G03X443523Y8770I988J-995D01*
G01X443552Y8660D01*
X442646Y7754D01*
X439754D01*
X439285Y7285D01*
X433338D01*
Y6838D01*
X432900Y6400D01*
Y3000D01*
X432100Y2200D01*
X430800D01*
X430000Y3000D01*
Y6800D01*
X429648Y7152D01*
Y7284D01*
X426646D01*
Y7200D01*
X426500D01*
Y3000D01*
X425700Y2200D01*
X423900D01*
X423200Y2900D01*
Y7000D01*
X423000Y7200D01*
X422757D01*
Y7284D01*
X419954D01*
Y7254D01*
X419600Y6900D01*
Y2600D01*
X418900Y1900D01*
X417500D01*
X416700Y2700D01*
Y7000D01*
X416500Y7200D01*
X416264D01*
Y7285D01*
X409913D01*
Y7213D01*
X409500Y6800D01*
Y1600D01*
X409100Y1200D01*
X407400D01*
X406800Y1800D01*
Y6600D01*
X406224Y7176D01*
Y7285D01*
X399874D01*
Y7174D01*
X399300Y6600D01*
Y0D01*
X399000Y-300D01*
X397000D01*
G37*
G36*
G01X367542Y8000D02*
X366009Y9533D01*
X365994Y9579D01*
G03X365392Y10369I-1429J-464D01*
G01Y15533D01*
X365559Y15561D01*
G03X366689Y17641I-248J1482D01*
G02X367055Y18200I367J159D01*
G01X368292D01*
X368890Y17601D01*
Y16585D01*
X368892Y16584D01*
Y16000D01*
X369292Y15600D01*
X370384D01*
X370385Y15598D01*
X373252D01*
X373290Y15560D01*
Y10541D01*
X373050Y10300D01*
X369776D01*
X369326Y9850D01*
X368890Y9415D01*
Y8500D01*
X368390Y8000D01*
X367542D01*
G37*
G36*
G01X370392Y-18500D02*
X370264Y-18372D01*
Y6868D01*
X370696Y7300D01*
X373518D01*
X374018Y6800D01*
Y5797D01*
X374990Y4825D01*
X379325D01*
X380800Y6300D01*
Y16100D01*
X380300Y16600D01*
X370800D01*
X370262Y17138D01*
Y28014D01*
G03X369892Y29281I-2351J1D01*
G01Y34675D01*
G03X370262Y35942I-1981J1266D01*
G01Y44098D01*
X378266D01*
X378517Y44350D01*
X378520D01*
X382040Y47870D01*
Y47873D01*
X382442Y48274D01*
Y53895D01*
X382954Y54407D01*
Y57806D01*
X382076Y58686D01*
X378500D01*
X376814Y57000D01*
X370400D01*
X370234Y57166D01*
Y60358D01*
X370236Y60373D01*
G03X370262Y60723I-2325J349D01*
G01Y65262D01*
X371000Y66000D01*
X372500D01*
X379500Y73000D01*
Y74544D01*
X380138Y76086D01*
Y87003D01*
X379820Y87773D01*
X379000Y89752D01*
Y93000D01*
X379238Y93238D01*
X384569D01*
G02X384931Y92667I0J-400D01*
G03X384586Y91128I3256J-1538D01*
G01Y86228D01*
G03X391788I3601J0D01*
G01Y91128D01*
G03X391443Y92667I-3601J1D01*
G02X391805Y93238I362J171D01*
G01X392003D01*
X392388Y92853D01*
Y92133D01*
X392392Y92129D01*
Y69614D01*
X392130Y69352D01*
G02X391788Y69494I-142J141D01*
G01Y72228D01*
G03X384586I-3601J0D01*
G01Y67328D01*
G03X391419Y65738I3601J0D01*
G02X392178Y65562I359J-176D01*
G01Y56622D01*
X393036Y55764D01*
Y47449D01*
X391468Y45882D01*
Y37204D01*
G02X390781Y36927I-400J1D01*
G03X384586Y34428I-2593J-2499D01*
G01Y29528D01*
G03X391788I3601J0D01*
G01Y33885D01*
G02X392130Y34026I200J0D01*
G01X392392Y33764D01*
Y8976D01*
X390792Y7376D01*
Y4592D01*
X384324Y-1876D01*
Y-12068D01*
X377892Y-18500D01*
X370392D01*
G37*
G36*
G01X376525Y48255D02*
Y55295D01*
X378915Y57685D01*
X381660D01*
X381952Y57392D01*
Y54822D01*
X381440Y54310D01*
Y48689D01*
X377851Y45100D01*
X370220D01*
X369970Y45350D01*
Y47420D01*
X370250Y47700D01*
X375970D01*
X376525Y48255D01*
G37*
G36*
G01X446892Y66500D02*
X445892Y67500D01*
X396591D01*
X396388Y67703D01*
Y69012D01*
X396170Y69230D01*
Y70169D01*
X396210Y70210D01*
X420121D01*
X420912Y71000D01*
X420992D01*
X421992Y72000D01*
X442392D01*
X443392Y73000D01*
Y74500D01*
X452892D01*
Y70000D01*
X449392Y66500D01*
X446892D01*
G37*
G36*
G01X397011Y45099D02*
X396800Y45310D01*
Y46825D01*
X397944Y47968D01*
Y50852D01*
X398892Y51800D01*
Y53737D01*
G03X399303Y55427I-863J1105D01*
G01X399245Y55553D01*
X400306Y56614D01*
X403537D01*
G02X403801Y55913I1J-400D01*
G03X403560Y54075I922J-1056D01*
G02X403228Y53452I-332J-223D01*
G01X402448D01*
Y52952D01*
X400948D01*
Y49048D01*
X402448D01*
Y48548D01*
X403403D01*
G02X403696Y47876I0J-400D01*
G03X405750I1027J-954D01*
G02X406043Y48548I293J272D01*
G01X406952D01*
Y49748D01*
X407446D01*
X407491Y49724D01*
G03Y52276I693J1276D01*
G01X407446Y52252D01*
X406952D01*
Y53189D01*
G02X407511Y53556I400J0D01*
G03X408978Y55909I558J1286D01*
G02X409237Y56614I259J305D01*
G01X413577D01*
G02X413841Y55913I1J-400D01*
G03X414707Y53456I922J-1056D01*
G02X414898Y53256I-9J-200D01*
G01Y52952D01*
X413398D01*
Y49048D01*
X414898D01*
Y48523D01*
G02X414707Y48323I-200J0D01*
G03X415790Y47876I56J-1401D01*
G02X416083Y48548I293J272D01*
G01X419402D01*
Y49698D01*
X420723D01*
X420762Y49680D01*
G03Y52320I606J1320D01*
G01X420723Y52302D01*
X419402D01*
Y53452D01*
X416258D01*
G02X415926Y54075I0J400D01*
G03X415685Y55913I-1163J782D01*
G02X415949Y56614I263J301D01*
G01X420270D01*
G02X420534Y55913I1J-400D01*
G03X422378I922J-1056D01*
G02X422642Y56614I263J301D01*
G01X423633D01*
G02X423892Y55909I0J-400D01*
G03X425710I909J-1067D01*
G02X425969Y56614I259J305D01*
G01X430326D01*
G02X430585Y55909I0J-400D01*
G03X430323Y54071I909J-1067D01*
G02X429989Y53452I-334J-219D01*
G01X427898D01*
Y52952D01*
X426398D01*
Y49048D01*
X427898D01*
Y48310D01*
X427755Y48267D01*
G03X429176Y47876I394J-1345D01*
G02X429469Y48548I293J272D01*
G01X432402D01*
Y49698D01*
X432863D01*
X432902Y49680D01*
G03Y52320I606J1320D01*
G01X432863Y52302D01*
X432402D01*
Y53773D01*
G03X432403Y55909I-908J1068D01*
G02X432662Y56614I259J305D01*
G01X436999D01*
G02X437263Y55913I0J-400D01*
G03X439111I924J-1054D01*
G02X439375Y56614I264J301D01*
G01X442678D01*
X443685Y55607D01*
X443622Y55478D01*
G03X443718Y54075I1258J-619D01*
G02X443386Y53452I-332J-223D01*
G01X440256D01*
Y52952D01*
X438756D01*
Y49048D01*
X440256D01*
Y48548D01*
X443560D01*
G02X443853Y47876I0J-400D01*
G03X443748Y46095I1027J-954D01*
G01X443849Y45957D01*
X442991Y45099D01*
X422170D01*
Y45715D01*
G03X420740I-715J1206D01*
G01Y45099D01*
X397011D01*
G37*
G36*
G01X355478Y45893D02*
G03X355817Y47467I-953J1029D01*
G02X356185Y48022I368J155D01*
G01X359590D01*
Y45800D01*
X358990Y45200D01*
X355749D01*
G02X355478Y45893I1J400D01*
G37*
G36*
G01X364950Y48550D02*
X364930Y48570D01*
Y52444D01*
X364740D01*
Y52610D01*
X364656Y52694D01*
G02X364860Y53369I283J283D01*
G03X365575Y55954I-295J1473D01*
G02X365844Y56650I269J296D01*
G01X366142D01*
X366892Y57400D01*
Y64400D01*
X365992Y65300D01*
Y66500D01*
X366492Y67000D01*
X368192D01*
X368900Y66292D01*
Y57050D01*
X369950Y56000D01*
X369984D01*
X369985Y55998D01*
X372572D01*
X373430Y55140D01*
Y49020D01*
X373111Y48702D01*
X369835D01*
X369684Y48550D01*
X364950D01*
G37*
G36*
G01X359406Y52970D02*
X358634Y53742D01*
X358111D01*
X358089Y53748D01*
G03X357435I-327J-1415D01*
G01X357413Y53742D01*
X356192D01*
X355901Y53452D01*
X355381D01*
Y53742D01*
X355449Y53802D01*
G03X355415Y55941I-923J1055D01*
G02X355669Y56650I254J309D01*
G01X359939D01*
G02X360208Y55954I0J-400D01*
G03X360267Y53680I1010J-1112D01*
G02X360014Y52970I-253J-310D01*
G01X359406D01*
G37*
G36*
G01X380094Y99928D02*
X385393D01*
X386992Y98329D01*
Y96600D01*
X385649Y95257D01*
X379047D01*
X379023Y95281D01*
Y98857D01*
X380094Y99928D01*
G37*
G36*
G01X381392Y268300D02*
X380092Y269600D01*
Y276179D01*
X378692Y277579D01*
X367026D01*
X365148Y279457D01*
Y284456D01*
X365522Y284830D01*
X409358D01*
Y284748D01*
X412362D01*
Y284830D01*
X414358D01*
Y284748D01*
X417362D01*
Y284830D01*
X419358D01*
Y284748D01*
X422362D01*
Y284800D01*
X442592D01*
X444192Y283200D01*
Y278600D01*
X443492Y277900D01*
X431400D01*
X430502Y277002D01*
X425998D01*
Y273398D01*
X425562Y272962D01*
X403650D01*
Y273092D01*
X400646D01*
Y272962D01*
X398758D01*
Y273092D01*
X396300D01*
X395692Y273700D01*
Y276900D01*
X395013Y277579D01*
X388692D01*
X387792Y276679D01*
Y269100D01*
X386992Y268300D01*
X381392D01*
G37*
G36*
G01X389478Y263636D02*
Y267448D01*
X389470D01*
Y268740D01*
X389808D01*
Y271742D01*
X389470D01*
Y273640D01*
X389800D01*
Y276578D01*
X394598D01*
X394690Y276485D01*
Y273285D01*
X394838Y273138D01*
Y271362D01*
X395100Y271100D01*
X395754D01*
Y271090D01*
X398758D01*
Y271100D01*
X400646D01*
Y271090D01*
X403610D01*
X403800Y270900D01*
X424944D01*
X426587Y269257D01*
Y266405D01*
X427667Y265325D01*
Y264170D01*
X427154Y263658D01*
X418041D01*
X418020Y263636D01*
X389478D01*
G37*
G36*
G01X407662Y301902D02*
Y301916D01*
X409558D01*
Y301902D01*
X412562D01*
Y301916D01*
X414458D01*
Y301902D01*
X417462D01*
Y301916D01*
X419358D01*
Y301902D01*
X422290D01*
X423092Y301100D01*
X425146D01*
Y301090D01*
X428150D01*
Y301100D01*
X430146D01*
Y301090D01*
X433150D01*
Y301100D01*
X435146D01*
Y301090D01*
X438150D01*
Y301100D01*
X440162D01*
Y300902D01*
X443164D01*
Y301100D01*
X445062D01*
Y300902D01*
X448064D01*
Y301100D01*
X449962D01*
Y300902D01*
X452964D01*
Y301000D01*
X453692D01*
X456092Y303400D01*
Y315700D01*
X456982Y316590D01*
X459650D01*
Y316700D01*
X462292D01*
X464092Y314900D01*
Y312000D01*
X463792Y311700D01*
X460100D01*
X458950Y310550D01*
Y309950D01*
X458850Y309850D01*
Y296550D01*
X458600Y296300D01*
X456700D01*
X455400Y295000D01*
Y294414D01*
X454656D01*
G03X454672Y292986I-1256J-728D01*
G01X455392D01*
Y286700D01*
X454892Y286200D01*
X446392D01*
X445192Y287400D01*
Y294100D01*
X444433Y294859D01*
X387541D01*
X387528Y294846D01*
X365902D01*
X365148Y295600D01*
Y301297D01*
X365754Y301902D01*
X368462D01*
Y301941D01*
X370358D01*
Y301902D01*
X373362D01*
Y301941D01*
X375258D01*
Y301902D01*
X378262D01*
Y301941D01*
X380158D01*
Y301902D01*
X383162D01*
Y301941D01*
X385058D01*
Y301902D01*
X388062D01*
Y301940D01*
X389958Y301938D01*
Y301902D01*
X392962D01*
Y301934D01*
X394858Y301932D01*
Y301902D01*
X397862D01*
Y301928D01*
X399758Y301926D01*
Y301902D01*
X402762D01*
Y301922D01*
X404658Y301920D01*
Y301902D01*
X407662D01*
G37*
G36*
G01X365230Y311000D02*
X364875Y311355D01*
Y316675D01*
X365602Y317402D01*
X368862D01*
Y317500D01*
X370558D01*
Y317402D01*
X373562D01*
Y317500D01*
X375258D01*
Y317402D01*
X378490D01*
X378792Y317100D01*
Y311700D01*
X378653Y311561D01*
X366753D01*
X366192Y311000D01*
X365230D01*
G37*
G36*
G01X421340Y317300D02*
X421316Y317324D01*
X380164D01*
Y320728D01*
X381064Y321628D01*
Y325672D01*
X381692Y326300D01*
X384292D01*
X385392Y327400D01*
Y328900D01*
X386240Y329748D01*
X389394D01*
Y330000D01*
X391290D01*
Y329948D01*
X394294D01*
Y330000D01*
X396190D01*
Y329948D01*
X399194D01*
Y330000D01*
X401090D01*
Y329948D01*
X404094D01*
Y330002D01*
X404692Y330600D01*
X406006D01*
Y330462D01*
X409008D01*
Y330600D01*
X410906D01*
Y330462D01*
X413908D01*
Y330600D01*
X415806D01*
Y330462D01*
X418808D01*
Y330600D01*
X420706D01*
Y330462D01*
X423708D01*
Y330600D01*
X425614D01*
Y330462D01*
X428616D01*
Y330600D01*
X429192D01*
X431992Y327800D01*
X432298D01*
Y327798D01*
X434102D01*
Y327800D01*
X435098D01*
Y327798D01*
X437102D01*
Y327800D01*
X438098D01*
Y327798D01*
X440102D01*
Y327800D01*
X441098D01*
Y327798D01*
X443102D01*
Y327800D01*
X449892D01*
X453092Y324600D01*
Y317800D01*
X452592Y317300D01*
X421340D01*
G37*
G36*
G01X385989Y332000D02*
X385648Y332341D01*
Y336341D01*
X388648Y339341D01*
X405400D01*
X405458Y339398D01*
X421402D01*
X423800Y337000D01*
Y332700D01*
X423600Y332500D01*
X405359D01*
X404859Y332000D01*
X385989D01*
G37*
G36*
G01X365148Y319341D02*
Y326632D01*
X366616Y328100D01*
X372900D01*
X376529Y331729D01*
X383822D01*
Y328390D01*
X380890D01*
X380791Y328291D01*
Y327484D01*
X379870Y326563D01*
Y321931D01*
X377344Y319406D01*
X375258D01*
Y319341D01*
X373562D01*
Y319406D01*
X370558D01*
Y319341D01*
X368862D01*
Y319406D01*
X365858D01*
Y319341D01*
X365148D01*
G37*
G36*
G01X409692Y287000D02*
X409092Y287600D01*
Y293000D01*
X409950Y293858D01*
X443634D01*
X444190Y293302D01*
Y288198D01*
X442992Y287000D01*
X409692D01*
G37*
G36*
G01X430146Y303092D02*
Y303000D01*
X428150D01*
Y303092D01*
X425146D01*
Y303069D01*
X423231D01*
X422400Y303900D01*
X422362D01*
Y303906D01*
X419358D01*
Y303900D01*
X417462D01*
Y303906D01*
X414458D01*
Y303900D01*
X412562D01*
Y303906D01*
X409354D01*
X408902Y304358D01*
Y307645D01*
X410194Y308938D01*
Y314994D01*
X410348Y315148D01*
X412694D01*
Y315300D01*
X414690D01*
Y315148D01*
X417694D01*
Y315300D01*
X419690D01*
Y315148D01*
X422694D01*
Y315300D01*
X424690D01*
Y315148D01*
X427694D01*
Y315300D01*
X429690D01*
Y315148D01*
X432694D01*
Y315300D01*
X434690D01*
Y315148D01*
X437694D01*
Y315300D01*
X439690D01*
Y315148D01*
X442694D01*
Y315198D01*
X443292Y314600D01*
Y311600D01*
X444092Y310800D01*
Y303600D01*
X443492Y303000D01*
X438150D01*
Y303092D01*
X435146D01*
Y303000D01*
X433150D01*
Y303092D01*
X430146D01*
G37*
G36*
G01X380353Y501966D02*
X379171Y503148D01*
Y507408D01*
X379254Y507491D01*
X383019D01*
X383762Y508234D01*
X385521D01*
X387143Y506612D01*
Y503568D01*
X385541Y501966D01*
X380353D01*
G37*
G36*
G01X376366Y545708D02*
X375819Y546254D01*
Y547606D01*
X376872Y548659D01*
Y554191D01*
X376999Y554318D01*
X380388D01*
Y546099D01*
X379997Y545708D01*
X376366D01*
G37*
G36*
G01X376294Y587654D02*
Y592180D01*
X375420D01*
Y592327D01*
X374887Y592860D01*
X373256D01*
X372696Y593420D01*
Y593977D01*
X373485Y594766D01*
X379026D01*
X379888Y593903D01*
Y587654D01*
X376294D01*
G37*
G36*
G01X406800Y534806D02*
X407250Y535256D01*
X445892D01*
X446892Y536256D01*
Y537092D01*
X447745Y537945D01*
X452055D01*
X452700Y537300D01*
Y532400D01*
X448556Y528256D01*
X444886D01*
X443392Y529750D01*
Y529756D01*
X442392Y530756D01*
X421992D01*
X420992Y531756D01*
X407300D01*
X406800Y532256D01*
Y534806D01*
G37*
G36*
G01X399870Y565930D02*
G02X399483Y566430I0J400D01*
G03X397034Y567932I-1454J377D01*
G02X396369Y568232I-265J300D01*
G01Y574648D01*
X397386Y575664D01*
X400050D01*
Y575209D01*
X400040Y575180D01*
G03Y574334I1337J-423D01*
G01X400050Y574305D01*
Y574209D01*
X400117Y574141D01*
X400132Y574113D01*
G03X402712Y575185I1245J645D01*
G01X402702Y575215D01*
Y575664D01*
X403396D01*
Y575209D01*
X403386Y575180D01*
G03X406058Y575185I1337J-423D01*
G01X406048Y575215D01*
Y575664D01*
X409850D01*
Y574858D01*
G03X409851Y574805I1565J3D01*
G01X409852Y574802D01*
Y574757D01*
G03X412972Y574597I1564J0D01*
G02X413370Y574599I199J-20D01*
G03X413426Y574334I1393J156D01*
G01X413436Y574305D01*
Y574209D01*
X413503Y574141D01*
X413518Y574113D01*
G03X416098Y575185I1245J645D01*
G01X416088Y575215D01*
Y575664D01*
X426820D01*
Y575206D01*
X426811Y575177D01*
G03Y574337I1338J-420D01*
G01X426820Y574308D01*
Y574210D01*
X426889Y574141D01*
X426904Y574113D01*
G03X429483Y575188I1245J645D01*
G01X429474Y575218D01*
Y575664D01*
X433514D01*
Y575206D01*
X433504Y575177D01*
G03Y574337I1338J-420D01*
G01X433514Y574308D01*
Y574210D01*
X433582Y574141D01*
X433597Y574113D01*
G03X436176Y575188I1245J645D01*
G01X436166Y575218D01*
Y575664D01*
X436460D01*
G02X436844Y575151I0J-400D01*
G03X439534I1345J-394D01*
G02X439918Y575664I384J113D01*
G01X442398D01*
X443026Y575036D01*
Y566265D01*
X442690Y565930D01*
X439514D01*
Y566361D01*
X439523Y566391D01*
G03X436944Y567466I-1334J430D01*
G01X436929Y567438D01*
X436860Y567369D01*
Y567271D01*
X436851Y567242D01*
G03Y566402I1338J-420D01*
G01X436860Y566373D01*
Y565930D01*
X433335D01*
G02X432948Y566430I0J400D01*
G03X430040I-1454J377D01*
G02X429653Y565930I-387J-100D01*
G01X426642D01*
G02X426255Y566430I0J400D01*
G03X423423Y566210I-1454J377D01*
G01X423439Y566171D01*
Y565930D01*
X422782D01*
Y566364D01*
X422791Y566394D01*
G03X420211Y567466I-1335J427D01*
G01X420196Y567438D01*
X420128Y567370D01*
Y567274D01*
X420119Y567245D01*
G03Y566399I1337J-423D01*
G01X420128Y566370D01*
Y565930D01*
X416088D01*
Y566364D01*
X416098Y566394D01*
G03X413518Y567466I-1335J427D01*
G01X413503Y567438D01*
X413436Y567370D01*
Y567274D01*
X413426Y567245D01*
G03Y566399I1337J-423D01*
G01X413436Y566370D01*
Y565930D01*
X409910D01*
G02X409523Y566430I0J400D01*
G03X406691Y566210I-1454J377D01*
G01X406707Y566171D01*
Y565930D01*
X406048D01*
Y566364D01*
X406058Y566394D01*
G03X403478Y567466I-1335J427D01*
G01X403463Y567438D01*
X403396Y567370D01*
Y567274D01*
X403386Y567245D01*
G03Y566399I1337J-423D01*
G01X403396Y566370D01*
Y565930D01*
X399870D01*
G37*
G36*
G01X364044Y591764D02*
X364595Y592315D01*
X364719Y592261D01*
G03X366692Y594234I592J1381D01*
G01X366638Y594358D01*
X366920Y594640D01*
X368430D01*
X368660Y594410D01*
Y592530D01*
X369450Y591740D01*
X372820D01*
X373290Y591270D01*
Y587654D01*
X369476D01*
X368524Y586701D01*
Y584560D01*
X366011D01*
G02X365644Y585119I0J400D01*
G03X364387Y587211I-1379J595D01*
G02X364020Y587610I33J399D01*
G01Y587848D01*
X364044D01*
Y591764D01*
G37*
G36*
G01X416117Y584134D02*
G02X415808Y584787I1J400D01*
G03X415790Y586676I-1045J935D01*
G02X416083Y587348I293J272D01*
G01X419402D01*
Y588498D01*
X419989D01*
X420028Y588480D01*
G03Y591120I606J1320D01*
G01X419989Y591102D01*
X419402D01*
Y592252D01*
X416258D01*
G02X415926Y592875I0J400D01*
G03X416129Y593975I-1163J783D01*
G02X416523Y594443I394J68D01*
G01X419696D01*
G02X420090Y593975I0J-400D01*
G03X422822I1366J-318D01*
G02X423216Y594443I394J68D01*
G01X423516D01*
Y594204D01*
X423501Y594168D01*
G03X423922Y592550I1300J-526D01*
G03X426146Y593247I879J1092D01*
G03X426168Y593954I-1345J396D01*
G02X426558Y594443I390J89D01*
G01X429737D01*
G02X430127Y593954I0J-400D01*
G03X430323Y592871I1367J-312D01*
G02X429989Y592252I-334J-219D01*
G01X427898D01*
Y591752D01*
X426398D01*
Y587848D01*
X427898D01*
Y587110D01*
X427755Y587067D01*
G03X427104Y584787I394J-1345D01*
G02X426795Y584134I-310J-253D01*
G01X422170D01*
Y584511D01*
X422256Y584571D01*
G03X421621Y587114I-800J1151D01*
G03X420654Y584571I-166J-1392D01*
G01X420740Y584512D01*
Y584134D01*
X416117D01*
G37*
G36*
G01X397358D02*
X396369Y585123D01*
Y592354D01*
G02X397037Y592651I400J0D01*
G03X399369Y593231I992J991D01*
G03X399396Y593954I-1340J412D01*
G02X399786Y594443I390J89D01*
G01X402963D01*
G02X403357Y593975I0J-400D01*
G03X403560Y592875I1366J-317D01*
G02X403228Y592252I-332J-223D01*
G01X402448D01*
Y591752D01*
X400948D01*
Y587848D01*
X402448D01*
Y587348D01*
X403403D01*
G02X403696Y586676I0J-400D01*
G03X403678Y584787I1027J-954D01*
G02X403369Y584134I-310J-253D01*
G01X402731D01*
G02X402422Y584787I1J400D01*
G03X400332I-1045J935D01*
G02X400023Y584134I-310J-253D01*
G01X397358D01*
G37*
G36*
G01X406077D02*
G02X405768Y584787I1J400D01*
G03X405750Y586676I-1045J935D01*
G02X406043Y587348I293J272D01*
G01X406952D01*
Y588498D01*
X407539D01*
X407578Y588480D01*
G03Y591120I606J1320D01*
G01X407539Y591102D01*
X406952D01*
Y591989D01*
G02X407511Y592356I400J0D01*
G03X409414Y593247I558J1286D01*
G03X409436Y593954I-1345J396D01*
G02X409826Y594443I390J89D01*
G01X413003D01*
G02X413397Y593975I0J-400D01*
G03X414707Y592256I1366J-318D01*
G02X414898Y592056I-9J-200D01*
G01Y591752D01*
X413398D01*
Y587848D01*
X414898D01*
Y587323D01*
G02X414707Y587123I-200J0D01*
G03X413718Y584787I56J-1401D01*
G02X413409Y584134I-310J-253D01*
G01X412770D01*
G02X412461Y584787I1J400D01*
G03X410371I-1045J935D01*
G02X410062Y584134I-310J-253D01*
G01X406077D01*
G37*
G36*
G01Y546334D02*
G02X405768Y546987I1J400D01*
G03X405750Y548876I-1045J935D01*
G02X406043Y549548I293J272D01*
G01X406952D01*
Y550698D01*
X407539D01*
X407578Y550680D01*
G03Y553320I606J1320D01*
G01X407539Y553302D01*
X406952D01*
Y554189D01*
G02X407511Y554556I400J0D01*
G03X409414Y555447I558J1286D01*
G03X409436Y556154I-1345J396D01*
G02X409826Y556643I390J89D01*
G01X413003D01*
G02X413397Y556175I0J-400D01*
G03X414707Y554456I1366J-318D01*
G02X414898Y554256I-9J-200D01*
G01Y553952D01*
X413398D01*
Y550048D01*
X414898D01*
Y549523D01*
G02X414707Y549323I-200J0D01*
G03X413718Y546987I56J-1401D01*
G02X413409Y546334I-310J-253D01*
G01X412770D01*
G02X412462Y546988I1J400D01*
G03X412608Y547185I-1049J930D01*
G03X410679Y549114I-1192J737D01*
G03X410383Y546972I736J-1193D01*
G02X410062Y546334I-322J-238D01*
G01X406077D01*
G37*
G36*
G01X416117D02*
G02X415808Y546987I1J400D01*
G03X415790Y548876I-1045J935D01*
G02X416083Y549548I293J272D01*
G01X419402D01*
Y550698D01*
X420723D01*
X420762Y550680D01*
G03Y553320I606J1320D01*
G01X420723Y553302D01*
X419402D01*
Y554452D01*
X416258D01*
G02X415926Y555075I0J400D01*
G03X416129Y556175I-1163J783D01*
G02X416523Y556643I394J68D01*
G01X419696D01*
G02X420090Y556175I0J-400D01*
G03X422822I1366J-318D01*
G02X423216Y556643I394J68D01*
G01X423516D01*
Y556404D01*
X423501Y556368D01*
G03X423922Y554750I1300J-526D01*
G03X426146Y555447I879J1092D01*
G03X426168Y556154I-1345J396D01*
G02X426558Y556643I390J89D01*
G01X429737D01*
G02X430127Y556154I0J-400D01*
G03X430323Y555071I1367J-312D01*
G02X429989Y554452I-334J-219D01*
G01X427898D01*
Y553952D01*
X426398D01*
Y550048D01*
X427898D01*
Y549310D01*
X427755Y549267D01*
G03X427104Y546987I394J-1345D01*
G02X426795Y546334I-310J-253D01*
G01X422810D01*
G02X422501Y546987I1J400D01*
G03X420411I-1045J935D01*
G02X420102Y546334I-310J-253D01*
G01X416117D01*
G37*
G36*
G01X397358D02*
X396369Y547323D01*
Y554554D01*
G02X397037Y554851I400J0D01*
G03X399369Y555431I992J991D01*
G03X399396Y556154I-1340J412D01*
G02X399786Y556643I390J89D01*
G01X402963D01*
G02X403357Y556175I0J-400D01*
G03X403560Y555075I1366J-317D01*
G02X403228Y554452I-332J-223D01*
G01X402448D01*
Y553952D01*
X400948D01*
Y550048D01*
X402448D01*
Y549548D01*
X403403D01*
G02X403696Y548876I0J-400D01*
G03X403678Y546987I1027J-954D01*
G02X403369Y546334I-310J-253D01*
G01X402730D01*
G02X402421Y546987I1J400D01*
G03X400331I-1045J935D01*
G02X400022Y546334I-310J-253D01*
G01X397358D01*
G37*
G36*
G01X356182Y546815D02*
G02X355815Y547372I1J400D01*
G03X355745Y548613I-1290J550D01*
G02X356093Y549210I348J197D01*
G01X356894D01*
X356933Y549191D01*
G03X358626Y549548I606J1320D01*
G01X360071D01*
G02X360375Y548889I0J-400D01*
G03X360121Y547362I1143J-975D01*
G02X359749Y546815I-372J-147D01*
G01X356182D01*
G37*
G36*
G01X355752Y554412D02*
Y554452D01*
X355581D01*
X355449Y554802D01*
G03X355909Y556087I-923J1055D01*
G02X356300Y556553I394J66D01*
G01X356700Y556953D01*
Y562300D01*
X357100Y562700D01*
X358600D01*
X359000Y562300D01*
Y556953D01*
X359400Y556553D01*
X359444D01*
G02X359838Y556088I-1J-400D01*
G03X360038Y555060I1482J-245D01*
G02X359696Y554452I-342J-208D01*
G01X358940D01*
Y554412D01*
X358184D01*
X358145Y554431D01*
G03X356933I-606J-1320D01*
G01X356894Y554412D01*
X355752D01*
G37*
G36*
G01X356182Y584615D02*
G02X355815Y585172I1J400D01*
G03X355881Y585367I-1291J546D01*
G03X355922Y585843I-1356J357D01*
G03X355899Y586002I-1397J-121D01*
G02X356294Y586464I395J62D01*
G01X356798D01*
G03X358405Y587348I0J1902D01*
G01X359790D01*
Y586552D01*
X359290D01*
Y584615D01*
X356182D01*
G37*
G36*
G01X365490Y547002D02*
Y547045D01*
G03Y548783I-1225J869D01*
G01Y554659D01*
G03X365909Y556512I-925J1183D01*
G02X366267Y557090I358J178D01*
G01X371750D01*
X373880Y554960D01*
Y554080D01*
X373840D01*
Y549076D01*
X373880D01*
Y547250D01*
X373632Y547002D01*
X370585D01*
X369784Y546200D01*
X366292D01*
X365490Y547002D01*
G37*
G36*
G01X372660Y535488D02*
X370062Y538086D01*
Y545062D01*
X371000Y546000D01*
X374657D01*
X375951Y544706D01*
X380412D01*
X381390Y545684D01*
Y556020D01*
X379110Y558300D01*
X370692D01*
X370262Y558730D01*
Y566138D01*
G03X370248Y566397I-2351J3D01*
G01X370247Y566408D01*
Y579447D01*
X370266Y579466D01*
Y584626D01*
X369540Y585352D01*
X369525D01*
Y586286D01*
X369891Y586652D01*
X380783D01*
X380890Y586759D01*
Y594318D01*
X379441Y595767D01*
X373070D01*
X371695Y594392D01*
Y593228D01*
X371267Y592800D01*
X370568D01*
X370268Y593100D01*
Y605335D01*
X370266Y605337D01*
Y618462D01*
X370092Y618636D01*
Y620100D01*
X370792Y620800D01*
X384125D01*
X384155Y620790D01*
G03X384730Y620698I576J1760D01*
G01X386748D01*
X386849Y620800D01*
X391200D01*
X393018Y618982D01*
Y592139D01*
X392471Y591592D01*
G02X391788Y591875I-283J283D01*
G01Y592129D01*
G03X384586I-3601J0D01*
G01Y587229D01*
G03X390564Y584523I3601J0D01*
G02X391228Y584222I264J-301D01*
G01Y576212D01*
G02X390564Y575911I-400J0D01*
G03X384586Y573205I-2377J-2706D01*
G01Y568305D01*
G03X391788I3601J0D01*
G01Y571925D01*
G02X392471Y572208I400J0D01*
G01X393018Y571661D01*
Y555120D01*
X392440Y554543D01*
G02X391761Y554776I-282J283D01*
G03X384586Y554329I-3574J-447D01*
G01Y549429D01*
G03X390665Y546816I3601J0D01*
G02X391340Y546526I275J-290D01*
G01Y538308D01*
G02X390665Y538018I-400J0D01*
G03X384641Y536035I-2478J-2613D01*
G01X384630Y535973D01*
X384145Y535488D01*
X372660D01*
G37*
G36*
G01X399859Y603581D02*
G02X399474Y604090I0J400D01*
G03X397034Y605624I-1445J409D01*
G02X396369Y605924I-265J300D01*
G01Y612448D01*
X397427Y613506D01*
X399528D01*
G02X399916Y613012I-1J-400D01*
G03X402765Y613230I1460J-354D01*
G01X402750Y613266D01*
Y613506D01*
X403396D01*
Y610570D01*
X403375Y610528D01*
G03X406069I1347J-664D01*
G01X406048Y610570D01*
Y613506D01*
X409850D01*
Y609864D01*
G03X412980I1565J0D01*
G01Y611350D01*
G02X413670Y611625I400J0D01*
G03X416221Y613012I1091J1032D01*
G02X416609Y613506I389J94D01*
G01X419684D01*
G02X420067Y612988I1J-400D01*
G03X422841I1387J-428D01*
G02X423224Y613506I382J118D01*
G01X426299D01*
G02X426687Y613012I-1J-400D01*
G03X429607I1460J-355D01*
G02X429995Y613506I389J94D01*
G01X432992D01*
G02X433380Y613012I-1J-400D01*
G03X436229Y613230I1460J-354D01*
G01X436213Y613266D01*
Y613506D01*
X436860D01*
Y610570D01*
X436840Y610528D01*
G03X439534I1347J-664D01*
G01X439514Y610570D01*
Y613506D01*
X442356D01*
X443026Y612836D01*
Y604065D01*
X442542Y603581D01*
X439514D01*
Y603908D01*
X439534Y603950D01*
G03X436840I-1347J664D01*
G01X436860Y603908D01*
Y603581D01*
X433324D01*
G02X432939Y604090I0J400D01*
G03X430049I-1445J409D01*
G02X429664Y603581I-385J-109D01*
G01X426128D01*
Y603908D01*
X426148Y603950D01*
G03X423454I-1347J664D01*
G01X423474Y603908D01*
Y603581D01*
X422782D01*
Y606588D01*
X422802Y606630D01*
G03X420108Y606626I-1348J662D01*
G01X420128Y606584D01*
Y603581D01*
X416088D01*
Y606588D01*
X416109Y606630D01*
G03X413415Y606626I-1348J662D01*
G01X413436Y606584D01*
Y603581D01*
X409396D01*
Y606588D01*
X409416Y606630D01*
G03X406722Y606626I-1348J662D01*
G01X406742Y606584D01*
Y603581D01*
X406065D01*
Y603825D01*
X406084Y603865D01*
G03X403277Y604090I-1362J634D01*
G02X402892Y603581I-385J-109D01*
G01X399859D01*
G37*
G36*
G01X357499Y592240D02*
X357456Y592262D01*
G03X356160Y592272I-658J-1295D01*
G01X356119Y592252D01*
X356022D01*
G02X355690Y592875I0J400D01*
G03X355737Y592950I-1164J782D01*
G03X355913Y593864I-1211J707D01*
G02X356308Y594323I395J59D01*
G01X360083D01*
G02X360478Y593864I0J-400D01*
G03X360681Y592860I1486J-222D01*
G02X360340Y592252I-341J-208D01*
G01X358040D01*
Y592240D01*
X357499D01*
G37*
G36*
G01X450571Y-345D02*
X450400Y-174D01*
Y6183D01*
X449766Y6818D01*
Y11727D01*
X448911Y12582D01*
X447526D01*
X446768Y11824D01*
Y10669D01*
X446627Y10528D01*
X446261D01*
X446089Y10700D01*
Y16330D01*
X446900Y17141D01*
Y26300D01*
X447242Y26642D01*
X449069D01*
X449300Y26411D01*
Y19405D01*
X450065Y18640D01*
Y16508D01*
X450924Y15649D01*
X452528D01*
X453500Y16621D01*
Y26300D01*
X453900Y26700D01*
X455700D01*
X455854Y26546D01*
Y17254D01*
X455872Y17235D01*
Y13814D01*
G02X455293Y13456I-400J0D01*
G03X454731Y10616I-674J-1342D01*
G02X455043Y9934I29J-399D01*
G01X453004Y7896D01*
Y104D01*
X452555Y-345D01*
X450571D01*
G37*
G36*
G01X448420Y45136D02*
X446220Y47336D01*
X446205Y47379D01*
G03X446184Y47437I-1328J-448D01*
G01X446170Y47472D01*
Y54213D01*
X448519Y56562D01*
X450101D01*
G02X450411Y55909I0J-400D01*
G03X452735I1162J-952D01*
G02X453045Y56562I310J253D01*
G01X454082D01*
X455710Y54935D01*
Y51336D01*
G02X455165Y50963I-400J0D01*
G03Y48165I-546J-1399D01*
G02X455710Y47792I145J-373D01*
G01Y45833D01*
X455013Y45136D01*
X448420D01*
G37*
G36*
G01X422673Y165522D02*
X421923Y165572D01*
Y165972D01*
X422673Y166022D01*
X422873D01*
Y165522D01*
X422673D01*
G37*
G36*
G01Y170722D02*
X421923Y170772D01*
Y171172D01*
X422673Y171222D01*
X422873D01*
Y170722D01*
X422673D01*
G37*
G36*
G01X423073Y172522D02*
X423823Y172472D01*
Y172072D01*
X423073Y172022D01*
X422873D01*
Y172522D01*
X423073D01*
G37*
G36*
G01Y169922D02*
X423823Y169872D01*
Y169472D01*
X423073Y169422D01*
X422873D01*
Y169922D01*
X423073D01*
G37*
G36*
G01X422673Y168122D02*
X421923Y168172D01*
Y168572D01*
X422673Y168622D01*
X422873D01*
Y168122D01*
X422673D01*
G37*
G36*
G01X423073Y167322D02*
X423823Y167272D01*
Y166872D01*
X423073Y166822D01*
X422873D01*
Y167322D01*
X423073D01*
G37*
G36*
G01X422673Y181122D02*
X421923Y181172D01*
Y181572D01*
X422673Y181622D01*
X422873D01*
Y181122D01*
X422673D01*
G37*
G36*
G01Y186322D02*
X421923Y186372D01*
Y186772D01*
X422673Y186822D01*
X422873D01*
Y186322D01*
X422673D01*
G37*
G36*
G01Y188922D02*
X421923Y188972D01*
Y189372D01*
X422673Y189422D01*
X422873D01*
Y188922D01*
X422673D01*
G37*
G36*
G01Y191522D02*
X421923Y191572D01*
Y191972D01*
X422673Y192022D01*
X422873D01*
Y191522D01*
X422673D01*
G37*
G36*
G01Y194122D02*
X421923Y194172D01*
Y194572D01*
X422673Y194622D01*
X422873D01*
Y194122D01*
X422673D01*
G37*
G36*
G01Y178522D02*
X421923Y178572D01*
Y178972D01*
X422673Y179022D01*
X422873D01*
Y178522D01*
X422673D01*
G37*
G36*
G01Y175922D02*
X421923Y175972D01*
Y176372D01*
X422673Y176422D01*
X422873D01*
Y175922D01*
X422673D01*
G37*
G36*
G01Y173322D02*
X421923Y173372D01*
Y173772D01*
X422673Y173822D01*
X422873D01*
Y173322D01*
X422673D01*
G37*
G36*
G01X423073Y182922D02*
X423823Y182872D01*
Y182472D01*
X423073Y182422D01*
X422873D01*
Y182922D01*
X423073D01*
G37*
G36*
G01Y185522D02*
X423823Y185472D01*
Y185072D01*
X423073Y185022D01*
X422873D01*
Y185522D01*
X423073D01*
G37*
G36*
G01Y188122D02*
X423823Y188072D01*
Y187672D01*
X423073Y187622D01*
X422873D01*
Y188122D01*
X423073D01*
G37*
G36*
G01Y190722D02*
X423823Y190672D01*
Y190272D01*
X423073Y190222D01*
X422873D01*
Y190722D01*
X423073D01*
G37*
G36*
G01Y193322D02*
X423823Y193272D01*
Y192872D01*
X423073Y192822D01*
X422873D01*
Y193322D01*
X423073D01*
G37*
G36*
G01Y180322D02*
X423823Y180272D01*
Y179872D01*
X423073Y179822D01*
X422873D01*
Y180322D01*
X423073D01*
G37*
G36*
G01Y177722D02*
X423823Y177672D01*
Y177272D01*
X423073Y177222D01*
X422873D01*
Y177722D01*
X423073D01*
G37*
G36*
G01Y175122D02*
X423823Y175072D01*
Y174672D01*
X423073Y174622D01*
X422873D01*
Y175122D01*
X423073D01*
G37*
G36*
G01X422673Y183722D02*
X421923Y183772D01*
Y184172D01*
X422673Y184222D01*
X422873D01*
Y183722D01*
X422673D01*
G37*
G36*
G01X424223Y165522D02*
X423473Y165572D01*
Y165972D01*
X424223Y166022D01*
X424423D01*
Y165522D01*
X424223D01*
G37*
G36*
G01Y170722D02*
X423473Y170772D01*
Y171172D01*
X424223Y171222D01*
X424423D01*
Y170722D01*
X424223D01*
G37*
G36*
G01X424623Y172522D02*
X425373Y172472D01*
Y172072D01*
X424623Y172022D01*
X424423D01*
Y172522D01*
X424623D01*
G37*
G36*
G01Y169922D02*
X425373Y169872D01*
Y169472D01*
X424623Y169422D01*
X424423D01*
Y169922D01*
X424623D01*
G37*
G36*
G01X424223Y168122D02*
X423473Y168172D01*
Y168572D01*
X424223Y168622D01*
X424423D01*
Y168122D01*
X424223D01*
G37*
G36*
G01X424623Y167322D02*
X425373Y167272D01*
Y166872D01*
X424623Y166822D01*
X424423D01*
Y167322D01*
X424623D01*
G37*
G36*
G01X424223Y175922D02*
X423473Y175972D01*
Y176372D01*
X424223Y176422D01*
X424423D01*
Y175922D01*
X424223D01*
G37*
G36*
G01Y173322D02*
X423473Y173372D01*
Y173772D01*
X424223Y173822D01*
X424423D01*
Y173322D01*
X424223D01*
G37*
G36*
G01Y178522D02*
X423473Y178572D01*
Y178972D01*
X424223Y179022D01*
X424423D01*
Y178522D01*
X424223D01*
G37*
G36*
G01Y181122D02*
X423473Y181172D01*
Y181572D01*
X424223Y181622D01*
X424423D01*
Y181122D01*
X424223D01*
G37*
G36*
G01Y183722D02*
X423473Y183772D01*
Y184172D01*
X424223Y184222D01*
X424423D01*
Y183722D01*
X424223D01*
G37*
G36*
G01Y186322D02*
X423473Y186372D01*
Y186772D01*
X424223Y186822D01*
X424423D01*
Y186322D01*
X424223D01*
G37*
G36*
G01Y188922D02*
X423473Y188972D01*
Y189372D01*
X424223Y189422D01*
X424423D01*
Y188922D01*
X424223D01*
G37*
G36*
G01Y191522D02*
X423473Y191572D01*
Y191972D01*
X424223Y192022D01*
X424423D01*
Y191522D01*
X424223D01*
G37*
G36*
G01Y194122D02*
X423473Y194172D01*
Y194572D01*
X424223Y194622D01*
X424423D01*
Y194122D01*
X424223D01*
G37*
G36*
G01X424623Y177722D02*
X425373Y177672D01*
Y177272D01*
X424623Y177222D01*
X424423D01*
Y177722D01*
X424623D01*
G37*
G36*
G01Y175122D02*
X425373Y175072D01*
Y174672D01*
X424623Y174622D01*
X424423D01*
Y175122D01*
X424623D01*
G37*
G36*
G01Y180322D02*
X425373Y180272D01*
Y179872D01*
X424623Y179822D01*
X424423D01*
Y180322D01*
X424623D01*
G37*
G36*
G01Y182922D02*
X425373Y182872D01*
Y182472D01*
X424623Y182422D01*
X424423D01*
Y182922D01*
X424623D01*
G37*
G36*
G01Y185522D02*
X425373Y185472D01*
Y185072D01*
X424623Y185022D01*
X424423D01*
Y185522D01*
X424623D01*
G37*
G36*
G01Y188122D02*
X425373Y188072D01*
Y187672D01*
X424623Y187622D01*
X424423D01*
Y188122D01*
X424623D01*
G37*
G36*
G01Y190722D02*
X425373Y190672D01*
Y190272D01*
X424623Y190222D01*
X424423D01*
Y190722D01*
X424623D01*
G37*
G36*
G01Y193322D02*
X425373Y193272D01*
Y192872D01*
X424623Y192822D01*
X424423D01*
Y193322D01*
X424623D01*
G37*
G36*
G01X435073Y165522D02*
X434323Y165572D01*
Y165972D01*
X435073Y166022D01*
X435273D01*
Y165522D01*
X435073D01*
G37*
G36*
G01Y168122D02*
X434323Y168172D01*
Y168572D01*
X435073Y168622D01*
X435273D01*
Y168122D01*
X435073D01*
G37*
G36*
G01Y170722D02*
X434323Y170772D01*
Y171172D01*
X435073Y171222D01*
X435273D01*
Y170722D01*
X435073D01*
G37*
G36*
G01X435473Y172522D02*
X436223Y172472D01*
Y172072D01*
X435473Y172022D01*
X435273D01*
Y172522D01*
X435473D01*
G37*
G36*
G01Y169922D02*
X436223Y169872D01*
Y169472D01*
X435473Y169422D01*
X435273D01*
Y169922D01*
X435473D01*
G37*
G36*
G01Y167322D02*
X436223Y167272D01*
Y166872D01*
X435473Y166822D01*
X435273D01*
Y167322D01*
X435473D01*
G37*
G36*
G01X435073Y175922D02*
X434323Y175972D01*
Y176372D01*
X435073Y176422D01*
X435273D01*
Y175922D01*
X435073D01*
G37*
G36*
G01Y173322D02*
X434323Y173372D01*
Y173772D01*
X435073Y173822D01*
X435273D01*
Y173322D01*
X435073D01*
G37*
G36*
G01Y178522D02*
X434323Y178572D01*
Y178972D01*
X435073Y179022D01*
X435273D01*
Y178522D01*
X435073D01*
G37*
G36*
G01Y181122D02*
X434323Y181172D01*
Y181572D01*
X435073Y181622D01*
X435273D01*
Y181122D01*
X435073D01*
G37*
G36*
G01Y183722D02*
X434323Y183772D01*
Y184172D01*
X435073Y184222D01*
X435273D01*
Y183722D01*
X435073D01*
G37*
G36*
G01Y186322D02*
X434323Y186372D01*
Y186772D01*
X435073Y186822D01*
X435273D01*
Y186322D01*
X435073D01*
G37*
G36*
G01Y188922D02*
X434323Y188972D01*
Y189372D01*
X435073Y189422D01*
X435273D01*
Y188922D01*
X435073D01*
G37*
G36*
G01Y191522D02*
X434323Y191572D01*
Y191972D01*
X435073Y192022D01*
X435273D01*
Y191522D01*
X435073D01*
G37*
G36*
G01Y194122D02*
X434323Y194172D01*
Y194572D01*
X435073Y194622D01*
X435273D01*
Y194122D01*
X435073D01*
G37*
G36*
G01X435473Y177722D02*
X436223Y177672D01*
Y177272D01*
X435473Y177222D01*
X435273D01*
Y177722D01*
X435473D01*
G37*
G36*
G01Y175122D02*
X436223Y175072D01*
Y174672D01*
X435473Y174622D01*
X435273D01*
Y175122D01*
X435473D01*
G37*
G36*
G01Y180322D02*
X436223Y180272D01*
Y179872D01*
X435473Y179822D01*
X435273D01*
Y180322D01*
X435473D01*
G37*
G36*
G01Y182922D02*
X436223Y182872D01*
Y182472D01*
X435473Y182422D01*
X435273D01*
Y182922D01*
X435473D01*
G37*
G36*
G01Y185522D02*
X436223Y185472D01*
Y185072D01*
X435473Y185022D01*
X435273D01*
Y185522D01*
X435473D01*
G37*
G36*
G01Y188122D02*
X436223Y188072D01*
Y187672D01*
X435473Y187622D01*
X435273D01*
Y188122D01*
X435473D01*
G37*
G36*
G01Y190722D02*
X436223Y190672D01*
Y190272D01*
X435473Y190222D01*
X435273D01*
Y190722D01*
X435473D01*
G37*
G36*
G01Y193322D02*
X436223Y193272D01*
Y192872D01*
X435473Y192822D01*
X435273D01*
Y193322D01*
X435473D01*
G37*
G36*
G01X436623Y165522D02*
X435873Y165572D01*
Y165972D01*
X436623Y166022D01*
X436823D01*
Y165522D01*
X436623D01*
G37*
G36*
G01X437023Y172522D02*
X437773Y172472D01*
Y172072D01*
X437023Y172022D01*
X436823D01*
Y172522D01*
X437023D01*
G37*
G36*
G01Y169922D02*
X437773Y169872D01*
Y169472D01*
X437023Y169422D01*
X436823D01*
Y169922D01*
X437023D01*
G37*
G36*
G01X436623Y170722D02*
X435873Y170772D01*
Y171172D01*
X436623Y171222D01*
X436823D01*
Y170722D01*
X436623D01*
G37*
G36*
G01X437023Y167322D02*
X437773Y167272D01*
Y166872D01*
X437023Y166822D01*
X436823D01*
Y167322D01*
X437023D01*
G37*
G36*
G01X436623Y168122D02*
X435873Y168172D01*
Y168572D01*
X436623Y168622D01*
X436823D01*
Y168122D01*
X436623D01*
G37*
G36*
G01X437023Y182922D02*
X437773Y182872D01*
Y182472D01*
X437023Y182422D01*
X436823D01*
Y182922D01*
X437023D01*
G37*
G36*
G01Y185522D02*
X437773Y185472D01*
Y185072D01*
X437023Y185022D01*
X436823D01*
Y185522D01*
X437023D01*
G37*
G36*
G01Y188122D02*
X437773Y188072D01*
Y187672D01*
X437023Y187622D01*
X436823D01*
Y188122D01*
X437023D01*
G37*
G36*
G01Y190722D02*
X437773Y190672D01*
Y190272D01*
X437023Y190222D01*
X436823D01*
Y190722D01*
X437023D01*
G37*
G36*
G01Y193322D02*
X437773Y193272D01*
Y192872D01*
X437023Y192822D01*
X436823D01*
Y193322D01*
X437023D01*
G37*
G36*
G01Y180322D02*
X437773Y180272D01*
Y179872D01*
X437023Y179822D01*
X436823D01*
Y180322D01*
X437023D01*
G37*
G36*
G01Y177722D02*
X437773Y177672D01*
Y177272D01*
X437023Y177222D01*
X436823D01*
Y177722D01*
X437023D01*
G37*
G36*
G01Y175122D02*
X437773Y175072D01*
Y174672D01*
X437023Y174622D01*
X436823D01*
Y175122D01*
X437023D01*
G37*
G36*
G01X436623Y183722D02*
X435873Y183772D01*
Y184172D01*
X436623Y184222D01*
X436823D01*
Y183722D01*
X436623D01*
G37*
G36*
G01Y186322D02*
X435873Y186372D01*
Y186772D01*
X436623Y186822D01*
X436823D01*
Y186322D01*
X436623D01*
G37*
G36*
G01Y188922D02*
X435873Y188972D01*
Y189372D01*
X436623Y189422D01*
X436823D01*
Y188922D01*
X436623D01*
G37*
G36*
G01Y191522D02*
X435873Y191572D01*
Y191972D01*
X436623Y192022D01*
X436823D01*
Y191522D01*
X436623D01*
G37*
G36*
G01Y194122D02*
X435873Y194172D01*
Y194572D01*
X436623Y194622D01*
X436823D01*
Y194122D01*
X436623D01*
G37*
G36*
G01Y181122D02*
X435873Y181172D01*
Y181572D01*
X436623Y181622D01*
X436823D01*
Y181122D01*
X436623D01*
G37*
G36*
G01Y178522D02*
X435873Y178572D01*
Y178972D01*
X436623Y179022D01*
X436823D01*
Y178522D01*
X436623D01*
G37*
G36*
G01Y175922D02*
X435873Y175972D01*
Y176372D01*
X436623Y176422D01*
X436823D01*
Y175922D01*
X436623D01*
G37*
G36*
G01Y173322D02*
X435873Y173372D01*
Y173772D01*
X436623Y173822D01*
X436823D01*
Y173322D01*
X436623D01*
G37*
G36*
G01X419573Y165522D02*
X418823Y165572D01*
Y165972D01*
X419573Y166022D01*
X419773D01*
Y165522D01*
X419573D01*
G37*
G36*
G01Y170722D02*
X418823Y170772D01*
Y171172D01*
X419573Y171222D01*
X419773D01*
Y170722D01*
X419573D01*
G37*
G36*
G01X419973Y172522D02*
X420723Y172472D01*
Y172072D01*
X419973Y172022D01*
X419773D01*
Y172522D01*
X419973D01*
G37*
G36*
G01Y169922D02*
X420723Y169872D01*
Y169472D01*
X419973Y169422D01*
X419773D01*
Y169922D01*
X419973D01*
G37*
G36*
G01X419573Y168122D02*
X418823Y168172D01*
Y168572D01*
X419573Y168622D01*
X419773D01*
Y168122D01*
X419573D01*
G37*
G36*
G01X419973Y167322D02*
X420723Y167272D01*
Y166872D01*
X419973Y166822D01*
X419773D01*
Y167322D01*
X419973D01*
G37*
G36*
G01X419573Y183722D02*
X418823Y183772D01*
Y184172D01*
X419573Y184222D01*
X419773D01*
Y183722D01*
X419573D01*
G37*
G36*
G01Y186322D02*
X418823Y186372D01*
Y186772D01*
X419573Y186822D01*
X419773D01*
Y186322D01*
X419573D01*
G37*
G36*
G01Y188922D02*
X418823Y188972D01*
Y189372D01*
X419573Y189422D01*
X419773D01*
Y188922D01*
X419573D01*
G37*
G36*
G01Y191522D02*
X418823Y191572D01*
Y191972D01*
X419573Y192022D01*
X419773D01*
Y191522D01*
X419573D01*
G37*
G36*
G01Y194122D02*
X418823Y194172D01*
Y194572D01*
X419573Y194622D01*
X419773D01*
Y194122D01*
X419573D01*
G37*
G36*
G01Y181122D02*
X418823Y181172D01*
Y181572D01*
X419573Y181622D01*
X419773D01*
Y181122D01*
X419573D01*
G37*
G36*
G01Y178522D02*
X418823Y178572D01*
Y178972D01*
X419573Y179022D01*
X419773D01*
Y178522D01*
X419573D01*
G37*
G36*
G01Y175922D02*
X418823Y175972D01*
Y176372D01*
X419573Y176422D01*
X419773D01*
Y175922D01*
X419573D01*
G37*
G36*
G01Y173322D02*
X418823Y173372D01*
Y173772D01*
X419573Y173822D01*
X419773D01*
Y173322D01*
X419573D01*
G37*
G36*
G01X419973Y182922D02*
X420723Y182872D01*
Y182472D01*
X419973Y182422D01*
X419773D01*
Y182922D01*
X419973D01*
G37*
G36*
G01Y185522D02*
X420723Y185472D01*
Y185072D01*
X419973Y185022D01*
X419773D01*
Y185522D01*
X419973D01*
G37*
G36*
G01Y188122D02*
X420723Y188072D01*
Y187672D01*
X419973Y187622D01*
X419773D01*
Y188122D01*
X419973D01*
G37*
G36*
G01Y190722D02*
X420723Y190672D01*
Y190272D01*
X419973Y190222D01*
X419773D01*
Y190722D01*
X419973D01*
G37*
G36*
G01Y193322D02*
X420723Y193272D01*
Y192872D01*
X419973Y192822D01*
X419773D01*
Y193322D01*
X419973D01*
G37*
G36*
G01Y180322D02*
X420723Y180272D01*
Y179872D01*
X419973Y179822D01*
X419773D01*
Y180322D01*
X419973D01*
G37*
G36*
G01Y177722D02*
X420723Y177672D01*
Y177272D01*
X419973Y177222D01*
X419773D01*
Y177722D01*
X419973D01*
G37*
G36*
G01Y175122D02*
X420723Y175072D01*
Y174672D01*
X419973Y174622D01*
X419773D01*
Y175122D01*
X419973D01*
G37*
G36*
G01X421123Y165522D02*
X420373Y165572D01*
Y165972D01*
X421123Y166022D01*
X421323D01*
Y165522D01*
X421123D01*
G37*
G36*
G01Y170722D02*
X420373Y170772D01*
Y171172D01*
X421123Y171222D01*
X421323D01*
Y170722D01*
X421123D01*
G37*
G36*
G01X421523Y172522D02*
X422273Y172472D01*
Y172072D01*
X421523Y172022D01*
X421323D01*
Y172522D01*
X421523D01*
G37*
G36*
G01Y169922D02*
X422273Y169872D01*
Y169472D01*
X421523Y169422D01*
X421323D01*
Y169922D01*
X421523D01*
G37*
G36*
G01X421123Y168122D02*
X420373Y168172D01*
Y168572D01*
X421123Y168622D01*
X421323D01*
Y168122D01*
X421123D01*
G37*
G36*
G01X421523Y167322D02*
X422273Y167272D01*
Y166872D01*
X421523Y166822D01*
X421323D01*
Y167322D01*
X421523D01*
G37*
G36*
G01X421123Y175922D02*
X420373Y175972D01*
Y176372D01*
X421123Y176422D01*
X421323D01*
Y175922D01*
X421123D01*
G37*
G36*
G01Y173322D02*
X420373Y173372D01*
Y173772D01*
X421123Y173822D01*
X421323D01*
Y173322D01*
X421123D01*
G37*
G36*
G01Y178522D02*
X420373Y178572D01*
Y178972D01*
X421123Y179022D01*
X421323D01*
Y178522D01*
X421123D01*
G37*
G36*
G01Y181122D02*
X420373Y181172D01*
Y181572D01*
X421123Y181622D01*
X421323D01*
Y181122D01*
X421123D01*
G37*
G36*
G01Y183722D02*
X420373Y183772D01*
Y184172D01*
X421123Y184222D01*
X421323D01*
Y183722D01*
X421123D01*
G37*
G36*
G01Y186322D02*
X420373Y186372D01*
Y186772D01*
X421123Y186822D01*
X421323D01*
Y186322D01*
X421123D01*
G37*
G36*
G01Y188922D02*
X420373Y188972D01*
Y189372D01*
X421123Y189422D01*
X421323D01*
Y188922D01*
X421123D01*
G37*
G36*
G01Y191522D02*
X420373Y191572D01*
Y191972D01*
X421123Y192022D01*
X421323D01*
Y191522D01*
X421123D01*
G37*
G36*
G01Y194122D02*
X420373Y194172D01*
Y194572D01*
X421123Y194622D01*
X421323D01*
Y194122D01*
X421123D01*
G37*
G36*
G01X421523Y177722D02*
X422273Y177672D01*
Y177272D01*
X421523Y177222D01*
X421323D01*
Y177722D01*
X421523D01*
G37*
G36*
G01Y175122D02*
X422273Y175072D01*
Y174672D01*
X421523Y174622D01*
X421323D01*
Y175122D01*
X421523D01*
G37*
G36*
G01Y180322D02*
X422273Y180272D01*
Y179872D01*
X421523Y179822D01*
X421323D01*
Y180322D01*
X421523D01*
G37*
G36*
G01Y182922D02*
X422273Y182872D01*
Y182472D01*
X421523Y182422D01*
X421323D01*
Y182922D01*
X421523D01*
G37*
G36*
G01Y185522D02*
X422273Y185472D01*
Y185072D01*
X421523Y185022D01*
X421323D01*
Y185522D01*
X421523D01*
G37*
G36*
G01Y188122D02*
X422273Y188072D01*
Y187672D01*
X421523Y187622D01*
X421323D01*
Y188122D01*
X421523D01*
G37*
G36*
G01Y190722D02*
X422273Y190672D01*
Y190272D01*
X421523Y190222D01*
X421323D01*
Y190722D01*
X421523D01*
G37*
G36*
G01Y193322D02*
X422273Y193272D01*
Y192872D01*
X421523Y192822D01*
X421323D01*
Y193322D01*
X421523D01*
G37*
G36*
G01X420596Y205334D02*
X421266Y204984D01*
Y204114D01*
X420596Y203764D01*
X420421D01*
Y205334D01*
X420596D01*
G37*
G36*
G01X423410Y208593D02*
X423418Y207838D01*
X422652Y207426D01*
X422027Y207851D01*
X421944Y208006D01*
X423327Y208748D01*
X423410Y208593D01*
G37*
G36*
G01X431973Y165522D02*
X431223Y165572D01*
Y165972D01*
X431973Y166022D01*
X432173D01*
Y165522D01*
X431973D01*
G37*
G36*
G01X432373Y167322D02*
X433123Y167272D01*
Y166872D01*
X432373Y166822D01*
X432173D01*
Y167322D01*
X432373D01*
G37*
G36*
G01X431973Y170722D02*
X431223Y170772D01*
Y171172D01*
X431973Y171222D01*
X432173D01*
Y170722D01*
X431973D01*
G37*
G36*
G01X432373Y172522D02*
X433123Y172472D01*
Y172072D01*
X432373Y172022D01*
X432173D01*
Y172522D01*
X432373D01*
G37*
G36*
G01Y169922D02*
X433123Y169872D01*
Y169472D01*
X432373Y169422D01*
X432173D01*
Y169922D01*
X432373D01*
G37*
G36*
G01X431973Y168122D02*
X431223Y168172D01*
Y168572D01*
X431973Y168622D01*
X432173D01*
Y168122D01*
X431973D01*
G37*
G36*
G01Y181122D02*
X431223Y181172D01*
Y181572D01*
X431973Y181622D01*
X432173D01*
Y181122D01*
X431973D01*
G37*
G36*
G01Y183722D02*
X431223Y183772D01*
Y184172D01*
X431973Y184222D01*
X432173D01*
Y183722D01*
X431973D01*
G37*
G36*
G01Y186322D02*
X431223Y186372D01*
Y186772D01*
X431973Y186822D01*
X432173D01*
Y186322D01*
X431973D01*
G37*
G36*
G01Y188922D02*
X431223Y188972D01*
Y189372D01*
X431973Y189422D01*
X432173D01*
Y188922D01*
X431973D01*
G37*
G36*
G01Y191522D02*
X431223Y191572D01*
Y191972D01*
X431973Y192022D01*
X432173D01*
Y191522D01*
X431973D01*
G37*
G36*
G01Y194122D02*
X431223Y194172D01*
Y194572D01*
X431973Y194622D01*
X432173D01*
Y194122D01*
X431973D01*
G37*
G36*
G01Y178522D02*
X431223Y178572D01*
Y178972D01*
X431973Y179022D01*
X432173D01*
Y178522D01*
X431973D01*
G37*
G36*
G01Y175922D02*
X431223Y175972D01*
Y176372D01*
X431973Y176422D01*
X432173D01*
Y175922D01*
X431973D01*
G37*
G36*
G01Y173322D02*
X431223Y173372D01*
Y173772D01*
X431973Y173822D01*
X432173D01*
Y173322D01*
X431973D01*
G37*
G36*
G01X432373Y182922D02*
X433123Y182872D01*
Y182472D01*
X432373Y182422D01*
X432173D01*
Y182922D01*
X432373D01*
G37*
G36*
G01Y185522D02*
X433123Y185472D01*
Y185072D01*
X432373Y185022D01*
X432173D01*
Y185522D01*
X432373D01*
G37*
G36*
G01Y188122D02*
X433123Y188072D01*
Y187672D01*
X432373Y187622D01*
X432173D01*
Y188122D01*
X432373D01*
G37*
G36*
G01Y190722D02*
X433123Y190672D01*
Y190272D01*
X432373Y190222D01*
X432173D01*
Y190722D01*
X432373D01*
G37*
G36*
G01Y193322D02*
X433123Y193272D01*
Y192872D01*
X432373Y192822D01*
X432173D01*
Y193322D01*
X432373D01*
G37*
G36*
G01Y180322D02*
X433123Y180272D01*
Y179872D01*
X432373Y179822D01*
X432173D01*
Y180322D01*
X432373D01*
G37*
G36*
G01Y177722D02*
X433123Y177672D01*
Y177272D01*
X432373Y177222D01*
X432173D01*
Y177722D01*
X432373D01*
G37*
G36*
G01Y175122D02*
X433123Y175072D01*
Y174672D01*
X432373Y174622D01*
X432173D01*
Y175122D01*
X432373D01*
G37*
G36*
G01X433523Y165522D02*
X432773Y165572D01*
Y165972D01*
X433523Y166022D01*
X433723D01*
Y165522D01*
X433523D01*
G37*
G36*
G01Y168122D02*
X432773Y168172D01*
Y168572D01*
X433523Y168622D01*
X433723D01*
Y168122D01*
X433523D01*
G37*
G36*
G01X433923Y167322D02*
X434673Y167272D01*
Y166872D01*
X433923Y166822D01*
X433723D01*
Y167322D01*
X433923D01*
G37*
G36*
G01Y169922D02*
X434673Y169872D01*
Y169472D01*
X433923Y169422D01*
X433723D01*
Y169922D01*
X433923D01*
G37*
G36*
G01Y172522D02*
X434673Y172472D01*
Y172072D01*
X433923Y172022D01*
X433723D01*
Y172522D01*
X433923D01*
G37*
G36*
G01X433523Y170722D02*
X432773Y170772D01*
Y171172D01*
X433523Y171222D01*
X433723D01*
Y170722D01*
X433523D01*
G37*
G36*
G01X433923Y188122D02*
X434673Y188072D01*
Y187672D01*
X433923Y187622D01*
X433723D01*
Y188122D01*
X433923D01*
G37*
G36*
G01Y190722D02*
X434673Y190672D01*
Y190272D01*
X433923Y190222D01*
X433723D01*
Y190722D01*
X433923D01*
G37*
G36*
G01Y193322D02*
X434673Y193272D01*
Y192872D01*
X433923Y192822D01*
X433723D01*
Y193322D01*
X433923D01*
G37*
G36*
G01Y185522D02*
X434673Y185472D01*
Y185072D01*
X433923Y185022D01*
X433723D01*
Y185522D01*
X433923D01*
G37*
G36*
G01Y175122D02*
X434673Y175072D01*
Y174672D01*
X433923Y174622D01*
X433723D01*
Y175122D01*
X433923D01*
G37*
G36*
G01Y180322D02*
X434673Y180272D01*
Y179872D01*
X433923Y179822D01*
X433723D01*
Y180322D01*
X433923D01*
G37*
G36*
G01Y177722D02*
X434673Y177672D01*
Y177272D01*
X433923Y177222D01*
X433723D01*
Y177722D01*
X433923D01*
G37*
G36*
G01Y182922D02*
X434673Y182872D01*
Y182472D01*
X433923Y182422D01*
X433723D01*
Y182922D01*
X433923D01*
G37*
G36*
G01X433523Y191522D02*
X432773Y191572D01*
Y191972D01*
X433523Y192022D01*
X433723D01*
Y191522D01*
X433523D01*
G37*
G36*
G01Y178522D02*
X432773Y178572D01*
Y178972D01*
X433523Y179022D01*
X433723D01*
Y178522D01*
X433523D01*
G37*
G36*
G01Y181122D02*
X432773Y181172D01*
Y181572D01*
X433523Y181622D01*
X433723D01*
Y181122D01*
X433523D01*
G37*
G36*
G01Y194122D02*
X432773Y194172D01*
Y194572D01*
X433523Y194622D01*
X433723D01*
Y194122D01*
X433523D01*
G37*
G36*
G01Y183722D02*
X432773Y183772D01*
Y184172D01*
X433523Y184222D01*
X433723D01*
Y183722D01*
X433523D01*
G37*
G36*
G01Y188922D02*
X432773Y188972D01*
Y189372D01*
X433523Y189422D01*
X433723D01*
Y188922D01*
X433523D01*
G37*
G36*
G01Y186322D02*
X432773Y186372D01*
Y186772D01*
X433523Y186822D01*
X433723D01*
Y186322D01*
X433523D01*
G37*
G36*
G01Y175922D02*
X432773Y175972D01*
Y176372D01*
X433523Y176422D01*
X433723D01*
Y175922D01*
X433523D01*
G37*
G36*
G01Y173322D02*
X432773Y173372D01*
Y173772D01*
X433523Y173822D01*
X433723D01*
Y173322D01*
X433523D01*
G37*
G36*
G01X427323Y165522D02*
X426573Y165572D01*
Y165972D01*
X427323Y166022D01*
X427523D01*
Y165522D01*
X427323D01*
G37*
G36*
G01X427723Y167322D02*
X428473Y167272D01*
Y166872D01*
X427723Y166822D01*
X427523D01*
Y167322D01*
X427723D01*
G37*
G36*
G01X427323Y168122D02*
X426573Y168172D01*
Y168572D01*
X427323Y168622D01*
X427523D01*
Y168122D01*
X427323D01*
G37*
G36*
G01X427723Y172522D02*
X428473Y172472D01*
Y172072D01*
X427723Y172022D01*
X427523D01*
Y172522D01*
X427723D01*
G37*
G36*
G01Y169922D02*
X428473Y169872D01*
Y169472D01*
X427723Y169422D01*
X427523D01*
Y169922D01*
X427723D01*
G37*
G36*
G01X427323Y170722D02*
X426573Y170772D01*
Y171172D01*
X427323Y171222D01*
X427523D01*
Y170722D01*
X427323D01*
G37*
G36*
G01X427723Y193322D02*
X428473Y193272D01*
Y192872D01*
X427723Y192822D01*
X427523D01*
Y193322D01*
X427723D01*
G37*
G36*
G01Y190722D02*
X428473Y190672D01*
Y190272D01*
X427723Y190222D01*
X427523D01*
Y190722D01*
X427723D01*
G37*
G36*
G01Y185522D02*
X428473Y185472D01*
Y185072D01*
X427723Y185022D01*
X427523D01*
Y185522D01*
X427723D01*
G37*
G36*
G01Y182922D02*
X428473Y182872D01*
Y182472D01*
X427723Y182422D01*
X427523D01*
Y182922D01*
X427723D01*
G37*
G36*
G01Y188122D02*
X428473Y188072D01*
Y187672D01*
X427723Y187622D01*
X427523D01*
Y188122D01*
X427723D01*
G37*
G36*
G01Y180322D02*
X428473Y180272D01*
Y179872D01*
X427723Y179822D01*
X427523D01*
Y180322D01*
X427723D01*
G37*
G36*
G01X427323Y194122D02*
X426573Y194172D01*
Y194572D01*
X427323Y194622D01*
X427523D01*
Y194122D01*
X427323D01*
G37*
G36*
G01Y191522D02*
X426573Y191572D01*
Y191972D01*
X427323Y192022D01*
X427523D01*
Y191522D01*
X427323D01*
G37*
G36*
G01X427723Y177722D02*
X428473Y177672D01*
Y177272D01*
X427723Y177222D01*
X427523D01*
Y177722D01*
X427723D01*
G37*
G36*
G01Y175122D02*
X428473Y175072D01*
Y174672D01*
X427723Y174622D01*
X427523D01*
Y175122D01*
X427723D01*
G37*
G36*
G01X427323Y188922D02*
X426573Y188972D01*
Y189372D01*
X427323Y189422D01*
X427523D01*
Y188922D01*
X427323D01*
G37*
G36*
G01Y186322D02*
X426573Y186372D01*
Y186772D01*
X427323Y186822D01*
X427523D01*
Y186322D01*
X427323D01*
G37*
G36*
G01Y178522D02*
X426573Y178572D01*
Y178972D01*
X427323Y179022D01*
X427523D01*
Y178522D01*
X427323D01*
G37*
G36*
G01Y183722D02*
X426573Y183772D01*
Y184172D01*
X427323Y184222D01*
X427523D01*
Y183722D01*
X427323D01*
G37*
G36*
G01Y181122D02*
X426573Y181172D01*
Y181572D01*
X427323Y181622D01*
X427523D01*
Y181122D01*
X427323D01*
G37*
G36*
G01Y175922D02*
X426573Y175972D01*
Y176372D01*
X427323Y176422D01*
X427523D01*
Y175922D01*
X427323D01*
G37*
G36*
G01Y173322D02*
X426573Y173372D01*
Y173772D01*
X427323Y173822D01*
X427523D01*
Y173322D01*
X427323D01*
G37*
G36*
G01X428873Y165522D02*
X428123Y165572D01*
Y165972D01*
X428873Y166022D01*
X429073D01*
Y165522D01*
X428873D01*
G37*
G36*
G01X429273Y172522D02*
X430023Y172472D01*
Y172072D01*
X429273Y172022D01*
X429073D01*
Y172522D01*
X429273D01*
G37*
G36*
G01Y169922D02*
X430023Y169872D01*
Y169472D01*
X429273Y169422D01*
X429073D01*
Y169922D01*
X429273D01*
G37*
G36*
G01X428873Y168122D02*
X428123Y168172D01*
Y168572D01*
X428873Y168622D01*
X429073D01*
Y168122D01*
X428873D01*
G37*
G36*
G01X429273Y167322D02*
X430023Y167272D01*
Y166872D01*
X429273Y166822D01*
X429073D01*
Y167322D01*
X429273D01*
G37*
G36*
G01X428873Y170722D02*
X428123Y170772D01*
Y171172D01*
X428873Y171222D01*
X429073D01*
Y170722D01*
X428873D01*
G37*
G36*
G01X429273Y193322D02*
X430023Y193272D01*
Y192872D01*
X429273Y192822D01*
X429073D01*
Y193322D01*
X429273D01*
G37*
G36*
G01Y180322D02*
X430023Y180272D01*
Y179872D01*
X429273Y179822D01*
X429073D01*
Y180322D01*
X429273D01*
G37*
G36*
G01Y177722D02*
X430023Y177672D01*
Y177272D01*
X429273Y177222D01*
X429073D01*
Y177722D01*
X429273D01*
G37*
G36*
G01Y175122D02*
X430023Y175072D01*
Y174672D01*
X429273Y174622D01*
X429073D01*
Y175122D01*
X429273D01*
G37*
G36*
G01Y188122D02*
X430023Y188072D01*
Y187672D01*
X429273Y187622D01*
X429073D01*
Y188122D01*
X429273D01*
G37*
G36*
G01Y185522D02*
X430023Y185472D01*
Y185072D01*
X429273Y185022D01*
X429073D01*
Y185522D01*
X429273D01*
G37*
G36*
G01Y190722D02*
X430023Y190672D01*
Y190272D01*
X429273Y190222D01*
X429073D01*
Y190722D01*
X429273D01*
G37*
G36*
G01X428873Y188922D02*
X428123Y188972D01*
Y189372D01*
X428873Y189422D01*
X429073D01*
Y188922D01*
X428873D01*
G37*
G36*
G01Y175922D02*
X428123Y175972D01*
Y176372D01*
X428873Y176422D01*
X429073D01*
Y175922D01*
X428873D01*
G37*
G36*
G01Y173322D02*
X428123Y173372D01*
Y173772D01*
X428873Y173822D01*
X429073D01*
Y173322D01*
X428873D01*
G37*
G36*
G01X429273Y182922D02*
X430023Y182872D01*
Y182472D01*
X429273Y182422D01*
X429073D01*
Y182922D01*
X429273D01*
G37*
G36*
G01X428873Y191522D02*
X428123Y191572D01*
Y191972D01*
X428873Y192022D01*
X429073D01*
Y191522D01*
X428873D01*
G37*
G36*
G01Y194122D02*
X428123Y194172D01*
Y194572D01*
X428873Y194622D01*
X429073D01*
Y194122D01*
X428873D01*
G37*
G36*
G01Y178522D02*
X428123Y178572D01*
Y178972D01*
X428873Y179022D01*
X429073D01*
Y178522D01*
X428873D01*
G37*
G36*
G01Y186322D02*
X428123Y186372D01*
Y186772D01*
X428873Y186822D01*
X429073D01*
Y186322D01*
X428873D01*
G37*
G36*
G01Y183722D02*
X428123Y183772D01*
Y184172D01*
X428873Y184222D01*
X429073D01*
Y183722D01*
X428873D01*
G37*
G36*
G01Y181122D02*
X428123Y181172D01*
Y181572D01*
X428873Y181622D01*
X429073D01*
Y181122D01*
X428873D01*
G37*
G36*
G01X425773Y165522D02*
X425023Y165572D01*
Y165972D01*
X425773Y166022D01*
X425973D01*
Y165522D01*
X425773D01*
G37*
G36*
G01Y170722D02*
X425023Y170772D01*
Y171172D01*
X425773Y171222D01*
X425973D01*
Y170722D01*
X425773D01*
G37*
G36*
G01X426173Y172522D02*
X426923Y172472D01*
Y172072D01*
X426173Y172022D01*
X425973D01*
Y172522D01*
X426173D01*
G37*
G36*
G01Y169922D02*
X426923Y169872D01*
Y169472D01*
X426173Y169422D01*
X425973D01*
Y169922D01*
X426173D01*
G37*
G36*
G01X425773Y168122D02*
X425023Y168172D01*
Y168572D01*
X425773Y168622D01*
X425973D01*
Y168122D01*
X425773D01*
G37*
G36*
G01X426173Y167322D02*
X426923Y167272D01*
Y166872D01*
X426173Y166822D01*
X425973D01*
Y167322D01*
X426173D01*
G37*
G36*
G01X425773Y175922D02*
X425023Y175972D01*
Y176372D01*
X425773Y176422D01*
X425973D01*
Y175922D01*
X425773D01*
G37*
G36*
G01Y173322D02*
X425023Y173372D01*
Y173772D01*
X425773Y173822D01*
X425973D01*
Y173322D01*
X425773D01*
G37*
G36*
G01Y178522D02*
X425023Y178572D01*
Y178972D01*
X425773Y179022D01*
X425973D01*
Y178522D01*
X425773D01*
G37*
G36*
G01Y181122D02*
X425023Y181172D01*
Y181572D01*
X425773Y181622D01*
X425973D01*
Y181122D01*
X425773D01*
G37*
G36*
G01Y183722D02*
X425023Y183772D01*
Y184172D01*
X425773Y184222D01*
X425973D01*
Y183722D01*
X425773D01*
G37*
G36*
G01Y186322D02*
X425023Y186372D01*
Y186772D01*
X425773Y186822D01*
X425973D01*
Y186322D01*
X425773D01*
G37*
G36*
G01Y188922D02*
X425023Y188972D01*
Y189372D01*
X425773Y189422D01*
X425973D01*
Y188922D01*
X425773D01*
G37*
G36*
G01Y191522D02*
X425023Y191572D01*
Y191972D01*
X425773Y192022D01*
X425973D01*
Y191522D01*
X425773D01*
G37*
G36*
G01Y194122D02*
X425023Y194172D01*
Y194572D01*
X425773Y194622D01*
X425973D01*
Y194122D01*
X425773D01*
G37*
G36*
G01X426173Y177722D02*
X426923Y177672D01*
Y177272D01*
X426173Y177222D01*
X425973D01*
Y177722D01*
X426173D01*
G37*
G36*
G01Y175122D02*
X426923Y175072D01*
Y174672D01*
X426173Y174622D01*
X425973D01*
Y175122D01*
X426173D01*
G37*
G36*
G01Y180322D02*
X426923Y180272D01*
Y179872D01*
X426173Y179822D01*
X425973D01*
Y180322D01*
X426173D01*
G37*
G36*
G01Y182922D02*
X426923Y182872D01*
Y182472D01*
X426173Y182422D01*
X425973D01*
Y182922D01*
X426173D01*
G37*
G36*
G01Y185522D02*
X426923Y185472D01*
Y185072D01*
X426173Y185022D01*
X425973D01*
Y185522D01*
X426173D01*
G37*
G36*
G01Y188122D02*
X426923Y188072D01*
Y187672D01*
X426173Y187622D01*
X425973D01*
Y188122D01*
X426173D01*
G37*
G36*
G01Y190722D02*
X426923Y190672D01*
Y190272D01*
X426173Y190222D01*
X425973D01*
Y190722D01*
X426173D01*
G37*
G36*
G01Y193322D02*
X426923Y193272D01*
Y192872D01*
X426173Y192822D01*
X425973D01*
Y193322D01*
X426173D01*
G37*
G36*
G01X430423Y165522D02*
X429673Y165572D01*
Y165972D01*
X430423Y166022D01*
X430623D01*
Y165522D01*
X430423D01*
G37*
G36*
G01Y170722D02*
X429673Y170772D01*
Y171172D01*
X430423Y171222D01*
X430623D01*
Y170722D01*
X430423D01*
G37*
G36*
G01X430823Y172522D02*
X431573Y172472D01*
Y172072D01*
X430823Y172022D01*
X430623D01*
Y172522D01*
X430823D01*
G37*
G36*
G01Y169922D02*
X431573Y169872D01*
Y169472D01*
X430823Y169422D01*
X430623D01*
Y169922D01*
X430823D01*
G37*
G36*
G01X430423Y168122D02*
X429673Y168172D01*
Y168572D01*
X430423Y168622D01*
X430623D01*
Y168122D01*
X430423D01*
G37*
G36*
G01X430823Y167322D02*
X431573Y167272D01*
Y166872D01*
X430823Y166822D01*
X430623D01*
Y167322D01*
X430823D01*
G37*
G36*
G01X430423Y181122D02*
X429673Y181172D01*
Y181572D01*
X430423Y181622D01*
X430623D01*
Y181122D01*
X430423D01*
G37*
G36*
G01Y183722D02*
X429673Y183772D01*
Y184172D01*
X430423Y184222D01*
X430623D01*
Y183722D01*
X430423D01*
G37*
G36*
G01Y186322D02*
X429673Y186372D01*
Y186772D01*
X430423Y186822D01*
X430623D01*
Y186322D01*
X430423D01*
G37*
G36*
G01Y188922D02*
X429673Y188972D01*
Y189372D01*
X430423Y189422D01*
X430623D01*
Y188922D01*
X430423D01*
G37*
G36*
G01Y191522D02*
X429673Y191572D01*
Y191972D01*
X430423Y192022D01*
X430623D01*
Y191522D01*
X430423D01*
G37*
G36*
G01Y194122D02*
X429673Y194172D01*
Y194572D01*
X430423Y194622D01*
X430623D01*
Y194122D01*
X430423D01*
G37*
G36*
G01Y178522D02*
X429673Y178572D01*
Y178972D01*
X430423Y179022D01*
X430623D01*
Y178522D01*
X430423D01*
G37*
G36*
G01Y175922D02*
X429673Y175972D01*
Y176372D01*
X430423Y176422D01*
X430623D01*
Y175922D01*
X430423D01*
G37*
G36*
G01Y173322D02*
X429673Y173372D01*
Y173772D01*
X430423Y173822D01*
X430623D01*
Y173322D01*
X430423D01*
G37*
G36*
G01X430823Y182922D02*
X431573Y182872D01*
Y182472D01*
X430823Y182422D01*
X430623D01*
Y182922D01*
X430823D01*
G37*
G36*
G01Y185522D02*
X431573Y185472D01*
Y185072D01*
X430823Y185022D01*
X430623D01*
Y185522D01*
X430823D01*
G37*
G36*
G01Y188122D02*
X431573Y188072D01*
Y187672D01*
X430823Y187622D01*
X430623D01*
Y188122D01*
X430823D01*
G37*
G36*
G01Y190722D02*
X431573Y190672D01*
Y190272D01*
X430823Y190222D01*
X430623D01*
Y190722D01*
X430823D01*
G37*
G36*
G01Y193322D02*
X431573Y193272D01*
Y192872D01*
X430823Y192822D01*
X430623D01*
Y193322D01*
X430823D01*
G37*
G36*
G01Y180322D02*
X431573Y180272D01*
Y179872D01*
X430823Y179822D01*
X430623D01*
Y180322D01*
X430823D01*
G37*
G36*
G01Y177722D02*
X431573Y177672D01*
Y177272D01*
X430823Y177222D01*
X430623D01*
Y177722D01*
X430823D01*
G37*
G36*
G01Y175122D02*
X431573Y175072D01*
Y174672D01*
X430823Y174622D01*
X430623D01*
Y175122D01*
X430823D01*
G37*
G36*
G01X444010Y184262D02*
X443444Y183767D01*
X443162Y184050D01*
X443656Y184616D01*
X443798Y184757D01*
X444151Y184404D01*
X444010Y184262D01*
G37*
G36*
G01X443598Y194252D02*
X444348Y194202D01*
Y193802D01*
X443598Y193752D01*
X443398D01*
Y194252D01*
X443598D01*
G37*
G36*
G01Y191652D02*
X444348Y191602D01*
Y191202D01*
X443598Y191152D01*
X443398D01*
Y191652D01*
X443598D01*
G37*
G36*
G01Y189052D02*
X444348Y189002D01*
Y188602D01*
X443598Y188552D01*
X443398D01*
Y189052D01*
X443598D01*
G37*
G36*
G01Y186452D02*
X444348Y186402D01*
Y186002D01*
X443598Y185952D01*
X443398D01*
Y186452D01*
X443598D01*
G37*
G36*
G01X443198Y192452D02*
X442448Y192502D01*
Y192902D01*
X443198Y192952D01*
X443398D01*
Y192452D01*
X443198D01*
G37*
G36*
G01Y189852D02*
X442448Y189902D01*
Y190302D01*
X443198Y190352D01*
X443398D01*
Y189852D01*
X443198D01*
G37*
G36*
G01Y187252D02*
X442448Y187302D01*
Y187702D01*
X443198Y187752D01*
X443398D01*
Y187252D01*
X443198D01*
G37*
G36*
G01X444859Y183979D02*
X445424Y184474D01*
X445707Y184191D01*
X445212Y183626D01*
X445071Y183484D01*
X444717Y183838D01*
X444859Y183979D01*
G37*
G36*
G01X445849Y182424D02*
X445283Y181929D01*
X445000Y182212D01*
X445495Y182777D01*
X445636Y182919D01*
X445990Y182565D01*
X445849Y182424D01*
G37*
G36*
G01X443860Y200577D02*
X443190Y200927D01*
Y201797D01*
X443860Y202147D01*
X444035D01*
Y200577D01*
X443860D01*
G37*
G36*
G01X458242Y166278D02*
X458992Y166228D01*
Y165828D01*
X458242Y165778D01*
X458042D01*
Y166278D01*
X458242D01*
G37*
G36*
G01X457842Y164478D02*
X457092Y164528D01*
Y164928D01*
X457842Y164978D01*
X458042D01*
Y164478D01*
X457842D01*
G37*
G36*
G01X455889Y172948D02*
X456455Y173443D01*
X456738Y173161D01*
X456243Y172595D01*
X456102Y172453D01*
X455748Y172807D01*
X455889Y172948D01*
G37*
G36*
G01X455041Y173231D02*
X454475Y172736D01*
X454192Y173019D01*
X454687Y173585D01*
X454829Y173726D01*
X455182Y173373D01*
X455041Y173231D01*
G37*
G36*
G01X456879Y171393D02*
X456314Y170898D01*
X456031Y171181D01*
X456526Y171746D01*
X456667Y171888D01*
X457021Y171534D01*
X456879Y171393D01*
G37*
G36*
G01X458242Y168878D02*
X458992Y168828D01*
Y168428D01*
X458242Y168378D01*
X458042D01*
Y168878D01*
X458242D01*
G37*
G36*
G01X457842Y167078D02*
X457092Y167128D01*
Y167528D01*
X457842Y167578D01*
X458042D01*
Y167078D01*
X457842D01*
G37*
G36*
G01X448536Y180302D02*
X449101Y180797D01*
X449384Y180514D01*
X448889Y179949D01*
X448748Y179807D01*
X448394Y180161D01*
X448536Y180302D01*
G37*
G36*
G01X446697Y182141D02*
X447263Y182636D01*
X447546Y182353D01*
X447051Y181787D01*
X446909Y181646D01*
X446556Y181999D01*
X446697Y182141D01*
G37*
G36*
G01X450374Y178464D02*
X450940Y178959D01*
X451223Y178676D01*
X450728Y178110D01*
X450586Y177969D01*
X450233Y178322D01*
X450374Y178464D01*
G37*
G36*
G01X452212Y176625D02*
X452778Y177120D01*
X453061Y176838D01*
X452566Y176272D01*
X452425Y176130D01*
X452071Y176484D01*
X452212Y176625D01*
G37*
G36*
G01X454051Y174787D02*
X454617Y175282D01*
X454899Y174999D01*
X454405Y174433D01*
X454263Y174292D01*
X453910Y174645D01*
X454051Y174787D01*
G37*
G36*
G01X449525Y178747D02*
X448960Y178252D01*
X448677Y178535D01*
X449172Y179100D01*
X449313Y179242D01*
X449667Y178888D01*
X449525Y178747D01*
G37*
G36*
G01X447687Y180585D02*
X447121Y180090D01*
X446838Y180373D01*
X447333Y180939D01*
X447475Y181080D01*
X447828Y180727D01*
X447687Y180585D01*
G37*
G36*
G01X451364Y176908D02*
X450798Y176413D01*
X450515Y176696D01*
X451010Y177262D01*
X451152Y177403D01*
X451505Y177050D01*
X451364Y176908D01*
G37*
G36*
G01X453202Y175070D02*
X452637Y174575D01*
X452354Y174858D01*
X452849Y175423D01*
X452990Y175565D01*
X453344Y175211D01*
X453202Y175070D01*
G37*
G36*
G01X445148Y189052D02*
X445898Y189002D01*
Y188602D01*
X445148Y188552D01*
X444948D01*
Y189052D01*
X445148D01*
G37*
G36*
G01Y191652D02*
X445898Y191602D01*
Y191202D01*
X445148Y191152D01*
X444948D01*
Y191652D01*
X445148D01*
G37*
G36*
G01Y194252D02*
X445898Y194202D01*
Y193802D01*
X445148Y193752D01*
X444948D01*
Y194252D01*
X445148D01*
G37*
G36*
G01X444748Y189852D02*
X443998Y189902D01*
Y190302D01*
X444748Y190352D01*
X444948D01*
Y189852D01*
X444748D01*
G37*
G36*
G01Y187252D02*
X443998Y187302D01*
Y187702D01*
X444748Y187752D01*
X444948D01*
Y187252D01*
X444748D01*
G37*
G36*
G01Y192452D02*
X443998Y192502D01*
Y192902D01*
X444748Y192952D01*
X444948D01*
Y192452D01*
X444748D01*
G37*
G36*
G01Y195052D02*
X443998Y195102D01*
Y195502D01*
X444748Y195552D01*
X444948D01*
Y195052D01*
X444748D01*
G37*
G36*
G01X444960Y202650D02*
X445630Y202300D01*
Y201430D01*
X444960Y201080D01*
X444785D01*
Y202650D01*
X444960D01*
G37*
G36*
G01X459792Y166278D02*
X460542Y166228D01*
Y165828D01*
X459792Y165778D01*
X459592D01*
Y166278D01*
X459792D01*
G37*
G36*
G01X459392Y164478D02*
X458642Y164528D01*
Y164928D01*
X459392Y164978D01*
X459592D01*
Y164478D01*
X459392D01*
G37*
G36*
G01X458824Y172206D02*
X459390Y172701D01*
X459673Y172419D01*
X459178Y171853D01*
X459037Y171711D01*
X458683Y172065D01*
X458824Y172206D01*
G37*
G36*
G01X457976Y172489D02*
X457410Y171994D01*
X457127Y172277D01*
X457622Y172843D01*
X457764Y172984D01*
X458117Y172631D01*
X457976Y172489D01*
G37*
G36*
G01X459392Y169678D02*
X458642Y169728D01*
Y170128D01*
X459392Y170178D01*
X459592D01*
Y169678D01*
X459392D01*
G37*
G36*
G01X459792Y168878D02*
X460542Y168828D01*
Y168428D01*
X459792Y168378D01*
X459592D01*
Y168878D01*
X459792D01*
G37*
G36*
G01X459392Y167078D02*
X458642Y167128D01*
Y167528D01*
X459392Y167578D01*
X459592D01*
Y167078D01*
X459392D01*
G37*
G36*
G01X445955Y185076D02*
X446521Y185571D01*
X446804Y185288D01*
X446309Y184722D01*
X446167Y184581D01*
X445814Y184934D01*
X445955Y185076D01*
G37*
G36*
G01X446945Y183520D02*
X446379Y183025D01*
X446096Y183308D01*
X446591Y183874D01*
X446733Y184015D01*
X447086Y183662D01*
X446945Y183520D01*
G37*
G36*
G01X455147Y175883D02*
X455713Y176378D01*
X455996Y176096D01*
X455501Y175530D01*
X455360Y175388D01*
X455006Y175742D01*
X455147Y175883D01*
G37*
G36*
G01X456986Y174045D02*
X457552Y174540D01*
X457834Y174257D01*
X457339Y173691D01*
X457198Y173550D01*
X456845Y173903D01*
X456986Y174045D01*
G37*
G36*
G01X453309Y177722D02*
X453875Y178217D01*
X454158Y177934D01*
X453663Y177368D01*
X453521Y177227D01*
X453168Y177580D01*
X453309Y177722D01*
G37*
G36*
G01X451470Y179560D02*
X452036Y180055D01*
X452319Y179772D01*
X451824Y179207D01*
X451683Y179065D01*
X451329Y179419D01*
X451470Y179560D01*
G37*
G36*
G01X449632Y181399D02*
X450198Y181894D01*
X450481Y181611D01*
X449986Y181045D01*
X449844Y180904D01*
X449491Y181257D01*
X449632Y181399D01*
G37*
G36*
G01X447794Y183237D02*
X448359Y183732D01*
X448642Y183449D01*
X448147Y182884D01*
X448006Y182742D01*
X447652Y183096D01*
X447794Y183237D01*
G37*
G36*
G01X454299Y176166D02*
X453733Y175671D01*
X453450Y175954D01*
X453945Y176520D01*
X454087Y176661D01*
X454440Y176308D01*
X454299Y176166D01*
G37*
G36*
G01X456137Y174328D02*
X455572Y173833D01*
X455289Y174116D01*
X455784Y174681D01*
X455925Y174823D01*
X456279Y174469D01*
X456137Y174328D01*
G37*
G36*
G01X452460Y178005D02*
X451895Y177510D01*
X451612Y177793D01*
X452107Y178358D01*
X452248Y178500D01*
X452602Y178146D01*
X452460Y178005D01*
G37*
G36*
G01X450622Y179843D02*
X450056Y179348D01*
X449773Y179631D01*
X450268Y180197D01*
X450410Y180338D01*
X450763Y179985D01*
X450622Y179843D01*
G37*
G36*
G01X448783Y181682D02*
X448218Y181187D01*
X447935Y181470D01*
X448430Y182035D01*
X448571Y182177D01*
X448925Y181823D01*
X448783Y181682D01*
G37*
G36*
G01X473005Y172811D02*
X472440Y172316D01*
X472157Y172599D01*
X472652Y173164D01*
X472793Y173306D01*
X473147Y172952D01*
X473005Y172811D01*
G37*
G36*
G01X474844Y170972D02*
X474278Y170477D01*
X473995Y170760D01*
X474490Y171326D01*
X474632Y171467D01*
X474985Y171114D01*
X474844Y170972D01*
G37*
G36*
G01X473854Y172528D02*
X474420Y173023D01*
X474702Y172740D01*
X474207Y172174D01*
X474066Y172033D01*
X473712Y172387D01*
X473854Y172528D01*
G37*
G36*
G01X476682Y169134D02*
X476117Y168639D01*
X475834Y168922D01*
X476329Y169487D01*
X476470Y169629D01*
X476824Y169275D01*
X476682Y169134D01*
G37*
G36*
G01X475692Y170690D02*
X476258Y171185D01*
X476541Y170902D01*
X476046Y170336D01*
X475904Y170195D01*
X475551Y170548D01*
X475692Y170690D01*
G37*
G36*
G01X464661Y181720D02*
X465227Y182215D01*
X465510Y181933D01*
X465015Y181367D01*
X464874Y181225D01*
X464520Y181579D01*
X464661Y181720D01*
G37*
G36*
G01X462823Y183559D02*
X463389Y184054D01*
X463671Y183771D01*
X463177Y183205D01*
X463035Y183064D01*
X462682Y183417D01*
X462823Y183559D01*
G37*
G36*
G01X460984Y185397D02*
X461550Y185892D01*
X461833Y185610D01*
X461338Y185044D01*
X461197Y184902D01*
X460843Y185256D01*
X460984Y185397D01*
G37*
G36*
G01X459146Y187236D02*
X459712Y187731D01*
X459995Y187448D01*
X459500Y186882D01*
X459358Y186741D01*
X459005Y187094D01*
X459146Y187236D01*
G37*
G36*
G01X457308Y189074D02*
X457873Y189569D01*
X458156Y189286D01*
X457661Y188721D01*
X457520Y188579D01*
X457166Y188933D01*
X457308Y189074D01*
G37*
G36*
G01X466500Y179882D02*
X467066Y180377D01*
X467348Y180094D01*
X466853Y179528D01*
X466712Y179387D01*
X466358Y179741D01*
X466500Y179882D01*
G37*
G36*
G01X468338Y178043D02*
X468904Y178538D01*
X469187Y178256D01*
X468692Y177690D01*
X468551Y177548D01*
X468197Y177902D01*
X468338Y178043D01*
G37*
G36*
G01X465651Y180165D02*
X465086Y179670D01*
X464803Y179953D01*
X465298Y180518D01*
X465439Y180660D01*
X465793Y180306D01*
X465651Y180165D01*
G37*
G36*
G01X463813Y182003D02*
X463247Y181508D01*
X462964Y181791D01*
X463459Y182357D01*
X463601Y182498D01*
X463954Y182145D01*
X463813Y182003D01*
G37*
G36*
G01X461974Y183842D02*
X461409Y183347D01*
X461126Y183630D01*
X461621Y184195D01*
X461762Y184337D01*
X462116Y183983D01*
X461974Y183842D01*
G37*
G36*
G01X460136Y185680D02*
X459570Y185185D01*
X459287Y185468D01*
X459782Y186034D01*
X459924Y186175D01*
X460277Y185822D01*
X460136Y185680D01*
G37*
G36*
G01X458297Y187519D02*
X457732Y187024D01*
X457449Y187307D01*
X457944Y187872D01*
X458085Y188014D01*
X458439Y187660D01*
X458297Y187519D01*
G37*
G36*
G01X456459Y189357D02*
X455893Y188862D01*
X455610Y189145D01*
X456105Y189711D01*
X456247Y189852D01*
X456600Y189499D01*
X456459Y189357D01*
G37*
G36*
G01X467490Y178326D02*
X466924Y177831D01*
X466641Y178114D01*
X467136Y178680D01*
X467278Y178821D01*
X467631Y178468D01*
X467490Y178326D01*
G37*
G36*
G01X455998Y191652D02*
X456748Y191602D01*
Y191202D01*
X455998Y191152D01*
X455798D01*
Y191652D01*
X455998D01*
G37*
G36*
G01X455598Y192452D02*
X454848Y192502D01*
Y192902D01*
X455598Y192952D01*
X455798D01*
Y192452D01*
X455598D01*
G37*
G36*
G01X469328Y176488D02*
X468763Y175993D01*
X468480Y176276D01*
X468975Y176841D01*
X469116Y176983D01*
X469470Y176629D01*
X469328Y176488D01*
G37*
G36*
G01X471167Y174649D02*
X470601Y174154D01*
X470318Y174437D01*
X470813Y175003D01*
X470955Y175144D01*
X471308Y174791D01*
X471167Y174649D01*
G37*
G36*
G01X470177Y176205D02*
X470743Y176700D01*
X471025Y176417D01*
X470530Y175851D01*
X470389Y175710D01*
X470035Y176064D01*
X470177Y176205D01*
G37*
G36*
G01X472015Y174367D02*
X472581Y174861D01*
X472864Y174579D01*
X472369Y174013D01*
X472227Y173872D01*
X471874Y174225D01*
X472015Y174367D01*
G37*
G36*
G01X456150Y203957D02*
X455396Y204012D01*
X455051Y204810D01*
X455527Y205398D01*
X455687Y205467D01*
X456311Y204027D01*
X456150Y203957D01*
G37*
G36*
G01X478521Y167296D02*
X477956Y166801D01*
X477673Y167084D01*
X478168Y167649D01*
X478309Y167791D01*
X478663Y167437D01*
X478521Y167296D01*
G37*
G36*
G01X477531Y168851D02*
X478096Y169346D01*
X478379Y169063D01*
X477884Y168498D01*
X477743Y168356D01*
X477389Y168710D01*
X477531Y168851D01*
G37*
G36*
G01X475940Y172069D02*
X475375Y171574D01*
X475092Y171857D01*
X475587Y172422D01*
X475728Y172564D01*
X476082Y172210D01*
X475940Y172069D01*
G37*
G36*
G01X458404Y190171D02*
X458970Y190666D01*
X459253Y190383D01*
X458758Y189817D01*
X458616Y189676D01*
X458263Y190029D01*
X458404Y190171D01*
G37*
G36*
G01X468586Y179423D02*
X468021Y178928D01*
X467738Y179211D01*
X468233Y179776D01*
X468374Y179918D01*
X468728Y179564D01*
X468586Y179423D01*
G37*
G36*
G01X466748Y181261D02*
X466182Y180766D01*
X465899Y181049D01*
X466394Y181615D01*
X466536Y181756D01*
X466889Y181403D01*
X466748Y181261D01*
G37*
G36*
G01X464909Y183100D02*
X464344Y182605D01*
X464061Y182888D01*
X464556Y183453D01*
X464697Y183595D01*
X465051Y183241D01*
X464909Y183100D01*
G37*
G36*
G01X463071Y184938D02*
X462505Y184443D01*
X462222Y184726D01*
X462717Y185292D01*
X462859Y185433D01*
X463212Y185080D01*
X463071Y184938D01*
G37*
G36*
G01X461232Y186777D02*
X460667Y186282D01*
X460384Y186565D01*
X460879Y187130D01*
X461020Y187272D01*
X461374Y186918D01*
X461232Y186777D01*
G37*
G36*
G01X459394Y188615D02*
X458828Y188120D01*
X458545Y188403D01*
X459040Y188969D01*
X459182Y189110D01*
X459535Y188757D01*
X459394Y188615D01*
G37*
G36*
G01X457148Y192452D02*
X456398Y192502D01*
Y192902D01*
X457148Y192952D01*
X457348D01*
Y192452D01*
X457148D01*
G37*
G36*
G01X467596Y180978D02*
X468162Y181473D01*
X468445Y181191D01*
X467950Y180625D01*
X467809Y180483D01*
X467455Y180837D01*
X467596Y180978D01*
G37*
G36*
G01X465758Y182817D02*
X466324Y183312D01*
X466606Y183029D01*
X466111Y182463D01*
X465970Y182322D01*
X465617Y182675D01*
X465758Y182817D01*
G37*
G36*
G01X463919Y184655D02*
X464485Y185150D01*
X464768Y184868D01*
X464273Y184302D01*
X464132Y184160D01*
X463778Y184514D01*
X463919Y184655D01*
G37*
G36*
G01X462081Y186494D02*
X462647Y186989D01*
X462930Y186706D01*
X462435Y186140D01*
X462293Y185999D01*
X461940Y186352D01*
X462081Y186494D01*
G37*
G36*
G01X460242Y188332D02*
X460808Y188827D01*
X461091Y188544D01*
X460596Y187979D01*
X460455Y187837D01*
X460101Y188191D01*
X460242Y188332D01*
G37*
G36*
G01X469435Y179140D02*
X470001Y179635D01*
X470283Y179352D01*
X469788Y178786D01*
X469647Y178645D01*
X469293Y178999D01*
X469435Y179140D01*
G37*
G36*
G01X471273Y177301D02*
X471839Y177796D01*
X472122Y177514D01*
X471627Y176948D01*
X471485Y176807D01*
X471132Y177160D01*
X471273Y177301D01*
G37*
G36*
G01X473112Y175463D02*
X473678Y175958D01*
X473960Y175675D01*
X473465Y175109D01*
X473324Y174968D01*
X472970Y175322D01*
X473112Y175463D01*
G37*
G36*
G01X470425Y177584D02*
X469859Y177089D01*
X469576Y177372D01*
X470071Y177938D01*
X470213Y178079D01*
X470566Y177726D01*
X470425Y177584D01*
G37*
G36*
G01X472263Y175746D02*
X471698Y175251D01*
X471415Y175534D01*
X471910Y176099D01*
X472051Y176241D01*
X472405Y175887D01*
X472263Y175746D01*
G37*
G36*
G01X474102Y173907D02*
X473536Y173412D01*
X473253Y173695D01*
X473748Y174261D01*
X473890Y174402D01*
X474243Y174049D01*
X474102Y173907D01*
G37*
G36*
G01X474950Y173625D02*
X475516Y174120D01*
X475799Y173837D01*
X475304Y173271D01*
X475162Y173130D01*
X474809Y173483D01*
X474950Y173625D01*
G37*
G36*
G01X455911Y209291D02*
X456665Y209236D01*
X457011Y208438D01*
X456536Y207850D01*
X456375Y207781D01*
X455751Y209221D01*
X455911Y209291D01*
G37*
G36*
G01X476789Y171786D02*
X477354Y172281D01*
X477637Y171998D01*
X477142Y171432D01*
X477001Y171291D01*
X476647Y171645D01*
X476789Y171786D01*
G37*
G36*
G01X477779Y170230D02*
X477213Y169735D01*
X476930Y170018D01*
X477425Y170584D01*
X477567Y170725D01*
X477920Y170372D01*
X477779Y170230D01*
G37*
G36*
G01X443656Y180231D02*
X443090Y179736D01*
X442807Y180019D01*
X443302Y180584D01*
X443443Y180726D01*
X443797Y180372D01*
X443656Y180231D01*
G37*
G36*
G01X441817Y182069D02*
X441251Y181574D01*
X440969Y181857D01*
X441463Y182423D01*
X441605Y182564D01*
X441958Y182211D01*
X441817Y182069D01*
G37*
G36*
G01X442666Y181786D02*
X443231Y182281D01*
X443514Y181998D01*
X443019Y181433D01*
X442878Y181291D01*
X442524Y181645D01*
X442666Y181786D01*
G37*
G36*
G01X440827Y183625D02*
X441393Y184120D01*
X441676Y183837D01*
X441181Y183271D01*
X441039Y183130D01*
X440686Y183483D01*
X440827Y183625D01*
G37*
G36*
G01X440098Y192452D02*
X439348Y192502D01*
Y192902D01*
X440098Y192952D01*
X440298D01*
Y192452D01*
X440098D01*
G37*
G36*
G01Y189852D02*
X439348Y189902D01*
Y190302D01*
X440098Y190352D01*
X440298D01*
Y189852D01*
X440098D01*
G37*
G36*
G01Y187252D02*
X439348Y187302D01*
Y187702D01*
X440098Y187752D01*
X440298D01*
Y187252D01*
X440098D01*
G37*
G36*
G01Y184652D02*
X439348Y184702D01*
Y185102D01*
X440098Y185152D01*
X440298D01*
Y184652D01*
X440098D01*
G37*
G36*
G01X440498Y191652D02*
X441248Y191602D01*
Y191202D01*
X440498Y191152D01*
X440298D01*
Y191652D01*
X440498D01*
G37*
G36*
G01Y189052D02*
X441248Y189002D01*
Y188602D01*
X440498Y188552D01*
X440298D01*
Y189052D01*
X440498D01*
G37*
G36*
G01Y186452D02*
X441248Y186402D01*
Y186002D01*
X440498Y185952D01*
X440298D01*
Y186452D01*
X440498D01*
G37*
G36*
G01Y194252D02*
X441248Y194202D01*
Y193802D01*
X440498Y193752D01*
X440298D01*
Y194252D01*
X440498D01*
G37*
G36*
G01X440098Y195052D02*
X439348Y195102D01*
Y195502D01*
X440098Y195552D01*
X440298D01*
Y195052D01*
X440098D01*
G37*
G36*
G01X445494Y178392D02*
X444928Y177897D01*
X444645Y178180D01*
X445140Y178746D01*
X445282Y178887D01*
X445635Y178534D01*
X445494Y178392D01*
G37*
G36*
G01X444504Y179948D02*
X445070Y180443D01*
X445353Y180160D01*
X444858Y179594D01*
X444716Y179453D01*
X444363Y179806D01*
X444504Y179948D01*
G37*
G36*
G01X439223Y199906D02*
X438553Y200256D01*
Y201126D01*
X439223Y201476D01*
X439398D01*
Y199906D01*
X439223D01*
G37*
G36*
G01X454742Y164478D02*
X453992Y164528D01*
Y164928D01*
X454742Y164978D01*
X454942D01*
Y164478D01*
X454742D01*
G37*
G36*
G01X455142Y166278D02*
X455892Y166228D01*
Y165828D01*
X455142Y165778D01*
X454942D01*
Y166278D01*
X455142D01*
G37*
G36*
G01X451009Y172877D02*
X450444Y172382D01*
X450161Y172665D01*
X450656Y173230D01*
X450797Y173372D01*
X451151Y173018D01*
X451009Y172877D01*
G37*
G36*
G01X452848Y171038D02*
X452282Y170543D01*
X451999Y170826D01*
X452494Y171392D01*
X452636Y171533D01*
X452989Y171180D01*
X452848Y171038D01*
G37*
G36*
G01X451858Y172594D02*
X452424Y173089D01*
X452706Y172806D01*
X452212Y172240D01*
X452070Y172099D01*
X451717Y172452D01*
X451858Y172594D01*
G37*
G36*
G01X453696Y170755D02*
X454262Y171250D01*
X454545Y170968D01*
X454050Y170402D01*
X453909Y170260D01*
X453555Y170614D01*
X453696Y170755D01*
G37*
G36*
G01X454742Y167078D02*
X453992Y167128D01*
Y167528D01*
X454742Y167578D01*
X454942D01*
Y167078D01*
X454742D01*
G37*
G36*
G01X455142Y168878D02*
X455892Y168828D01*
Y168428D01*
X455142Y168378D01*
X454942D01*
Y168878D01*
X455142D01*
G37*
G36*
G01X446343Y178109D02*
X446908Y178604D01*
X447191Y178321D01*
X446696Y177756D01*
X446555Y177614D01*
X446201Y177968D01*
X446343Y178109D01*
G37*
G36*
G01X447332Y176554D02*
X446767Y176059D01*
X446484Y176342D01*
X446979Y176907D01*
X447120Y177049D01*
X447474Y176695D01*
X447332Y176554D01*
G37*
G36*
G01X449171Y174715D02*
X448605Y174220D01*
X448322Y174503D01*
X448817Y175069D01*
X448959Y175210D01*
X449312Y174857D01*
X449171Y174715D01*
G37*
G36*
G01X448181Y176271D02*
X448747Y176766D01*
X449030Y176483D01*
X448535Y175917D01*
X448393Y175776D01*
X448040Y176129D01*
X448181Y176271D01*
G37*
G36*
G01X450019Y174432D02*
X450585Y174927D01*
X450868Y174645D01*
X450373Y174079D01*
X450232Y173937D01*
X449878Y174291D01*
X450019Y174432D01*
G37*
G36*
G01X442914Y183166D02*
X442348Y182671D01*
X442065Y182953D01*
X442560Y183519D01*
X442701Y183661D01*
X443055Y183307D01*
X442914Y183166D01*
G37*
G36*
G01X442048Y186452D02*
X442798Y186402D01*
Y186002D01*
X442048Y185952D01*
X441848D01*
Y186452D01*
X442048D01*
G37*
G36*
G01Y189052D02*
X442798Y189002D01*
Y188602D01*
X442048Y188552D01*
X441848D01*
Y189052D01*
X442048D01*
G37*
G36*
G01Y191652D02*
X442798Y191602D01*
Y191202D01*
X442048Y191152D01*
X441848D01*
Y191652D01*
X442048D01*
G37*
G36*
G01X441648Y187252D02*
X440898Y187302D01*
Y187702D01*
X441648Y187752D01*
X441848D01*
Y187252D01*
X441648D01*
G37*
G36*
G01Y189852D02*
X440898Y189902D01*
Y190302D01*
X441648Y190352D01*
X441848D01*
Y189852D01*
X441648D01*
G37*
G36*
G01Y192452D02*
X440898Y192502D01*
Y192902D01*
X441648Y192952D01*
X441848D01*
Y192452D01*
X441648D01*
G37*
G36*
G01Y195052D02*
X440898Y195102D01*
Y195502D01*
X441648Y195552D01*
X441848D01*
Y195052D01*
X441648D01*
G37*
G36*
G01X442048Y194252D02*
X442798Y194202D01*
Y193802D01*
X442048Y193752D01*
X441848D01*
Y194252D01*
X442048D01*
G37*
G36*
G01X443762Y182883D02*
X444328Y183378D01*
X444611Y183095D01*
X444116Y182529D01*
X443974Y182388D01*
X443621Y182741D01*
X443762Y182883D01*
G37*
G36*
G01X444752Y181327D02*
X444186Y180832D01*
X443903Y181115D01*
X444398Y181681D01*
X444540Y181822D01*
X444893Y181469D01*
X444752Y181327D01*
G37*
G36*
G01X440865Y205281D02*
X441535Y204931D01*
Y204061D01*
X440865Y203711D01*
X440690D01*
Y205281D01*
X440865D01*
G37*
G36*
G01X456692Y163678D02*
X457442Y163628D01*
Y163228D01*
X456692Y163178D01*
X456492D01*
Y163678D01*
X456692D01*
G37*
G36*
G01Y166278D02*
X457442Y166228D01*
Y165828D01*
X456692Y165778D01*
X456492D01*
Y166278D01*
X456692D01*
G37*
G36*
G01X456292Y164478D02*
X455542Y164528D01*
Y164928D01*
X456292Y164978D01*
X456492D01*
Y164478D01*
X456292D01*
G37*
G36*
G01X454793Y171852D02*
X455359Y172347D01*
X455641Y172064D01*
X455146Y171498D01*
X455005Y171357D01*
X454652Y171710D01*
X454793Y171852D01*
G37*
G36*
G01X453944Y172135D02*
X453379Y171640D01*
X453096Y171923D01*
X453591Y172488D01*
X453732Y172630D01*
X454086Y172276D01*
X453944Y172135D01*
G37*
G36*
G01X455783Y170296D02*
X455217Y169801D01*
X454934Y170084D01*
X455429Y170650D01*
X455571Y170791D01*
X455924Y170438D01*
X455783Y170296D01*
G37*
G36*
G01X456692Y168878D02*
X457442Y168828D01*
Y168428D01*
X456692Y168378D01*
X456492D01*
Y168878D01*
X456692D01*
G37*
G36*
G01X456292Y167078D02*
X455542Y167128D01*
Y167528D01*
X456292Y167578D01*
X456492D01*
Y167078D01*
X456292D01*
G37*
G36*
G01X445601Y181044D02*
X446166Y181539D01*
X446449Y181256D01*
X445954Y180691D01*
X445813Y180549D01*
X445459Y180903D01*
X445601Y181044D01*
G37*
G36*
G01X446590Y179489D02*
X446025Y178994D01*
X445742Y179277D01*
X446237Y179842D01*
X446378Y179984D01*
X446732Y179630D01*
X446590Y179489D01*
G37*
G36*
G01X451116Y175529D02*
X451682Y176024D01*
X451965Y175741D01*
X451470Y175175D01*
X451328Y175034D01*
X450975Y175387D01*
X451116Y175529D01*
G37*
G36*
G01X452954Y173690D02*
X453520Y174185D01*
X453803Y173903D01*
X453308Y173337D01*
X453167Y173195D01*
X452813Y173549D01*
X452954Y173690D01*
G37*
G36*
G01X449277Y177367D02*
X449843Y177862D01*
X450126Y177579D01*
X449631Y177014D01*
X449490Y176872D01*
X449136Y177226D01*
X449277Y177367D01*
G37*
G36*
G01X447439Y179206D02*
X448005Y179701D01*
X448288Y179418D01*
X447793Y178852D01*
X447651Y178711D01*
X447298Y179064D01*
X447439Y179206D01*
G37*
G36*
G01X452106Y173973D02*
X451540Y173478D01*
X451257Y173761D01*
X451752Y174327D01*
X451894Y174468D01*
X452247Y174115D01*
X452106Y173973D01*
G37*
G36*
G01X450267Y175812D02*
X449702Y175317D01*
X449419Y175600D01*
X449914Y176165D01*
X450055Y176307D01*
X450409Y175953D01*
X450267Y175812D01*
G37*
G36*
G01X448429Y177650D02*
X447863Y177155D01*
X447580Y177438D01*
X448075Y178004D01*
X448217Y178145D01*
X448570Y177792D01*
X448429Y177650D01*
G37*
G36*
G01X468974Y172456D02*
X468408Y171961D01*
X468125Y172244D01*
X468620Y172810D01*
X468762Y172951D01*
X469115Y172598D01*
X468974Y172456D01*
G37*
G36*
G01X469822Y172174D02*
X470388Y172668D01*
X470671Y172386D01*
X470176Y171820D01*
X470034Y171679D01*
X469681Y172032D01*
X469822Y172174D01*
G37*
G36*
G01X471661Y170335D02*
X472227Y170830D01*
X472509Y170547D01*
X472014Y169981D01*
X471873Y169840D01*
X471519Y170194D01*
X471661Y170335D01*
G37*
G36*
G01X470812Y170618D02*
X470247Y170123D01*
X469964Y170406D01*
X470459Y170971D01*
X470600Y171113D01*
X470954Y170759D01*
X470812Y170618D01*
G37*
G36*
G01X473499Y168497D02*
X474065Y168992D01*
X474348Y168709D01*
X473853Y168143D01*
X473711Y168002D01*
X473358Y168355D01*
X473499Y168497D01*
G37*
G36*
G01X475337Y166658D02*
X475903Y167153D01*
X476186Y166870D01*
X475691Y166304D01*
X475549Y166163D01*
X475196Y166516D01*
X475337Y166658D01*
G37*
G36*
G01X460630Y181366D02*
X461196Y181861D01*
X461478Y181578D01*
X460984Y181012D01*
X460842Y180871D01*
X460489Y181224D01*
X460630Y181366D01*
G37*
G36*
G01X458791Y183204D02*
X459357Y183699D01*
X459640Y183417D01*
X459145Y182851D01*
X459004Y182709D01*
X458650Y183063D01*
X458791Y183204D01*
G37*
G36*
G01X456953Y185043D02*
X457519Y185538D01*
X457802Y185255D01*
X457307Y184689D01*
X457165Y184548D01*
X456812Y184901D01*
X456953Y185043D01*
G37*
G36*
G01X455115Y186881D02*
X455680Y187376D01*
X455963Y187093D01*
X455468Y186528D01*
X455327Y186386D01*
X454973Y186740D01*
X455115Y186881D01*
G37*
G36*
G01X453276Y188720D02*
X453842Y189215D01*
X454125Y188932D01*
X453630Y188366D01*
X453488Y188225D01*
X453135Y188578D01*
X453276Y188720D01*
G37*
G36*
G01X465297Y176133D02*
X464731Y175638D01*
X464448Y175921D01*
X464943Y176487D01*
X465085Y176628D01*
X465438Y176275D01*
X465297Y176133D01*
G37*
G36*
G01X467135Y174295D02*
X466570Y173800D01*
X466287Y174083D01*
X466782Y174648D01*
X466923Y174790D01*
X467277Y174436D01*
X467135Y174295D01*
G37*
G36*
G01X463458Y177972D02*
X462893Y177477D01*
X462610Y177760D01*
X463105Y178325D01*
X463246Y178467D01*
X463600Y178113D01*
X463458Y177972D01*
G37*
G36*
G01X461620Y179810D02*
X461054Y179315D01*
X460771Y179598D01*
X461266Y180164D01*
X461408Y180305D01*
X461761Y179952D01*
X461620Y179810D01*
G37*
G36*
G01X459781Y181649D02*
X459216Y181154D01*
X458933Y181437D01*
X459428Y182002D01*
X459569Y182144D01*
X459923Y181790D01*
X459781Y181649D01*
G37*
G36*
G01X457943Y183487D02*
X457377Y182992D01*
X457094Y183275D01*
X457589Y183841D01*
X457731Y183982D01*
X458084Y183629D01*
X457943Y183487D01*
G37*
G36*
G01X456104Y185326D02*
X455539Y184831D01*
X455256Y185114D01*
X455751Y185679D01*
X455892Y185821D01*
X456246Y185467D01*
X456104Y185326D01*
G37*
G36*
G01X454266Y187164D02*
X453700Y186669D01*
X453417Y186952D01*
X453912Y187518D01*
X454054Y187659D01*
X454407Y187306D01*
X454266Y187164D01*
G37*
G36*
G01X452898Y191652D02*
X453648Y191602D01*
Y191202D01*
X452898Y191152D01*
X452698D01*
Y191652D01*
X452898D01*
G37*
G36*
G01Y194252D02*
X453648Y194202D01*
Y193802D01*
X452898Y193752D01*
X452698D01*
Y194252D01*
X452898D01*
G37*
G36*
G01X452498Y189852D02*
X451748Y189902D01*
Y190302D01*
X452498Y190352D01*
X452698D01*
Y189852D01*
X452498D01*
G37*
G36*
G01Y192452D02*
X451748Y192502D01*
Y192902D01*
X452498Y192952D01*
X452698D01*
Y192452D01*
X452498D01*
G37*
G36*
G01X452223Y197359D02*
X451553Y197709D01*
Y198579D01*
X452223Y198929D01*
X452398D01*
Y197359D01*
X452223D01*
G37*
G36*
G01X466145Y175850D02*
X466711Y176345D01*
X466994Y176063D01*
X466499Y175497D01*
X466358Y175355D01*
X466004Y175709D01*
X466145Y175850D01*
G37*
G36*
G01X467984Y174012D02*
X468550Y174507D01*
X468832Y174224D01*
X468337Y173658D01*
X468196Y173517D01*
X467842Y173871D01*
X467984Y174012D01*
G37*
G36*
G01X464307Y177689D02*
X464873Y178184D01*
X465155Y177901D01*
X464660Y177335D01*
X464519Y177194D01*
X464165Y177548D01*
X464307Y177689D01*
G37*
G36*
G01X462468Y179527D02*
X463034Y180022D01*
X463317Y179740D01*
X462822Y179174D01*
X462681Y179032D01*
X462327Y179386D01*
X462468Y179527D01*
G37*
G36*
G01X452223Y201259D02*
X451553Y201609D01*
Y202479D01*
X452223Y202829D01*
X452398D01*
Y201259D01*
X452223D01*
G37*
G36*
G01X470919Y173270D02*
X471485Y173765D01*
X471767Y173482D01*
X471272Y172916D01*
X471131Y172775D01*
X470777Y173129D01*
X470919Y173270D01*
G37*
G36*
G01X472757Y171432D02*
X473323Y171927D01*
X473606Y171644D01*
X473111Y171078D01*
X472969Y170937D01*
X472616Y171290D01*
X472757Y171432D01*
G37*
G36*
G01X471909Y171714D02*
X471343Y171219D01*
X471060Y171502D01*
X471555Y172068D01*
X471697Y172209D01*
X472050Y171856D01*
X471909Y171714D01*
G37*
G36*
G01X473747Y169876D02*
X473182Y169381D01*
X472899Y169664D01*
X473394Y170229D01*
X473535Y170371D01*
X473889Y170017D01*
X473747Y169876D01*
G37*
G36*
G01X474596Y169593D02*
X475161Y170088D01*
X475444Y169805D01*
X474949Y169239D01*
X474808Y169098D01*
X474454Y169452D01*
X474596Y169593D01*
G37*
G36*
G01X475586Y168037D02*
X475020Y167542D01*
X474737Y167825D01*
X475232Y168391D01*
X475374Y168532D01*
X475727Y168179D01*
X475586Y168037D01*
G37*
G36*
G01X463565Y180624D02*
X464131Y181119D01*
X464413Y180836D01*
X463918Y180270D01*
X463777Y180129D01*
X463424Y180482D01*
X463565Y180624D01*
G37*
G36*
G01X461726Y182462D02*
X462292Y182957D01*
X462575Y182675D01*
X462080Y182109D01*
X461939Y181967D01*
X461585Y182321D01*
X461726Y182462D01*
G37*
G36*
G01X459888Y184301D02*
X460454Y184796D01*
X460737Y184513D01*
X460242Y183947D01*
X460100Y183806D01*
X459747Y184159D01*
X459888Y184301D01*
G37*
G36*
G01X458049Y186139D02*
X458615Y186634D01*
X458898Y186351D01*
X458403Y185786D01*
X458262Y185644D01*
X457908Y185998D01*
X458049Y186139D01*
G37*
G36*
G01X456211Y187978D02*
X456777Y188473D01*
X457060Y188190D01*
X456565Y187624D01*
X456423Y187483D01*
X456070Y187836D01*
X456211Y187978D01*
G37*
G36*
G01X465403Y178785D02*
X465969Y179280D01*
X466252Y178998D01*
X465757Y178432D01*
X465616Y178290D01*
X465262Y178644D01*
X465403Y178785D01*
G37*
G36*
G01X467242Y176947D02*
X467808Y177442D01*
X468090Y177159D01*
X467595Y176593D01*
X467454Y176452D01*
X467100Y176806D01*
X467242Y176947D01*
G37*
G36*
G01X464555Y179068D02*
X463989Y178573D01*
X463706Y178856D01*
X464201Y179422D01*
X464343Y179563D01*
X464696Y179210D01*
X464555Y179068D01*
G37*
G36*
G01X462716Y180907D02*
X462151Y180412D01*
X461868Y180695D01*
X462363Y181260D01*
X462504Y181402D01*
X462858Y181048D01*
X462716Y180907D01*
G37*
G36*
G01X460878Y182745D02*
X460312Y182250D01*
X460029Y182533D01*
X460524Y183099D01*
X460666Y183240D01*
X461019Y182887D01*
X460878Y182745D01*
G37*
G36*
G01X459039Y184584D02*
X458474Y184089D01*
X458191Y184372D01*
X458686Y184937D01*
X458827Y185079D01*
X459181Y184725D01*
X459039Y184584D01*
G37*
G36*
G01X457201Y186422D02*
X456635Y185927D01*
X456352Y186210D01*
X456847Y186776D01*
X456989Y186917D01*
X457342Y186564D01*
X457201Y186422D01*
G37*
G36*
G01X455362Y188261D02*
X454797Y187766D01*
X454514Y188049D01*
X455009Y188614D01*
X455150Y188756D01*
X455504Y188402D01*
X455362Y188261D01*
G37*
G36*
G01X466393Y177230D02*
X465828Y176735D01*
X465545Y177018D01*
X466040Y177583D01*
X466181Y177725D01*
X466535Y177371D01*
X466393Y177230D01*
G37*
G36*
G01X468232Y175391D02*
X467666Y174896D01*
X467383Y175179D01*
X467878Y175745D01*
X468020Y175886D01*
X468373Y175533D01*
X468232Y175391D01*
G37*
G36*
G01X454448Y194252D02*
X455198Y194202D01*
Y193802D01*
X454448Y193752D01*
X454248D01*
Y194252D01*
X454448D01*
G37*
G36*
G01Y191652D02*
X455198Y191602D01*
Y191202D01*
X454448Y191152D01*
X454248D01*
Y191652D01*
X454448D01*
G37*
G36*
G01X454048Y192452D02*
X453298Y192502D01*
Y192902D01*
X454048Y192952D01*
X454248D01*
Y192452D01*
X454048D01*
G37*
G36*
G01X453323Y201140D02*
X453993Y200790D01*
Y199920D01*
X453323Y199570D01*
X453148D01*
Y201140D01*
X453323D01*
G37*
G36*
G01X469080Y175108D02*
X469646Y175603D01*
X469929Y175321D01*
X469434Y174755D01*
X469292Y174614D01*
X468939Y174967D01*
X469080Y175108D01*
G37*
G36*
G01X470070Y173553D02*
X469505Y173058D01*
X469222Y173341D01*
X469717Y173906D01*
X469858Y174048D01*
X470212Y173694D01*
X470070Y173553D01*
G37*
G36*
G01X453634Y205301D02*
X454304Y204951D01*
Y204081D01*
X453634Y203731D01*
X453459D01*
Y205301D01*
X453634D01*
G37*
G36*
G01Y209182D02*
X454304Y208832D01*
Y207962D01*
X453634Y207612D01*
X453459D01*
Y209182D01*
X453634D01*
G37*
G36*
G01X476434Y167754D02*
X476999Y168249D01*
X477282Y167966D01*
X476787Y167400D01*
X476646Y167259D01*
X476292Y167613D01*
X476434Y167754D01*
G37*
G36*
G01X467057Y192048D02*
X467623Y192543D01*
X467906Y192260D01*
X467411Y191694D01*
X467269Y191553D01*
X466916Y191906D01*
X467057Y192048D01*
G37*
G36*
G01X465218Y193886D02*
X465784Y194381D01*
X466067Y194098D01*
X465572Y193533D01*
X465431Y193391D01*
X465077Y193745D01*
X465218Y193886D01*
G37*
G36*
G01X468047Y190492D02*
X467481Y189997D01*
X467198Y190280D01*
X467693Y190846D01*
X467835Y190987D01*
X468188Y190634D01*
X468047Y190492D01*
G37*
G36*
G01X466208Y192331D02*
X465643Y191836D01*
X465360Y192119D01*
X465855Y192684D01*
X465996Y192826D01*
X466350Y192472D01*
X466208Y192331D01*
G37*
G36*
G01X464073Y196108D02*
X463403Y196458D01*
Y197328D01*
X464073Y197678D01*
X464248D01*
Y196108D01*
X464073D01*
G37*
G36*
G01Y200008D02*
X463403Y200358D01*
Y201228D01*
X464073Y201578D01*
X464248D01*
Y200008D01*
X464073D01*
G37*
G36*
G01X472572Y186532D02*
X473138Y187027D01*
X473421Y186745D01*
X472926Y186179D01*
X472785Y186037D01*
X472431Y186391D01*
X472572Y186532D01*
G37*
G36*
G01X470734Y188371D02*
X471300Y188866D01*
X471582Y188583D01*
X471087Y188017D01*
X470946Y187876D01*
X470593Y188229D01*
X470734Y188371D01*
G37*
G36*
G01X468895Y190209D02*
X469461Y190704D01*
X469744Y190422D01*
X469249Y189856D01*
X469108Y189714D01*
X468754Y190068D01*
X468895Y190209D01*
G37*
G36*
G01X473562Y184977D02*
X472997Y184482D01*
X472714Y184765D01*
X473209Y185330D01*
X473350Y185472D01*
X473704Y185118D01*
X473562Y184977D01*
G37*
G36*
G01X471724Y186815D02*
X471158Y186320D01*
X470875Y186603D01*
X471370Y187169D01*
X471512Y187310D01*
X471865Y186957D01*
X471724Y186815D01*
G37*
G36*
G01X469885Y188654D02*
X469320Y188159D01*
X469037Y188442D01*
X469532Y189007D01*
X469673Y189149D01*
X470027Y188795D01*
X469885Y188654D01*
G37*
G36*
G01X474411Y184694D02*
X474977Y185189D01*
X475259Y184906D01*
X474764Y184340D01*
X474623Y184199D01*
X474269Y184553D01*
X474411Y184694D01*
G37*
G36*
G01X476249Y182855D02*
X476815Y183350D01*
X477098Y183068D01*
X476603Y182502D01*
X476461Y182361D01*
X476108Y182714D01*
X476249Y182855D01*
G37*
G36*
G01X475401Y183138D02*
X474835Y182643D01*
X474552Y182926D01*
X475047Y183492D01*
X475189Y183633D01*
X475542Y183280D01*
X475401Y183138D01*
G37*
G36*
G01X477239Y181300D02*
X476674Y180805D01*
X476391Y181088D01*
X476886Y181653D01*
X477027Y181795D01*
X477381Y181441D01*
X477239Y181300D01*
G37*
G36*
G01X469143Y191589D02*
X468578Y191094D01*
X468295Y191377D01*
X468790Y191942D01*
X468931Y192084D01*
X469285Y191730D01*
X469143Y191589D01*
G37*
G36*
G01X467305Y193427D02*
X466739Y192932D01*
X466456Y193215D01*
X466951Y193781D01*
X467093Y193922D01*
X467446Y193569D01*
X467305Y193427D01*
G37*
G36*
G01X465173Y197678D02*
X465843Y197328D01*
Y196458D01*
X465173Y196108D01*
X464998D01*
Y197678D01*
X465173D01*
G37*
G36*
G01Y201578D02*
X465843Y201228D01*
Y200358D01*
X465173Y200008D01*
X464998D01*
Y201578D01*
X465173D01*
G37*
G36*
G01X473669Y187629D02*
X474235Y188124D01*
X474517Y187841D01*
X474022Y187275D01*
X473881Y187134D01*
X473527Y187488D01*
X473669Y187629D01*
G37*
G36*
G01X471830Y189467D02*
X472396Y189962D01*
X472679Y189680D01*
X472184Y189114D01*
X472043Y188972D01*
X471689Y189326D01*
X471830Y189467D01*
G37*
G36*
G01X469992Y191306D02*
X470558Y191801D01*
X470840Y191518D01*
X470346Y190952D01*
X470204Y190811D01*
X469851Y191164D01*
X469992Y191306D01*
G37*
G36*
G01X474659Y186073D02*
X474093Y185578D01*
X473810Y185861D01*
X474305Y186427D01*
X474447Y186568D01*
X474800Y186215D01*
X474659Y186073D01*
G37*
G36*
G01X472820Y187912D02*
X472255Y187417D01*
X471972Y187700D01*
X472467Y188265D01*
X472608Y188407D01*
X472962Y188053D01*
X472820Y187912D01*
G37*
G36*
G01X470982Y189750D02*
X470416Y189255D01*
X470133Y189538D01*
X470628Y190104D01*
X470770Y190245D01*
X471123Y189892D01*
X470982Y189750D01*
G37*
G36*
G01X475507Y185790D02*
X476073Y186285D01*
X476356Y186003D01*
X475861Y185437D01*
X475720Y185295D01*
X475366Y185649D01*
X475507Y185790D01*
G37*
G36*
G01X476497Y184235D02*
X475932Y183740D01*
X475649Y184023D01*
X476144Y184588D01*
X476285Y184730D01*
X476639Y184376D01*
X476497Y184235D01*
G37*
G36*
G01X478336Y182396D02*
X477770Y181901D01*
X477487Y182184D01*
X477982Y182750D01*
X478124Y182891D01*
X478477Y182538D01*
X478336Y182396D01*
G37*
G36*
G01X477346Y183952D02*
X477912Y184447D01*
X478194Y184164D01*
X477699Y183598D01*
X477558Y183457D01*
X477204Y183811D01*
X477346Y183952D01*
G37*
G36*
G01X478069Y198729D02*
X477399Y199079D01*
Y199949D01*
X478069Y200299D01*
X478244D01*
Y198729D01*
X478069D01*
G37*
G36*
G01X477292Y207211D02*
X477962Y206861D01*
Y205991D01*
X477292Y205641D01*
X477118D01*
X477117Y207212D01*
X477292Y207211D01*
G37*
G36*
G01X467692Y186461D02*
X467127Y185966D01*
X466844Y186249D01*
X467339Y186814D01*
X467480Y186956D01*
X467834Y186602D01*
X467692Y186461D01*
G37*
G36*
G01X465854Y188299D02*
X465288Y187804D01*
X465005Y188087D01*
X465500Y188653D01*
X465642Y188794D01*
X465995Y188441D01*
X465854Y188299D01*
G37*
G36*
G01X464015Y190138D02*
X463450Y189643D01*
X463167Y189926D01*
X463662Y190491D01*
X463803Y190633D01*
X464157Y190279D01*
X464015Y190138D01*
G37*
G36*
G01X468541Y186178D02*
X469107Y186673D01*
X469389Y186390D01*
X468894Y185824D01*
X468753Y185683D01*
X468400Y186036D01*
X468541Y186178D01*
G37*
G36*
G01X466702Y188016D02*
X467268Y188511D01*
X467551Y188229D01*
X467056Y187663D01*
X466915Y187521D01*
X466561Y187875D01*
X466702Y188016D01*
G37*
G36*
G01X464864Y189855D02*
X465430Y190350D01*
X465713Y190067D01*
X465218Y189501D01*
X465076Y189360D01*
X464723Y189713D01*
X464864Y189855D01*
G37*
G36*
G01X463025Y191693D02*
X463591Y192188D01*
X463874Y191905D01*
X463379Y191340D01*
X463238Y191198D01*
X462884Y191552D01*
X463025Y191693D01*
G37*
G36*
G01X461021Y195120D02*
X460300Y194894D01*
X459685Y195509D01*
X459911Y196230D01*
X460035Y196354D01*
X461145Y195244D01*
X461021Y195120D01*
G37*
G36*
G01X469531Y184622D02*
X468965Y184127D01*
X468682Y184410D01*
X469177Y184976D01*
X469319Y185117D01*
X469672Y184764D01*
X469531Y184622D01*
G37*
G36*
G01X471369Y182784D02*
X470804Y182289D01*
X470521Y182572D01*
X471016Y183137D01*
X471157Y183279D01*
X471511Y182925D01*
X471369Y182784D01*
G37*
G36*
G01X473208Y180945D02*
X472642Y180450D01*
X472359Y180733D01*
X472854Y181299D01*
X472996Y181440D01*
X473349Y181087D01*
X473208Y180945D01*
G37*
G36*
G01X475046Y179107D02*
X474481Y178612D01*
X474198Y178895D01*
X474693Y179460D01*
X474834Y179602D01*
X475188Y179248D01*
X475046Y179107D01*
G37*
G36*
G01X470379Y184339D02*
X470945Y184834D01*
X471228Y184552D01*
X470733Y183986D01*
X470592Y183844D01*
X470238Y184198D01*
X470379Y184339D01*
G37*
G36*
G01X472218Y182501D02*
X472784Y182996D01*
X473066Y182713D01*
X472571Y182147D01*
X472430Y182006D01*
X472076Y182360D01*
X472218Y182501D01*
G37*
G36*
G01X474056Y180662D02*
X474622Y181157D01*
X474905Y180875D01*
X474410Y180309D01*
X474268Y180168D01*
X473915Y180521D01*
X474056Y180662D01*
G37*
G36*
G01X476885Y177268D02*
X476319Y176773D01*
X476036Y177056D01*
X476531Y177622D01*
X476673Y177763D01*
X477026Y177410D01*
X476885Y177268D01*
G37*
G36*
G01X475895Y178824D02*
X476461Y179319D01*
X476743Y179036D01*
X476248Y178470D01*
X476107Y178329D01*
X475753Y178683D01*
X475895Y178824D01*
G37*
G36*
G01X477733Y176986D02*
X478299Y177481D01*
X478582Y177198D01*
X478087Y176632D01*
X477945Y176491D01*
X477592Y176844D01*
X477733Y176986D01*
G37*
G36*
G01X467799Y189113D02*
X468365Y189608D01*
X468647Y189325D01*
X468153Y188759D01*
X468011Y188618D01*
X467658Y188971D01*
X467799Y189113D01*
G37*
G36*
G01X465960Y190951D02*
X466526Y191446D01*
X466809Y191164D01*
X466314Y190598D01*
X466173Y190456D01*
X465819Y190810D01*
X465960Y190951D01*
G37*
G36*
G01X464122Y192790D02*
X464688Y193285D01*
X464971Y193002D01*
X464476Y192436D01*
X464334Y192295D01*
X463981Y192648D01*
X464122Y192790D01*
G37*
G36*
G01X468789Y187557D02*
X468223Y187062D01*
X467940Y187345D01*
X468435Y187911D01*
X468577Y188052D01*
X468930Y187699D01*
X468789Y187557D01*
G37*
G36*
G01X466950Y189396D02*
X466385Y188901D01*
X466102Y189184D01*
X466597Y189749D01*
X466738Y189891D01*
X467092Y189537D01*
X466950Y189396D01*
G37*
G36*
G01X465112Y191234D02*
X464546Y190739D01*
X464263Y191022D01*
X464758Y191588D01*
X464900Y191729D01*
X465253Y191376D01*
X465112Y191234D01*
G37*
G36*
G01X461160Y196538D02*
X461882Y196764D01*
X462497Y196149D01*
X462271Y195428D01*
X462147Y195304D01*
X461037Y196414D01*
X461160Y196538D01*
G37*
G36*
G01X470627Y185719D02*
X470062Y185224D01*
X469779Y185507D01*
X470274Y186072D01*
X470415Y186214D01*
X470769Y185860D01*
X470627Y185719D01*
G37*
G36*
G01X472466Y183880D02*
X471900Y183385D01*
X471617Y183668D01*
X472112Y184234D01*
X472254Y184375D01*
X472607Y184022D01*
X472466Y183880D01*
G37*
G36*
G01X474304Y182042D02*
X473739Y181547D01*
X473456Y181830D01*
X473951Y182395D01*
X474092Y182537D01*
X474446Y182183D01*
X474304Y182042D01*
G37*
G36*
G01X471476Y185436D02*
X472042Y185931D01*
X472324Y185648D01*
X471829Y185082D01*
X471688Y184941D01*
X471334Y185295D01*
X471476Y185436D01*
G37*
G36*
G01X469637Y187274D02*
X470203Y187769D01*
X470486Y187487D01*
X469991Y186921D01*
X469850Y186779D01*
X469496Y187133D01*
X469637Y187274D01*
G37*
G36*
G01X473314Y183597D02*
X473880Y184092D01*
X474163Y183810D01*
X473668Y183244D01*
X473527Y183102D01*
X473173Y183456D01*
X473314Y183597D01*
G37*
G36*
G01X475153Y181759D02*
X475719Y182254D01*
X476001Y181971D01*
X475506Y181405D01*
X475365Y181264D01*
X475011Y181618D01*
X475153Y181759D01*
G37*
G36*
G01X476143Y180203D02*
X475577Y179708D01*
X475294Y179991D01*
X475789Y180557D01*
X475931Y180698D01*
X476284Y180345D01*
X476143Y180203D01*
G37*
G36*
G01X463984Y208591D02*
X464016Y207836D01*
X463263Y207401D01*
X462625Y207806D01*
X462537Y207957D01*
X463897Y208743D01*
X463984Y208591D01*
G37*
G36*
G01X476991Y179921D02*
X477557Y180415D01*
X477840Y180133D01*
X477345Y179567D01*
X477203Y179426D01*
X476850Y179779D01*
X476991Y179921D01*
G37*
G36*
G01X477981Y178365D02*
X477416Y177870D01*
X477133Y178153D01*
X477628Y178718D01*
X477769Y178860D01*
X478123Y178506D01*
X477981Y178365D01*
G37*
G36*
G01X461145Y205278D02*
X461815Y204928D01*
Y204058D01*
X461145Y203708D01*
X460970D01*
Y205278D01*
X461145D01*
G37*
G36*
G01X474132Y197039D02*
X473411Y196813D01*
X472796Y197428D01*
X473022Y198149D01*
X473146Y198273D01*
X474256Y197163D01*
X474132Y197039D01*
G37*
G36*
G01X472713Y199847D02*
X472043Y200197D01*
Y201067D01*
X472713Y201417D01*
X472888D01*
Y199847D01*
X472713D01*
G37*
G36*
G01X476464Y195233D02*
X475899Y194738D01*
X475616Y195021D01*
X476111Y195586D01*
X476252Y195728D01*
X476606Y195374D01*
X476464Y195233D01*
G37*
G36*
G01X477313Y194950D02*
X477879Y195445D01*
X478161Y195162D01*
X477666Y194596D01*
X477525Y194455D01*
X477172Y194808D01*
X477313Y194950D01*
G37*
G36*
G01X478303Y193394D02*
X477737Y192899D01*
X477454Y193182D01*
X477949Y193748D01*
X478091Y193889D01*
X478444Y193536D01*
X478303Y193394D01*
G37*
G36*
G01X473813Y205217D02*
X474483Y204867D01*
Y203997D01*
X473813Y203647D01*
X473638D01*
Y205217D01*
X473813D01*
G37*
G36*
G01Y209117D02*
X474483Y208767D01*
Y207897D01*
X473813Y207547D01*
X473638D01*
Y209117D01*
X473813D01*
G37*
G36*
G01X465954Y164964D02*
X466704Y164914D01*
Y164514D01*
X465954Y164464D01*
X465754D01*
Y164964D01*
X465954D01*
G37*
G36*
G01X465554Y165764D02*
X464804Y165814D01*
Y166214D01*
X465554Y166264D01*
X465754D01*
Y165764D01*
X465554D01*
G37*
G36*
G01Y163164D02*
X464804Y163214D01*
Y163614D01*
X465554Y163664D01*
X465754D01*
Y163164D01*
X465554D01*
G37*
G36*
G01X465954Y167564D02*
X466704Y167514D01*
Y167114D01*
X465954Y167064D01*
X465754D01*
Y167564D01*
X465954D01*
G37*
G36*
G01X465554Y168364D02*
X464804Y168414D01*
Y168814D01*
X465554Y168864D01*
X465754D01*
Y168364D01*
X465554D01*
G37*
G36*
G01X462856Y172561D02*
X463422Y173056D01*
X463704Y172773D01*
X463209Y172207D01*
X463068Y172066D01*
X462714Y172420D01*
X462856Y172561D01*
G37*
G36*
G01X464694Y170722D02*
X465260Y171217D01*
X465543Y170935D01*
X465048Y170369D01*
X464906Y170228D01*
X464553Y170581D01*
X464694Y170722D01*
G37*
G36*
G01X462007Y172844D02*
X461442Y172349D01*
X461159Y172632D01*
X461654Y173197D01*
X461795Y173339D01*
X462149Y172985D01*
X462007Y172844D01*
G37*
G36*
G01X463846Y171005D02*
X463280Y170510D01*
X462997Y170793D01*
X463492Y171359D01*
X463634Y171500D01*
X463987Y171147D01*
X463846Y171005D01*
G37*
G36*
G01X447848Y189852D02*
X447098Y189902D01*
Y190302D01*
X447848Y190352D01*
X448048D01*
Y189852D01*
X447848D01*
G37*
G36*
G01X455502Y179915D02*
X456068Y180410D01*
X456351Y180127D01*
X455856Y179561D01*
X455714Y179420D01*
X455361Y179773D01*
X455502Y179915D01*
G37*
G36*
G01X453663Y181753D02*
X454229Y182248D01*
X454512Y181965D01*
X454017Y181400D01*
X453876Y181258D01*
X453522Y181612D01*
X453663Y181753D01*
G37*
G36*
G01X451825Y183592D02*
X452391Y184087D01*
X452674Y183804D01*
X452179Y183238D01*
X452037Y183097D01*
X451684Y183450D01*
X451825Y183592D01*
G37*
G36*
G01X449987Y185430D02*
X450552Y185925D01*
X450835Y185642D01*
X450340Y185077D01*
X450199Y184935D01*
X449845Y185289D01*
X449987Y185430D01*
G37*
G36*
G01X457340Y178076D02*
X457906Y178571D01*
X458189Y178289D01*
X457694Y177723D01*
X457553Y177581D01*
X457199Y177935D01*
X457340Y178076D01*
G37*
G36*
G01X459179Y176238D02*
X459745Y176733D01*
X460027Y176450D01*
X459532Y175884D01*
X459391Y175743D01*
X459038Y176096D01*
X459179Y176238D01*
G37*
G36*
G01X461017Y174399D02*
X461583Y174894D01*
X461866Y174612D01*
X461371Y174046D01*
X461230Y173904D01*
X460876Y174258D01*
X461017Y174399D01*
G37*
G36*
G01X456492Y178359D02*
X455926Y177864D01*
X455643Y178147D01*
X456138Y178713D01*
X456280Y178854D01*
X456633Y178501D01*
X456492Y178359D01*
G37*
G36*
G01X454653Y180198D02*
X454088Y179703D01*
X453805Y179986D01*
X454300Y180551D01*
X454441Y180693D01*
X454795Y180339D01*
X454653Y180198D01*
G37*
G36*
G01X452815Y182036D02*
X452249Y181541D01*
X451966Y181824D01*
X452461Y182390D01*
X452603Y182531D01*
X452956Y182178D01*
X452815Y182036D01*
G37*
G36*
G01X450976Y183875D02*
X450411Y183380D01*
X450128Y183663D01*
X450623Y184228D01*
X450764Y184370D01*
X451118Y184016D01*
X450976Y183875D01*
G37*
G36*
G01X449138Y185713D02*
X448572Y185218D01*
X448289Y185501D01*
X448784Y186067D01*
X448926Y186208D01*
X449279Y185855D01*
X449138Y185713D01*
G37*
G36*
G01X458330Y176521D02*
X457765Y176026D01*
X457482Y176309D01*
X457977Y176874D01*
X458118Y177016D01*
X458472Y176662D01*
X458330Y176521D01*
G37*
G36*
G01X460169Y174682D02*
X459603Y174187D01*
X459320Y174470D01*
X459815Y175036D01*
X459957Y175177D01*
X460310Y174824D01*
X460169Y174682D01*
G37*
G36*
G01X448248Y194252D02*
X448998Y194202D01*
Y193802D01*
X448248Y193752D01*
X448048D01*
Y194252D01*
X448248D01*
G37*
G36*
G01Y191652D02*
X448998Y191602D01*
Y191202D01*
X448248Y191152D01*
X448048D01*
Y191652D01*
X448248D01*
G37*
G36*
G01Y189052D02*
X448998Y189002D01*
Y188602D01*
X448248Y188552D01*
X448048D01*
Y189052D01*
X448248D01*
G37*
G36*
G01X447848Y192452D02*
X447098Y192502D01*
Y192902D01*
X447848Y192952D01*
X448048D01*
Y192452D01*
X447848D01*
G37*
G36*
G01X447817Y199888D02*
X448487Y199538D01*
Y198668D01*
X447817Y198318D01*
X447642D01*
Y199888D01*
X447817D01*
G37*
G36*
G01X474023Y191660D02*
X474589Y192155D01*
X474872Y191873D01*
X474377Y191307D01*
X474236Y191165D01*
X473882Y191519D01*
X474023Y191660D01*
G37*
G36*
G01X472185Y193499D02*
X472751Y193994D01*
X473033Y193711D01*
X472539Y193145D01*
X472397Y193004D01*
X472044Y193357D01*
X472185Y193499D01*
G37*
G36*
G01X475013Y190105D02*
X474448Y189610D01*
X474165Y189893D01*
X474660Y190458D01*
X474801Y190600D01*
X475155Y190246D01*
X475013Y190105D01*
G37*
G36*
G01X473176Y191943D02*
X472610Y191448D01*
X472327Y191731D01*
X472822Y192297D01*
X472964Y192438D01*
X473317Y192085D01*
X473176Y191943D01*
G37*
G36*
G01X469015Y196028D02*
X469736Y196255D01*
X470352Y195639D01*
X470125Y194918D01*
X470002Y194794D01*
X468891Y195905D01*
X469015Y196028D01*
G37*
G36*
G01X475862Y189822D02*
X476428Y190317D01*
X476710Y190034D01*
X476215Y189468D01*
X476074Y189327D01*
X475720Y189681D01*
X475862Y189822D01*
G37*
G36*
G01X476853Y188266D02*
X476287Y187771D01*
X476004Y188054D01*
X476499Y188620D01*
X476641Y188761D01*
X476994Y188408D01*
X476853Y188266D01*
G37*
G36*
G01X478690Y186428D02*
X478125Y185933D01*
X477842Y186216D01*
X478337Y186781D01*
X478478Y186923D01*
X478832Y186569D01*
X478690Y186428D01*
G37*
G36*
G01X477700Y187983D02*
X478266Y188478D01*
X478549Y188196D01*
X478054Y187630D01*
X477913Y187488D01*
X477559Y187842D01*
X477700Y187983D01*
G37*
G36*
G01X468304Y165764D02*
X467554Y165814D01*
Y166214D01*
X468304Y166264D01*
X468504D01*
Y165764D01*
X468304D01*
G37*
G36*
G01X465791Y171819D02*
X466357Y172314D01*
X466639Y172031D01*
X466144Y171465D01*
X466003Y171324D01*
X465649Y171678D01*
X465791Y171819D01*
G37*
G36*
G01X467629Y169981D02*
X468195Y170475D01*
X468478Y170193D01*
X467983Y169627D01*
X467841Y169486D01*
X467488Y169839D01*
X467629Y169981D01*
G37*
G36*
G01X464942Y172102D02*
X464377Y171607D01*
X464094Y171890D01*
X464589Y172455D01*
X464730Y172597D01*
X465084Y172243D01*
X464942Y172102D01*
G37*
G36*
G01X466781Y170263D02*
X466215Y169768D01*
X465932Y170051D01*
X466427Y170617D01*
X466569Y170758D01*
X466922Y170405D01*
X466781Y170263D01*
G37*
G36*
G01X468704Y164964D02*
X469454Y164914D01*
Y164514D01*
X468704Y164464D01*
X468504D01*
Y164964D01*
X468704D01*
G37*
G36*
G01Y167564D02*
X469454Y167514D01*
Y167114D01*
X468704Y167064D01*
X468504D01*
Y167564D01*
X468704D01*
G37*
G36*
G01X462114Y175496D02*
X462680Y175991D01*
X462962Y175708D01*
X462467Y175142D01*
X462326Y175001D01*
X461972Y175355D01*
X462114Y175496D01*
G37*
G36*
G01X463952Y173657D02*
X464518Y174152D01*
X464801Y173870D01*
X464306Y173304D01*
X464165Y173162D01*
X463811Y173516D01*
X463952Y173657D01*
G37*
G36*
G01X457588Y179456D02*
X457023Y178961D01*
X456740Y179244D01*
X457235Y179809D01*
X457376Y179951D01*
X457730Y179597D01*
X457588Y179456D01*
G37*
G36*
G01X455750Y181294D02*
X455184Y180799D01*
X454901Y181082D01*
X455396Y181648D01*
X455538Y181789D01*
X455891Y181436D01*
X455750Y181294D01*
G37*
G36*
G01X453911Y183133D02*
X453346Y182638D01*
X453063Y182921D01*
X453558Y183486D01*
X453699Y183628D01*
X454053Y183274D01*
X453911Y183133D01*
G37*
G36*
G01X452073Y184971D02*
X451507Y184476D01*
X451224Y184759D01*
X451719Y185325D01*
X451861Y185466D01*
X452214Y185113D01*
X452073Y184971D01*
G37*
G36*
G01X450235Y186810D02*
X449669Y186315D01*
X449386Y186598D01*
X449881Y187163D01*
X450022Y187305D01*
X450376Y186951D01*
X450235Y186810D01*
G37*
G36*
G01X459427Y177617D02*
X458861Y177122D01*
X458578Y177405D01*
X459073Y177971D01*
X459215Y178112D01*
X459568Y177759D01*
X459427Y177617D01*
G37*
G36*
G01X461265Y175779D02*
X460700Y175284D01*
X460417Y175567D01*
X460912Y176132D01*
X461053Y176274D01*
X461407Y175920D01*
X461265Y175779D01*
G37*
G36*
G01X463104Y173940D02*
X462538Y173445D01*
X462255Y173728D01*
X462750Y174294D01*
X462892Y174435D01*
X463245Y174082D01*
X463104Y173940D01*
G37*
G36*
G01X449798Y194252D02*
X450548Y194202D01*
Y193802D01*
X449798Y193752D01*
X449598D01*
Y194252D01*
X449798D01*
G37*
G36*
G01Y191652D02*
X450548Y191602D01*
Y191202D01*
X449798Y191152D01*
X449598D01*
Y191652D01*
X449798D01*
G37*
G36*
G01Y189052D02*
X450548Y189002D01*
Y188602D01*
X449798Y188552D01*
X449598D01*
Y189052D01*
X449798D01*
G37*
G36*
G01X449398Y192452D02*
X448648Y192502D01*
Y192902D01*
X449398Y192952D01*
X449598D01*
Y192452D01*
X449398D01*
G37*
G36*
G01Y189852D02*
X448648Y189902D01*
Y190302D01*
X449398Y190352D01*
X449598D01*
Y189852D01*
X449398D01*
G37*
G36*
G01X454760Y182850D02*
X455326Y183345D01*
X455609Y183062D01*
X455114Y182496D01*
X454972Y182355D01*
X454619Y182708D01*
X454760Y182850D01*
G37*
G36*
G01X452922Y184688D02*
X453487Y185183D01*
X453770Y184900D01*
X453275Y184335D01*
X453134Y184193D01*
X452780Y184547D01*
X452922Y184688D01*
G37*
G36*
G01X451083Y186527D02*
X451649Y187022D01*
X451932Y186739D01*
X451437Y186173D01*
X451295Y186032D01*
X450942Y186385D01*
X451083Y186527D01*
G37*
G36*
G01X458437Y179173D02*
X459003Y179668D01*
X459285Y179385D01*
X458791Y178819D01*
X458649Y178678D01*
X458296Y179031D01*
X458437Y179173D01*
G37*
G36*
G01X460275Y177334D02*
X460841Y177829D01*
X461124Y177547D01*
X460629Y176981D01*
X460488Y176839D01*
X460134Y177193D01*
X460275Y177334D01*
G37*
G36*
G01X456598Y181011D02*
X457164Y181506D01*
X457447Y181224D01*
X456952Y180658D01*
X456811Y180516D01*
X456457Y180870D01*
X456598Y181011D01*
G37*
G36*
G01X449813Y199306D02*
X449143Y199656D01*
Y200526D01*
X449813Y200876D01*
X449988D01*
Y199306D01*
X449813D01*
G37*
G36*
G01X474271Y193040D02*
X473706Y192545D01*
X473423Y192828D01*
X473918Y193393D01*
X474059Y193535D01*
X474413Y193181D01*
X474271Y193040D01*
G37*
G36*
G01X472216Y194823D02*
X471495Y194597D01*
X470880Y195212D01*
X471106Y195933D01*
X471230Y196057D01*
X472340Y194947D01*
X472216Y194823D01*
G37*
G36*
G01X469630Y198480D02*
X468960Y198830D01*
Y199700D01*
X469630Y200050D01*
X469805D01*
Y198480D01*
X469630D01*
G37*
G36*
G01X475120Y192757D02*
X475686Y193252D01*
X475968Y192969D01*
X475473Y192403D01*
X475332Y192262D01*
X474979Y192615D01*
X475120Y192757D01*
G37*
G36*
G01X476110Y191201D02*
X475544Y190706D01*
X475261Y190989D01*
X475756Y191555D01*
X475898Y191696D01*
X476251Y191343D01*
X476110Y191201D01*
G37*
G36*
G01X476958Y190918D02*
X477524Y191413D01*
X477807Y191131D01*
X477312Y190565D01*
X477171Y190423D01*
X476817Y190777D01*
X476958Y190918D01*
G37*
G36*
G01X477948Y189363D02*
X477383Y188868D01*
X477100Y189151D01*
X477595Y189716D01*
X477736Y189858D01*
X478090Y189504D01*
X477948Y189363D01*
G37*
G36*
G01X464004Y165764D02*
X463254Y165814D01*
Y166214D01*
X464004Y166264D01*
X464204D01*
Y165764D01*
X464004D01*
G37*
G36*
G01Y163164D02*
X463254Y163214D01*
Y163614D01*
X464004Y163664D01*
X464204D01*
Y163164D01*
X464004D01*
G37*
G36*
G01X464404Y164964D02*
X465154Y164914D01*
Y164514D01*
X464404Y164464D01*
X464204D01*
Y164964D01*
X464404D01*
G37*
G36*
G01X459921Y173303D02*
X460487Y173798D01*
X460769Y173515D01*
X460274Y172949D01*
X460133Y172808D01*
X459779Y173162D01*
X459921Y173303D01*
G37*
G36*
G01X461759Y171464D02*
X462325Y171959D01*
X462608Y171677D01*
X462113Y171111D01*
X461972Y170969D01*
X461618Y171323D01*
X461759Y171464D01*
G37*
G36*
G01X463598Y169626D02*
X464164Y170121D01*
X464446Y169838D01*
X463951Y169272D01*
X463810Y169131D01*
X463456Y169485D01*
X463598Y169626D01*
G37*
G36*
G01X464404Y167564D02*
X465154Y167514D01*
Y167114D01*
X464404Y167064D01*
X464204D01*
Y167564D01*
X464404D01*
G37*
G36*
G01X454405Y178818D02*
X454971Y179313D01*
X455254Y179031D01*
X454759Y178465D01*
X454618Y178323D01*
X454264Y178677D01*
X454405Y178818D01*
G37*
G36*
G01X452567Y180657D02*
X453133Y181152D01*
X453416Y180869D01*
X452921Y180303D01*
X452779Y180162D01*
X452426Y180515D01*
X452567Y180657D01*
G37*
G36*
G01X450729Y182495D02*
X451294Y182990D01*
X451577Y182707D01*
X451082Y182142D01*
X450941Y182000D01*
X450587Y182354D01*
X450729Y182495D01*
G37*
G36*
G01X448890Y184334D02*
X449456Y184829D01*
X449739Y184546D01*
X449244Y183980D01*
X449102Y183839D01*
X448749Y184192D01*
X448890Y184334D01*
G37*
G36*
G01X447052Y186172D02*
X447617Y186667D01*
X447900Y186384D01*
X447405Y185819D01*
X447264Y185677D01*
X446910Y186031D01*
X447052Y186172D01*
G37*
G36*
G01X456244Y176980D02*
X456810Y177475D01*
X457092Y177192D01*
X456598Y176626D01*
X456456Y176485D01*
X456103Y176838D01*
X456244Y176980D01*
G37*
G36*
G01X458082Y175141D02*
X458648Y175636D01*
X458931Y175354D01*
X458436Y174788D01*
X458295Y174646D01*
X457941Y175000D01*
X458082Y175141D01*
G37*
G36*
G01X453557Y179101D02*
X452991Y178606D01*
X452708Y178889D01*
X453203Y179455D01*
X453345Y179596D01*
X453698Y179243D01*
X453557Y179101D01*
G37*
G36*
G01X451718Y180940D02*
X451153Y180445D01*
X450870Y180728D01*
X451365Y181293D01*
X451506Y181435D01*
X451860Y181081D01*
X451718Y180940D01*
G37*
G36*
G01X449880Y182778D02*
X449314Y182283D01*
X449031Y182566D01*
X449526Y183132D01*
X449668Y183273D01*
X450021Y182920D01*
X449880Y182778D01*
G37*
G36*
G01X448042Y184617D02*
X447476Y184122D01*
X447193Y184405D01*
X447688Y184970D01*
X447829Y185112D01*
X448183Y184758D01*
X448042Y184617D01*
G37*
G36*
G01X455395Y177263D02*
X454830Y176768D01*
X454547Y177051D01*
X455042Y177616D01*
X455183Y177758D01*
X455537Y177404D01*
X455395Y177263D01*
G37*
G36*
G01X457234Y175424D02*
X456668Y174929D01*
X456385Y175212D01*
X456880Y175778D01*
X457022Y175919D01*
X457375Y175566D01*
X457234Y175424D01*
G37*
G36*
G01X459072Y173586D02*
X458507Y173091D01*
X458224Y173374D01*
X458719Y173939D01*
X458860Y174081D01*
X459214Y173727D01*
X459072Y173586D01*
G37*
G36*
G01X446698Y194252D02*
X447448Y194202D01*
Y193802D01*
X446698Y193752D01*
X446498D01*
Y194252D01*
X446698D01*
G37*
G36*
G01Y191652D02*
X447448Y191602D01*
Y191202D01*
X446698Y191152D01*
X446498D01*
Y191652D01*
X446698D01*
G37*
G36*
G01Y189052D02*
X447448Y189002D01*
Y188602D01*
X446698Y188552D01*
X446498D01*
Y189052D01*
X446698D01*
G37*
G36*
G01X446298Y192452D02*
X445548Y192502D01*
Y192902D01*
X446298Y192952D01*
X446498D01*
Y192452D01*
X446298D01*
G37*
G36*
G01Y189852D02*
X445548Y189902D01*
Y190302D01*
X446298Y190352D01*
X446498D01*
Y189852D01*
X446298D01*
G37*
G36*
G01Y187252D02*
X445548Y187302D01*
Y187702D01*
X446298Y187752D01*
X446498D01*
Y187252D01*
X446298D01*
G37*
G36*
G01X446717Y198264D02*
X446047Y198614D01*
Y199484D01*
X446717Y199834D01*
X446892D01*
Y198264D01*
X446717D01*
G37*
G36*
G01X469347Y194140D02*
X468626Y193914D01*
X468011Y194529D01*
X468237Y195250D01*
X468361Y195374D01*
X469471Y194264D01*
X469347Y194140D01*
G37*
G36*
G01X472926Y190564D02*
X473492Y191059D01*
X473775Y190777D01*
X473280Y190211D01*
X473139Y190069D01*
X472785Y190423D01*
X472926Y190564D01*
G37*
G36*
G01X471088Y192403D02*
X471654Y192898D01*
X471936Y192615D01*
X471442Y192049D01*
X471300Y191908D01*
X470947Y192261D01*
X471088Y192403D01*
G37*
G36*
G01X473917Y189009D02*
X473352Y188514D01*
X473069Y188797D01*
X473564Y189362D01*
X473705Y189504D01*
X474059Y189150D01*
X473917Y189009D01*
G37*
G36*
G01X472079Y190847D02*
X471513Y190352D01*
X471230Y190635D01*
X471725Y191201D01*
X471867Y191342D01*
X472220Y190989D01*
X472079Y190847D01*
G37*
G36*
G01X474765Y188726D02*
X475331Y189221D01*
X475613Y188938D01*
X475118Y188372D01*
X474977Y188231D01*
X474623Y188585D01*
X474765Y188726D01*
G37*
G36*
G01X475756Y187170D02*
X475190Y186675D01*
X474907Y186958D01*
X475402Y187524D01*
X475544Y187665D01*
X475897Y187312D01*
X475756Y187170D01*
G37*
G36*
G01X476603Y186887D02*
X477169Y187382D01*
X477452Y187100D01*
X476957Y186534D01*
X476816Y186392D01*
X476462Y186746D01*
X476603Y186887D01*
G37*
G36*
G01X477594Y185332D02*
X477029Y184837D01*
X476746Y185120D01*
X477241Y185685D01*
X477382Y185827D01*
X477736Y185473D01*
X477594Y185332D01*
G37*
G36*
G01X466887Y172915D02*
X467453Y173410D01*
X467736Y173128D01*
X467241Y172562D01*
X467099Y172421D01*
X466746Y172774D01*
X466887Y172915D01*
G37*
G36*
G01X466039Y173198D02*
X465473Y172703D01*
X465190Y172986D01*
X465685Y173552D01*
X465827Y173693D01*
X466180Y173340D01*
X466039Y173198D01*
G37*
G36*
G01X467877Y171360D02*
X467312Y170865D01*
X467029Y171148D01*
X467524Y171713D01*
X467665Y171855D01*
X468019Y171501D01*
X467877Y171360D01*
G37*
G36*
G01X470254Y164964D02*
X471004Y164914D01*
Y164514D01*
X470254Y164464D01*
X470054D01*
Y164964D01*
X470254D01*
G37*
G36*
G01X469854Y165764D02*
X469104Y165814D01*
Y166214D01*
X469854Y166264D01*
X470054D01*
Y165764D01*
X469854D01*
G37*
G36*
G01X468726Y171077D02*
X469292Y171572D01*
X469574Y171289D01*
X469079Y170723D01*
X468938Y170582D01*
X468584Y170936D01*
X468726Y171077D01*
G37*
G36*
G01X470254Y167564D02*
X471004Y167514D01*
Y167114D01*
X470254Y167064D01*
X470054D01*
Y167564D01*
X470254D01*
G37*
G36*
G01X469854Y168364D02*
X469104Y168414D01*
Y168814D01*
X469854Y168864D01*
X470054D01*
Y168364D01*
X469854D01*
G37*
G36*
G01X450948Y192452D02*
X450198Y192502D01*
Y192902D01*
X450948Y192952D01*
X451148D01*
Y192452D01*
X450948D01*
G37*
G36*
G01Y189852D02*
X450198Y189902D01*
Y190302D01*
X450948Y190352D01*
X451148D01*
Y189852D01*
X450948D01*
G37*
G36*
G01X459533Y180269D02*
X460099Y180764D01*
X460382Y180482D01*
X459887Y179916D01*
X459746Y179774D01*
X459392Y180128D01*
X459533Y180269D01*
G37*
G36*
G01X457695Y182108D02*
X458261Y182603D01*
X458544Y182320D01*
X458049Y181754D01*
X457907Y181613D01*
X457554Y181966D01*
X457695Y182108D01*
G37*
G36*
G01X455856Y183946D02*
X456422Y184441D01*
X456705Y184158D01*
X456210Y183593D01*
X456069Y183451D01*
X455715Y183805D01*
X455856Y183946D01*
G37*
G36*
G01X454018Y185785D02*
X454584Y186280D01*
X454867Y185997D01*
X454372Y185431D01*
X454230Y185290D01*
X453877Y185643D01*
X454018Y185785D01*
G37*
G36*
G01X452180Y187623D02*
X452745Y188118D01*
X453028Y187835D01*
X452533Y187270D01*
X452392Y187128D01*
X452038Y187482D01*
X452180Y187623D01*
G37*
G36*
G01X461372Y178431D02*
X461938Y178926D01*
X462220Y178643D01*
X461725Y178077D01*
X461584Y177936D01*
X461231Y178289D01*
X461372Y178431D01*
G37*
G36*
G01X463210Y176592D02*
X463776Y177087D01*
X464059Y176805D01*
X463564Y176239D01*
X463423Y176097D01*
X463069Y176451D01*
X463210Y176592D01*
G37*
G36*
G01X465049Y174754D02*
X465615Y175249D01*
X465897Y174966D01*
X465402Y174400D01*
X465261Y174259D01*
X464907Y174613D01*
X465049Y174754D01*
G37*
G36*
G01X458685Y180552D02*
X458119Y180057D01*
X457836Y180340D01*
X458331Y180906D01*
X458473Y181047D01*
X458826Y180694D01*
X458685Y180552D01*
G37*
G36*
G01X456846Y182391D02*
X456281Y181896D01*
X455998Y182179D01*
X456493Y182744D01*
X456634Y182886D01*
X456988Y182532D01*
X456846Y182391D01*
G37*
G36*
G01X455008Y184229D02*
X454442Y183734D01*
X454159Y184017D01*
X454654Y184583D01*
X454796Y184724D01*
X455149Y184371D01*
X455008Y184229D01*
G37*
G36*
G01X453169Y186068D02*
X452604Y185573D01*
X452321Y185856D01*
X452816Y186421D01*
X452957Y186563D01*
X453311Y186209D01*
X453169Y186068D01*
G37*
G36*
G01X460523Y178714D02*
X459958Y178219D01*
X459675Y178502D01*
X460170Y179067D01*
X460311Y179209D01*
X460665Y178855D01*
X460523Y178714D01*
G37*
G36*
G01X462362Y176875D02*
X461796Y176380D01*
X461513Y176663D01*
X462008Y177229D01*
X462150Y177370D01*
X462503Y177017D01*
X462362Y176875D01*
G37*
G36*
G01X464200Y175037D02*
X463635Y174542D01*
X463352Y174825D01*
X463847Y175390D01*
X463988Y175532D01*
X464342Y175178D01*
X464200Y175037D01*
G37*
G36*
G01X451348Y194252D02*
X452098Y194202D01*
Y193802D01*
X451348Y193752D01*
X451148D01*
Y194252D01*
X451348D01*
G37*
G36*
G01Y191652D02*
X452098Y191602D01*
Y191202D01*
X451348Y191152D01*
X451148D01*
Y191652D01*
X451348D01*
G37*
G36*
G01X450913Y200930D02*
X451583Y200580D01*
Y199710D01*
X450913Y199360D01*
X450738D01*
Y200930D01*
X450913D01*
G37*
G36*
G01X470730Y200104D02*
X471400Y199754D01*
Y198884D01*
X470730Y198534D01*
X470555D01*
Y200104D01*
X470730D01*
G37*
G36*
G01X476216Y193853D02*
X476782Y194348D01*
X477065Y194066D01*
X476570Y193500D01*
X476429Y193358D01*
X476075Y193712D01*
X476216Y193853D01*
G37*
G36*
G01X475368Y194136D02*
X474802Y193641D01*
X474519Y193924D01*
X475014Y194490D01*
X475156Y194631D01*
X475509Y194278D01*
X475368Y194136D01*
G37*
G36*
G01X471312Y203273D02*
X471982Y202923D01*
Y202053D01*
X471312Y201703D01*
X471137D01*
Y203273D01*
X471312D01*
G37*
G36*
G01X471284Y207188D02*
X471954Y206838D01*
Y205968D01*
X471284Y205618D01*
X471110D01*
X471109Y207189D01*
X471284Y207188D01*
G37*
G36*
G01X477206Y192298D02*
X476641Y191803D01*
X476358Y192086D01*
X476853Y192651D01*
X476994Y192793D01*
X477348Y192439D01*
X477206Y192298D01*
G37*
G36*
G01X450602Y273500D02*
Y274802D01*
X447598D01*
Y274302D01*
X447102D01*
Y274802D01*
X444098D01*
Y274000D01*
X443502D01*
Y274002D01*
X441698D01*
Y274000D01*
X440502D01*
Y274002D01*
X438498D01*
Y274000D01*
X437002D01*
Y274002D01*
X434998D01*
Y274000D01*
X433002D01*
Y274002D01*
X430998D01*
Y274000D01*
X429002D01*
Y274002D01*
X427000D01*
Y276000D01*
X430800D01*
X430900Y275900D01*
X431200Y276200D01*
X444900D01*
X445992Y277292D01*
Y283641D01*
X446492Y284141D01*
X446796D01*
Y284090D01*
X449800D01*
Y284141D01*
X451796D01*
Y284090D01*
X454800D01*
Y284092D01*
X456048Y285341D01*
X456800D01*
Y291387D01*
X456803Y291405D01*
G03X456828Y291661I-1577J283D01*
G01X456829Y291742D01*
X457073Y291986D01*
X458556D01*
X458900Y291642D01*
Y291302D01*
X458898D01*
Y289498D01*
X458900D01*
Y288502D01*
X458898D01*
Y286498D01*
X458900D01*
Y285502D01*
X458898D01*
Y283598D01*
X458641Y283341D01*
X456348D01*
X455850Y282842D01*
X455746D01*
Y282740D01*
X455648Y282641D01*
Y276341D01*
X452807Y273500D01*
X450602D01*
G37*
G36*
G01X448064Y302804D02*
Y302906D01*
X445094D01*
Y311215D01*
X444692Y311616D01*
Y315148D01*
X447694D01*
Y315341D01*
X449690D01*
Y315148D01*
X452650D01*
X455090Y312708D01*
Y304746D01*
X453166Y302822D01*
X452964Y302906D01*
X449962D01*
Y302804D01*
X448064D01*
G37*
G36*
G01X467648Y307841D02*
X465647Y309842D01*
Y315127D01*
X463518Y317256D01*
G02X463773Y317938I283J283D01*
G03X462311Y318879I-102J1448D01*
G02X461936Y318339I-375J-140D01*
G01X459650D01*
Y318592D01*
X456394D01*
X456148Y318839D01*
Y321839D01*
X456648Y322339D01*
X468115D01*
G02X468503Y321843I0J-400D01*
G03X470910Y320440I1410J-347D01*
G01X470967Y320494D01*
X471175D01*
X471232Y320444D01*
G03X473515Y321126I930J1047D01*
G02X474184Y321305I386J-104D01*
G01X474506Y320983D01*
G02X474524Y320437I-283J-283D01*
G03X475025Y318298I1018J-890D01*
G01X475148Y318247D01*
Y316947D01*
X475025Y316896D01*
G03X476010Y314378I517J-1249D01*
G02X476548Y314003I138J-375D01*
G01Y312589D01*
G03Y310905I1244J-842D01*
G01Y309241D01*
X476290Y308983D01*
X476160Y309049D01*
G03X474201Y308016I-618J-1202D01*
G01X474179Y307841D01*
X467648D01*
G37*
G36*
G01X439267Y400687D02*
X438599Y401038D01*
X438601Y401908D01*
X439272Y402256D01*
X439447D01*
X439443Y400686D01*
X439267Y400687D01*
G37*
G36*
G01X440865Y404206D02*
X441535Y403856D01*
Y402986D01*
X440865Y402636D01*
X440690D01*
Y404206D01*
X440865D01*
G37*
G36*
G01X427623Y395005D02*
X426985Y394600D01*
X426232Y395034D01*
X426264Y395789D01*
X426351Y395942D01*
X427710Y395156D01*
X427623Y395005D01*
G37*
G36*
G01X427345Y404158D02*
X428015Y403808D01*
Y402938D01*
X427345Y402588D01*
X427170D01*
Y404158D01*
X427345D01*
G37*
G36*
G01X436612Y398713D02*
X435942Y399063D01*
Y399933D01*
X436612Y400283D01*
X436787D01*
Y398713D01*
X436612D01*
G37*
G36*
G01X437485Y402257D02*
X438155Y401907D01*
Y401037D01*
X437485Y400687D01*
X437310D01*
Y402257D01*
X437485D01*
G37*
G36*
G01X434104Y404208D02*
X434774Y403858D01*
Y402988D01*
X434104Y402638D01*
X433929D01*
Y404208D01*
X434104D01*
G37*
G36*
G01X434105Y400281D02*
X434775Y399931D01*
Y399061D01*
X434105Y398711D01*
X433930D01*
Y400281D01*
X434105D01*
G37*
G36*
G01X432481Y400637D02*
X431811Y400987D01*
Y401857D01*
X432481Y402207D01*
X432656D01*
Y400637D01*
X432481D01*
G37*
G36*
G01X432431Y396815D02*
X431794Y397222D01*
X431870Y398088D01*
X432568Y398378D01*
X432742Y398363D01*
X432606Y396800D01*
X432431Y396815D01*
G37*
G36*
G01X459521Y400709D02*
X458851Y401059D01*
Y401929D01*
X459521Y402279D01*
X459696D01*
Y400709D01*
X459521D01*
G37*
G36*
G01X446754Y396781D02*
X446083Y397131D01*
Y398000D01*
X446752Y398351D01*
X446926D01*
X446929Y396781D01*
X446754D01*
G37*
G36*
G01X450492Y395617D02*
X450077Y394986D01*
X449212Y395073D01*
X448931Y395774D01*
X448948Y395948D01*
X450510Y395792D01*
X450492Y395617D01*
G37*
G36*
G01X447627Y404197D02*
X448297Y403847D01*
Y402977D01*
X447627Y402627D01*
X447452D01*
Y404197D01*
X447627D01*
G37*
G36*
G01X447723Y399921D02*
X448478Y399887D01*
X448846Y399099D01*
X448386Y398499D01*
X448228Y398425D01*
X447564Y399847D01*
X447723Y399921D01*
G37*
G36*
G01X457765Y402257D02*
X458435Y401907D01*
Y401037D01*
X457765Y400687D01*
X457590D01*
Y402257D01*
X457765D01*
G37*
G36*
G01X456892Y398713D02*
X456222Y399063D01*
Y399933D01*
X456892Y400283D01*
X457067D01*
Y398713D01*
X456892D01*
G37*
G36*
G01X468568Y395649D02*
X467930Y395244D01*
X467177Y395679D01*
X467209Y396434D01*
X467296Y396585D01*
X468656Y395801D01*
X468568Y395649D01*
G37*
G36*
G01X478044Y402207D02*
X478714Y401857D01*
Y400987D01*
X478044Y400637D01*
X477869D01*
Y402207D01*
X478044D01*
G37*
G36*
G01X477171Y398731D02*
X476501Y399081D01*
Y399951D01*
X477171Y400301D01*
X477346D01*
Y398731D01*
X477171D01*
G37*
G36*
G01X454385Y404206D02*
X455055Y403856D01*
Y402986D01*
X454385Y402636D01*
X454210D01*
Y404206D01*
X454385D01*
G37*
G36*
G01Y400281D02*
X455055Y399931D01*
Y399061D01*
X454385Y398711D01*
X454210D01*
Y400281D01*
X454385D01*
G37*
G36*
G01X474663Y404217D02*
X475333Y403867D01*
Y402997D01*
X474663Y402647D01*
X474488D01*
Y404217D01*
X474663D01*
G37*
G36*
G01X452761Y400637D02*
X452091Y400987D01*
Y401857D01*
X452761Y402207D01*
X452936D01*
Y400637D01*
X452761D01*
G37*
G36*
G01X473041Y396720D02*
X472371Y397070D01*
Y397940D01*
X473041Y398289D01*
X473215Y398290D01*
X473216Y396720D01*
X473041D01*
G37*
G36*
G01X426148Y417123D02*
X425388Y417473D01*
Y418373D01*
X426148Y418723D01*
X426323D01*
Y417123D01*
X426148D01*
G37*
G36*
G01Y413623D02*
X425388Y413973D01*
Y414873D01*
X426148Y415223D01*
X426323D01*
Y413623D01*
X426148D01*
G37*
G36*
G01X428528Y410182D02*
X427743Y409892D01*
X427107Y410528D01*
X427397Y411313D01*
X427520Y411437D01*
X428652Y410305D01*
X428528Y410182D01*
G37*
G36*
G01X426123Y422834D02*
X426873Y422784D01*
Y422384D01*
X426123Y422334D01*
X425923D01*
Y422834D01*
X426123D01*
G37*
G36*
G01Y425434D02*
X426873Y425384D01*
Y424984D01*
X426123Y424934D01*
X425923D01*
Y425434D01*
X426123D01*
G37*
G36*
G01Y428034D02*
X426873Y427984D01*
Y427584D01*
X426123Y427534D01*
X425923D01*
Y428034D01*
X426123D01*
G37*
G36*
G01Y430634D02*
X426873Y430584D01*
Y430184D01*
X426123Y430134D01*
X425923D01*
Y430634D01*
X426123D01*
G37*
G36*
G01Y433234D02*
X426873Y433184D01*
Y432784D01*
X426123Y432734D01*
X425923D01*
Y433234D01*
X426123D01*
G37*
G36*
G01Y438434D02*
X426873Y438384D01*
Y437984D01*
X426123Y437934D01*
X425923D01*
Y438434D01*
X426123D01*
G37*
G36*
G01Y435834D02*
X426873Y435784D01*
Y435384D01*
X426123Y435334D01*
X425923D01*
Y435834D01*
X426123D01*
G37*
G36*
G01X425723Y421034D02*
X424973Y421084D01*
Y421484D01*
X425723Y421534D01*
X425923D01*
Y421034D01*
X425723D01*
G37*
G36*
G01Y423634D02*
X424973Y423684D01*
Y424084D01*
X425723Y424134D01*
X425923D01*
Y423634D01*
X425723D01*
G37*
G36*
G01Y426234D02*
X424973Y426284D01*
Y426684D01*
X425723Y426734D01*
X425923D01*
Y426234D01*
X425723D01*
G37*
G36*
G01Y428834D02*
X424973Y428884D01*
Y429284D01*
X425723Y429334D01*
X425923D01*
Y428834D01*
X425723D01*
G37*
G36*
G01Y431434D02*
X424973Y431484D01*
Y431884D01*
X425723Y431934D01*
X425923D01*
Y431434D01*
X425723D01*
G37*
G36*
G01Y434034D02*
X424973Y434084D01*
Y434484D01*
X425723Y434534D01*
X425923D01*
Y434034D01*
X425723D01*
G37*
G36*
G01Y439234D02*
X424973Y439284D01*
Y439684D01*
X425723Y439734D01*
X425923D01*
Y439234D01*
X425723D01*
G37*
G36*
G01Y436634D02*
X424973Y436684D01*
Y437084D01*
X425723Y437134D01*
X425923D01*
Y436634D01*
X425723D01*
G37*
G36*
G01X429674Y402895D02*
X428914Y403245D01*
Y404145D01*
X429674Y404495D01*
X429849D01*
Y402895D01*
X429674D01*
G37*
G36*
G01X428175Y412091D02*
X428960Y412381D01*
X429596Y411745D01*
X429306Y410960D01*
X429183Y410836D01*
X428051Y411968D01*
X428175Y412091D01*
G37*
G36*
G01X427248Y418723D02*
X428008Y418373D01*
Y417473D01*
X427248Y417123D01*
X427073D01*
Y418723D01*
X427248D01*
G37*
G36*
G01Y415223D02*
X428008Y414873D01*
Y413973D01*
X427248Y413623D01*
X427073D01*
Y415223D01*
X427248D01*
G37*
G36*
G01X430774Y407495D02*
X431534Y407145D01*
Y406245D01*
X430774Y405895D01*
X430599D01*
Y407495D01*
X430774D01*
G37*
G36*
G01X427673Y422834D02*
X428423Y422784D01*
Y422384D01*
X427673Y422334D01*
X427473D01*
Y422834D01*
X427673D01*
G37*
G36*
G01Y425434D02*
X428423Y425384D01*
Y424984D01*
X427673Y424934D01*
X427473D01*
Y425434D01*
X427673D01*
G37*
G36*
G01Y428034D02*
X428423Y427984D01*
Y427584D01*
X427673Y427534D01*
X427473D01*
Y428034D01*
X427673D01*
G37*
G36*
G01Y430634D02*
X428423Y430584D01*
Y430184D01*
X427673Y430134D01*
X427473D01*
Y430634D01*
X427673D01*
G37*
G36*
G01Y433234D02*
X428423Y433184D01*
Y432784D01*
X427673Y432734D01*
X427473D01*
Y433234D01*
X427673D01*
G37*
G36*
G01Y438434D02*
X428423Y438384D01*
Y437984D01*
X427673Y437934D01*
X427473D01*
Y438434D01*
X427673D01*
G37*
G36*
G01Y435834D02*
X428423Y435784D01*
Y435384D01*
X427673Y435334D01*
X427473D01*
Y435834D01*
X427673D01*
G37*
G36*
G01X427273Y421034D02*
X426523Y421084D01*
Y421484D01*
X427273Y421534D01*
X427473D01*
Y421034D01*
X427273D01*
G37*
G36*
G01Y423634D02*
X426523Y423684D01*
Y424084D01*
X427273Y424134D01*
X427473D01*
Y423634D01*
X427273D01*
G37*
G36*
G01Y426234D02*
X426523Y426284D01*
Y426684D01*
X427273Y426734D01*
X427473D01*
Y426234D01*
X427273D01*
G37*
G36*
G01Y428834D02*
X426523Y428884D01*
Y429284D01*
X427273Y429334D01*
X427473D01*
Y428834D01*
X427273D01*
G37*
G36*
G01Y431434D02*
X426523Y431484D01*
Y431884D01*
X427273Y431934D01*
X427473D01*
Y431434D01*
X427273D01*
G37*
G36*
G01Y439234D02*
X426523Y439284D01*
Y439684D01*
X427273Y439734D01*
X427473D01*
Y439234D01*
X427273D01*
G37*
G36*
G01Y436634D02*
X426523Y436684D01*
Y437084D01*
X427273Y437134D01*
X427473D01*
Y436634D01*
X427273D01*
G37*
G36*
G01Y434034D02*
X426523Y434084D01*
Y434484D01*
X427273Y434534D01*
X427473D01*
Y434034D01*
X427273D01*
G37*
G36*
G01X440465Y416011D02*
X439681Y415721D01*
X439044Y416358D01*
X439334Y417142D01*
X439458Y417266D01*
X440589Y416135D01*
X440465Y416011D01*
G37*
G36*
G01X441149Y411584D02*
X440389Y411934D01*
Y412834D01*
X441149Y413184D01*
X441324D01*
Y411584D01*
X441149D01*
G37*
G36*
G01X440274Y407881D02*
X439791Y408565D01*
X440241Y409344D01*
X441074Y409267D01*
X441226Y409179D01*
X440425Y407794D01*
X440274Y407881D01*
G37*
G36*
G01X438523Y422834D02*
X439273Y422784D01*
Y422384D01*
X438523Y422334D01*
X438323D01*
Y422834D01*
X438523D01*
G37*
G36*
G01Y425434D02*
X439273Y425384D01*
Y424984D01*
X438523Y424934D01*
X438323D01*
Y425434D01*
X438523D01*
G37*
G36*
G01Y428034D02*
X439273Y427984D01*
Y427584D01*
X438523Y427534D01*
X438323D01*
Y428034D01*
X438523D01*
G37*
G36*
G01Y430634D02*
X439273Y430584D01*
Y430184D01*
X438523Y430134D01*
X438323D01*
Y430634D01*
X438523D01*
G37*
G36*
G01Y433234D02*
X439273Y433184D01*
Y432784D01*
X438523Y432734D01*
X438323D01*
Y433234D01*
X438523D01*
G37*
G36*
G01Y438434D02*
X439273Y438384D01*
Y437984D01*
X438523Y437934D01*
X438323D01*
Y438434D01*
X438523D01*
G37*
G36*
G01Y435834D02*
X439273Y435784D01*
Y435384D01*
X438523Y435334D01*
X438323D01*
Y435834D01*
X438523D01*
G37*
G36*
G01X438123Y421034D02*
X437373Y421084D01*
Y421484D01*
X438123Y421534D01*
X438323D01*
Y421034D01*
X438123D01*
G37*
G36*
G01Y423634D02*
X437373Y423684D01*
Y424084D01*
X438123Y424134D01*
X438323D01*
Y423634D01*
X438123D01*
G37*
G36*
G01Y426234D02*
X437373Y426284D01*
Y426684D01*
X438123Y426734D01*
X438323D01*
Y426234D01*
X438123D01*
G37*
G36*
G01Y428834D02*
X437373Y428884D01*
Y429284D01*
X438123Y429334D01*
X438323D01*
Y428834D01*
X438123D01*
G37*
G36*
G01Y431434D02*
X437373Y431484D01*
Y431884D01*
X438123Y431934D01*
X438323D01*
Y431434D01*
X438123D01*
G37*
G36*
G01Y439234D02*
X437373Y439284D01*
Y439684D01*
X438123Y439734D01*
X438323D01*
Y439234D01*
X438123D01*
G37*
G36*
G01Y436634D02*
X437373Y436684D01*
Y437084D01*
X438123Y437134D01*
X438323D01*
Y436634D01*
X438123D01*
G37*
G36*
G01Y434034D02*
X437373Y434084D01*
Y434484D01*
X438123Y434534D01*
X438323D01*
Y434034D01*
X438123D01*
G37*
G36*
G01X440166Y417974D02*
X440950Y418264D01*
X441587Y417627D01*
X441297Y416843D01*
X441173Y416719D01*
X440042Y417850D01*
X440166Y417974D01*
G37*
G36*
G01X442249Y413184D02*
X443009Y412834D01*
Y411934D01*
X442249Y411584D01*
X442074D01*
Y413184D01*
X442249D01*
G37*
G36*
G01X442026Y408717D02*
X442508Y408034D01*
X442058Y407254D01*
X441225Y407332D01*
X441073Y407419D01*
X441874Y408805D01*
X442026Y408717D01*
G37*
G36*
G01X439673Y421034D02*
X438923Y421084D01*
Y421484D01*
X439673Y421534D01*
X439873D01*
Y421034D01*
X439673D01*
G37*
G36*
G01Y423634D02*
X438923Y423684D01*
Y424084D01*
X439673Y424134D01*
X439873D01*
Y423634D01*
X439673D01*
G37*
G36*
G01Y426234D02*
X438923Y426284D01*
Y426684D01*
X439673Y426734D01*
X439873D01*
Y426234D01*
X439673D01*
G37*
G36*
G01Y428834D02*
X438923Y428884D01*
Y429284D01*
X439673Y429334D01*
X439873D01*
Y428834D01*
X439673D01*
G37*
G36*
G01Y431434D02*
X438923Y431484D01*
Y431884D01*
X439673Y431934D01*
X439873D01*
Y431434D01*
X439673D01*
G37*
G36*
G01Y436634D02*
X438923Y436684D01*
Y437084D01*
X439673Y437134D01*
X439873D01*
Y436634D01*
X439673D01*
G37*
G36*
G01Y434034D02*
X438923Y434084D01*
Y434484D01*
X439673Y434534D01*
X439873D01*
Y434034D01*
X439673D01*
G37*
G36*
G01X440073Y422834D02*
X440823Y422784D01*
Y422384D01*
X440073Y422334D01*
X439873D01*
Y422834D01*
X440073D01*
G37*
G36*
G01Y425434D02*
X440823Y425384D01*
Y424984D01*
X440073Y424934D01*
X439873D01*
Y425434D01*
X440073D01*
G37*
G36*
G01Y428034D02*
X440823Y427984D01*
Y427584D01*
X440073Y427534D01*
X439873D01*
Y428034D01*
X440073D01*
G37*
G36*
G01Y430634D02*
X440823Y430584D01*
Y430184D01*
X440073Y430134D01*
X439873D01*
Y430634D01*
X440073D01*
G37*
G36*
G01Y433234D02*
X440823Y433184D01*
Y432784D01*
X440073Y432734D01*
X439873D01*
Y433234D01*
X440073D01*
G37*
G36*
G01Y438434D02*
X440823Y438384D01*
Y437984D01*
X440073Y437934D01*
X439873D01*
Y438434D01*
X440073D01*
G37*
G36*
G01Y435834D02*
X440823Y435784D01*
Y435384D01*
X440073Y435334D01*
X439873D01*
Y435834D01*
X440073D01*
G37*
G36*
G01X439673Y439234D02*
X438923Y439284D01*
Y439684D01*
X439673Y439734D01*
X439873D01*
Y439234D01*
X439673D01*
G37*
G36*
G01X423048Y410296D02*
X422288Y410646D01*
Y411546D01*
X423048Y411896D01*
X423223D01*
Y410296D01*
X423048D01*
G37*
G36*
G01Y414196D02*
X422288Y414546D01*
Y415446D01*
X423048Y415796D01*
X423223D01*
Y414196D01*
X423048D01*
G37*
G36*
G01X424534Y405635D02*
X423749Y405345D01*
X423113Y405981D01*
X423403Y406766D01*
X423526Y406890D01*
X424658Y405758D01*
X424534Y405635D01*
G37*
G36*
G01X423023Y422834D02*
X423773Y422784D01*
Y422384D01*
X423023Y422334D01*
X422823D01*
Y422834D01*
X423023D01*
G37*
G36*
G01Y425434D02*
X423773Y425384D01*
Y424984D01*
X423023Y424934D01*
X422823D01*
Y425434D01*
X423023D01*
G37*
G36*
G01Y428034D02*
X423773Y427984D01*
Y427584D01*
X423023Y427534D01*
X422823D01*
Y428034D01*
X423023D01*
G37*
G36*
G01Y430634D02*
X423773Y430584D01*
Y430184D01*
X423023Y430134D01*
X422823D01*
Y430634D01*
X423023D01*
G37*
G36*
G01Y433234D02*
X423773Y433184D01*
Y432784D01*
X423023Y432734D01*
X422823D01*
Y433234D01*
X423023D01*
G37*
G36*
G01Y438434D02*
X423773Y438384D01*
Y437984D01*
X423023Y437934D01*
X422823D01*
Y438434D01*
X423023D01*
G37*
G36*
G01Y435834D02*
X423773Y435784D01*
Y435384D01*
X423023Y435334D01*
X422823D01*
Y435834D01*
X423023D01*
G37*
G36*
G01X422623Y421034D02*
X421873Y421084D01*
Y421484D01*
X422623Y421534D01*
X422823D01*
Y421034D01*
X422623D01*
G37*
G36*
G01Y423634D02*
X421873Y423684D01*
Y424084D01*
X422623Y424134D01*
X422823D01*
Y423634D01*
X422623D01*
G37*
G36*
G01Y426234D02*
X421873Y426284D01*
Y426684D01*
X422623Y426734D01*
X422823D01*
Y426234D01*
X422623D01*
G37*
G36*
G01Y428834D02*
X421873Y428884D01*
Y429284D01*
X422623Y429334D01*
X422823D01*
Y428834D01*
X422623D01*
G37*
G36*
G01Y431434D02*
X421873Y431484D01*
Y431884D01*
X422623Y431934D01*
X422823D01*
Y431434D01*
X422623D01*
G37*
G36*
G01Y434034D02*
X421873Y434084D01*
Y434484D01*
X422623Y434534D01*
X422823D01*
Y434034D01*
X422623D01*
G37*
G36*
G01Y439234D02*
X421873Y439284D01*
Y439684D01*
X422623Y439734D01*
X422823D01*
Y439234D01*
X422623D01*
G37*
G36*
G01Y436634D02*
X421873Y436684D01*
Y437084D01*
X422623Y437134D01*
X422823D01*
Y436634D01*
X422623D01*
G37*
G36*
G01X424148Y411896D02*
X424908Y411546D01*
Y410646D01*
X424148Y410296D01*
X423973D01*
Y411896D01*
X424148D01*
G37*
G36*
G01Y415796D02*
X424908Y415446D01*
Y414546D01*
X424148Y414196D01*
X423973D01*
Y415796D01*
X424148D01*
G37*
G36*
G01X424192Y407555D02*
X424977Y407845D01*
X425613Y407209D01*
X425323Y406424D01*
X425200Y406300D01*
X424068Y407432D01*
X424192Y407555D01*
G37*
G36*
G01X424173Y426234D02*
X423423Y426284D01*
Y426684D01*
X424173Y426734D01*
X424373D01*
Y426234D01*
X424173D01*
G37*
G36*
G01Y428834D02*
X423423Y428884D01*
Y429284D01*
X424173Y429334D01*
X424373D01*
Y428834D01*
X424173D01*
G37*
G36*
G01Y434034D02*
X423423Y434084D01*
Y434484D01*
X424173Y434534D01*
X424373D01*
Y434034D01*
X424173D01*
G37*
G36*
G01Y431434D02*
X423423Y431484D01*
Y431884D01*
X424173Y431934D01*
X424373D01*
Y431434D01*
X424173D01*
G37*
G36*
G01Y421034D02*
X423423Y421084D01*
Y421484D01*
X424173Y421534D01*
X424373D01*
Y421034D01*
X424173D01*
G37*
G36*
G01X424573Y438434D02*
X425323Y438384D01*
Y437984D01*
X424573Y437934D01*
X424373D01*
Y438434D01*
X424573D01*
G37*
G36*
G01Y435834D02*
X425323Y435784D01*
Y435384D01*
X424573Y435334D01*
X424373D01*
Y435834D01*
X424573D01*
G37*
G36*
G01Y433234D02*
X425323Y433184D01*
Y432784D01*
X424573Y432734D01*
X424373D01*
Y433234D01*
X424573D01*
G37*
G36*
G01Y422834D02*
X425323Y422784D01*
Y422384D01*
X424573Y422334D01*
X424373D01*
Y422834D01*
X424573D01*
G37*
G36*
G01Y425434D02*
X425323Y425384D01*
Y424984D01*
X424573Y424934D01*
X424373D01*
Y425434D01*
X424573D01*
G37*
G36*
G01Y428034D02*
X425323Y427984D01*
Y427584D01*
X424573Y427534D01*
X424373D01*
Y428034D01*
X424573D01*
G37*
G36*
G01Y430634D02*
X425323Y430584D01*
Y430184D01*
X424573Y430134D01*
X424373D01*
Y430634D01*
X424573D01*
G37*
G36*
G01X424173Y439234D02*
X423423Y439284D01*
Y439684D01*
X424173Y439734D01*
X424373D01*
Y439234D01*
X424173D01*
G37*
G36*
G01Y436634D02*
X423423Y436684D01*
Y437084D01*
X424173Y437134D01*
X424373D01*
Y436634D01*
X424173D01*
G37*
G36*
G01Y423634D02*
X423423Y423684D01*
Y424084D01*
X424173Y424134D01*
X424373D01*
Y423634D01*
X424173D01*
G37*
G36*
G01X438028Y410246D02*
X437268Y410596D01*
Y411496D01*
X438028Y411846D01*
X438203D01*
Y410246D01*
X438028D01*
G37*
G36*
G01X435423Y422834D02*
X436173Y422784D01*
Y422384D01*
X435423Y422334D01*
X435223D01*
Y422834D01*
X435423D01*
G37*
G36*
G01Y425434D02*
X436173Y425384D01*
Y424984D01*
X435423Y424934D01*
X435223D01*
Y425434D01*
X435423D01*
G37*
G36*
G01Y428034D02*
X436173Y427984D01*
Y427584D01*
X435423Y427534D01*
X435223D01*
Y428034D01*
X435423D01*
G37*
G36*
G01Y430634D02*
X436173Y430584D01*
Y430184D01*
X435423Y430134D01*
X435223D01*
Y430634D01*
X435423D01*
G37*
G36*
G01Y433234D02*
X436173Y433184D01*
Y432784D01*
X435423Y432734D01*
X435223D01*
Y433234D01*
X435423D01*
G37*
G36*
G01Y438434D02*
X436173Y438384D01*
Y437984D01*
X435423Y437934D01*
X435223D01*
Y438434D01*
X435423D01*
G37*
G36*
G01Y435834D02*
X436173Y435784D01*
Y435384D01*
X435423Y435334D01*
X435223D01*
Y435834D01*
X435423D01*
G37*
G36*
G01X435023Y421034D02*
X434273Y421084D01*
Y421484D01*
X435023Y421534D01*
X435223D01*
Y421034D01*
X435023D01*
G37*
G36*
G01Y423634D02*
X434273Y423684D01*
Y424084D01*
X435023Y424134D01*
X435223D01*
Y423634D01*
X435023D01*
G37*
G36*
G01Y426234D02*
X434273Y426284D01*
Y426684D01*
X435023Y426734D01*
X435223D01*
Y426234D01*
X435023D01*
G37*
G36*
G01Y428834D02*
X434273Y428884D01*
Y429284D01*
X435023Y429334D01*
X435223D01*
Y428834D01*
X435023D01*
G37*
G36*
G01Y431434D02*
X434273Y431484D01*
Y431884D01*
X435023Y431934D01*
X435223D01*
Y431434D01*
X435023D01*
G37*
G36*
G01Y439234D02*
X434273Y439284D01*
Y439684D01*
X435023Y439734D01*
X435223D01*
Y439234D01*
X435023D01*
G37*
G36*
G01Y436634D02*
X434273Y436684D01*
Y437084D01*
X435023Y437134D01*
X435223D01*
Y436634D01*
X435023D01*
G37*
G36*
G01Y434034D02*
X434273Y434084D01*
Y434484D01*
X435023Y434534D01*
X435223D01*
Y434034D01*
X435023D01*
G37*
G36*
G01X437221Y416618D02*
X438006Y416908D01*
X438642Y416272D01*
X438352Y415487D01*
X438229Y415363D01*
X437097Y416495D01*
X437221Y416618D01*
G37*
G36*
G01X438528Y408346D02*
X439288Y407996D01*
Y407096D01*
X438528Y406746D01*
X438353D01*
Y408346D01*
X438528D01*
G37*
G36*
G01X439128Y411846D02*
X439888Y411496D01*
Y410596D01*
X439128Y410246D01*
X438953D01*
Y411846D01*
X439128D01*
G37*
G36*
G01X436973Y422834D02*
X437723Y422784D01*
Y422384D01*
X436973Y422334D01*
X436773D01*
Y422834D01*
X436973D01*
G37*
G36*
G01Y425434D02*
X437723Y425384D01*
Y424984D01*
X436973Y424934D01*
X436773D01*
Y425434D01*
X436973D01*
G37*
G36*
G01Y428034D02*
X437723Y427984D01*
Y427584D01*
X436973Y427534D01*
X436773D01*
Y428034D01*
X436973D01*
G37*
G36*
G01Y430634D02*
X437723Y430584D01*
Y430184D01*
X436973Y430134D01*
X436773D01*
Y430634D01*
X436973D01*
G37*
G36*
G01Y433234D02*
X437723Y433184D01*
Y432784D01*
X436973Y432734D01*
X436773D01*
Y433234D01*
X436973D01*
G37*
G36*
G01Y438434D02*
X437723Y438384D01*
Y437984D01*
X436973Y437934D01*
X436773D01*
Y438434D01*
X436973D01*
G37*
G36*
G01Y435834D02*
X437723Y435784D01*
Y435384D01*
X436973Y435334D01*
X436773D01*
Y435834D01*
X436973D01*
G37*
G36*
G01X436573Y421034D02*
X435823Y421084D01*
Y421484D01*
X436573Y421534D01*
X436773D01*
Y421034D01*
X436573D01*
G37*
G36*
G01Y423634D02*
X435823Y423684D01*
Y424084D01*
X436573Y424134D01*
X436773D01*
Y423634D01*
X436573D01*
G37*
G36*
G01Y426234D02*
X435823Y426284D01*
Y426684D01*
X436573Y426734D01*
X436773D01*
Y426234D01*
X436573D01*
G37*
G36*
G01Y428834D02*
X435823Y428884D01*
Y429284D01*
X436573Y429334D01*
X436773D01*
Y428834D01*
X436573D01*
G37*
G36*
G01Y431434D02*
X435823Y431484D01*
Y431884D01*
X436573Y431934D01*
X436773D01*
Y431434D01*
X436573D01*
G37*
G36*
G01Y439234D02*
X435823Y439284D01*
Y439684D01*
X436573Y439734D01*
X436773D01*
Y439234D01*
X436573D01*
G37*
G36*
G01Y436634D02*
X435823Y436684D01*
Y437084D01*
X436573Y437134D01*
X436773D01*
Y436634D01*
X436573D01*
G37*
G36*
G01Y434034D02*
X435823Y434084D01*
Y434484D01*
X436573Y434534D01*
X436773D01*
Y434034D01*
X436573D01*
G37*
G36*
G01X430348Y417530D02*
X431108Y417180D01*
Y416280D01*
X430348Y415930D01*
X430173D01*
Y417530D01*
X430348D01*
G37*
G36*
G01X431364Y413335D02*
X432148Y413625D01*
X432785Y412988D01*
X432495Y412204D01*
X432371Y412080D01*
X431240Y413211D01*
X431364Y413335D01*
G37*
G36*
G01X433613Y410621D02*
X434373Y410271D01*
Y409371D01*
X433613Y409021D01*
X433438D01*
Y410621D01*
X433613D01*
G37*
G36*
G01X430773Y422834D02*
X431523Y422784D01*
Y422384D01*
X430773Y422334D01*
X430573D01*
Y422834D01*
X430773D01*
G37*
G36*
G01Y425434D02*
X431523Y425384D01*
Y424984D01*
X430773Y424934D01*
X430573D01*
Y425434D01*
X430773D01*
G37*
G36*
G01Y428034D02*
X431523Y427984D01*
Y427584D01*
X430773Y427534D01*
X430573D01*
Y428034D01*
X430773D01*
G37*
G36*
G01Y430634D02*
X431523Y430584D01*
Y430184D01*
X430773Y430134D01*
X430573D01*
Y430634D01*
X430773D01*
G37*
G36*
G01Y433234D02*
X431523Y433184D01*
Y432784D01*
X430773Y432734D01*
X430573D01*
Y433234D01*
X430773D01*
G37*
G36*
G01Y438434D02*
X431523Y438384D01*
Y437984D01*
X430773Y437934D01*
X430573D01*
Y438434D01*
X430773D01*
G37*
G36*
G01Y435834D02*
X431523Y435784D01*
Y435384D01*
X430773Y435334D01*
X430573D01*
Y435834D01*
X430773D01*
G37*
G36*
G01X430373Y421034D02*
X429623Y421084D01*
Y421484D01*
X430373Y421534D01*
X430573D01*
Y421034D01*
X430373D01*
G37*
G36*
G01Y423634D02*
X429623Y423684D01*
Y424084D01*
X430373Y424134D01*
X430573D01*
Y423634D01*
X430373D01*
G37*
G36*
G01Y426234D02*
X429623Y426284D01*
Y426684D01*
X430373Y426734D01*
X430573D01*
Y426234D01*
X430373D01*
G37*
G36*
G01Y428834D02*
X429623Y428884D01*
Y429284D01*
X430373Y429334D01*
X430573D01*
Y428834D01*
X430373D01*
G37*
G36*
G01Y431434D02*
X429623Y431484D01*
Y431884D01*
X430373Y431934D01*
X430573D01*
Y431434D01*
X430373D01*
G37*
G36*
G01Y439234D02*
X429623Y439284D01*
Y439684D01*
X430373Y439734D01*
X430573D01*
Y439234D01*
X430373D01*
G37*
G36*
G01Y436634D02*
X429623Y436684D01*
Y437084D01*
X430373Y437134D01*
X430573D01*
Y436634D01*
X430373D01*
G37*
G36*
G01Y434034D02*
X429623Y434084D01*
Y434484D01*
X430373Y434534D01*
X430573D01*
Y434034D01*
X430373D01*
G37*
G36*
G01X434278Y413167D02*
X433493Y412877D01*
X432857Y413513D01*
X433147Y414298D01*
X433270Y414422D01*
X434402Y413290D01*
X434278Y413167D01*
G37*
G36*
G01X432348Y416530D02*
X431588Y416880D01*
Y417780D01*
X432348Y418130D01*
X432523D01*
Y416530D01*
X432348D01*
G37*
G36*
G01X434973Y407281D02*
X434213Y407631D01*
Y408531D01*
X434973Y408881D01*
X435148D01*
Y407281D01*
X434973D01*
G37*
G36*
G01X432323Y422834D02*
X433073Y422784D01*
Y422384D01*
X432323Y422334D01*
X432123D01*
Y422834D01*
X432323D01*
G37*
G36*
G01Y425434D02*
X433073Y425384D01*
Y424984D01*
X432323Y424934D01*
X432123D01*
Y425434D01*
X432323D01*
G37*
G36*
G01Y428034D02*
X433073Y427984D01*
Y427584D01*
X432323Y427534D01*
X432123D01*
Y428034D01*
X432323D01*
G37*
G36*
G01Y430634D02*
X433073Y430584D01*
Y430184D01*
X432323Y430134D01*
X432123D01*
Y430634D01*
X432323D01*
G37*
G36*
G01Y433234D02*
X433073Y433184D01*
Y432784D01*
X432323Y432734D01*
X432123D01*
Y433234D01*
X432323D01*
G37*
G36*
G01Y438434D02*
X433073Y438384D01*
Y437984D01*
X432323Y437934D01*
X432123D01*
Y438434D01*
X432323D01*
G37*
G36*
G01Y435834D02*
X433073Y435784D01*
Y435384D01*
X432323Y435334D01*
X432123D01*
Y435834D01*
X432323D01*
G37*
G36*
G01X431923Y421034D02*
X431173Y421084D01*
Y421484D01*
X431923Y421534D01*
X432123D01*
Y421034D01*
X431923D01*
G37*
G36*
G01Y423634D02*
X431173Y423684D01*
Y424084D01*
X431923Y424134D01*
X432123D01*
Y423634D01*
X431923D01*
G37*
G36*
G01Y426234D02*
X431173Y426284D01*
Y426684D01*
X431923Y426734D01*
X432123D01*
Y426234D01*
X431923D01*
G37*
G36*
G01Y428834D02*
X431173Y428884D01*
Y429284D01*
X431923Y429334D01*
X432123D01*
Y428834D01*
X431923D01*
G37*
G36*
G01Y431434D02*
X431173Y431484D01*
Y431884D01*
X431923Y431934D01*
X432123D01*
Y431434D01*
X431923D01*
G37*
G36*
G01Y439234D02*
X431173Y439284D01*
Y439684D01*
X431923Y439734D01*
X432123D01*
Y439234D01*
X431923D01*
G37*
G36*
G01Y436634D02*
X431173Y436684D01*
Y437084D01*
X431923Y437134D01*
X432123D01*
Y436634D01*
X431923D01*
G37*
G36*
G01Y434034D02*
X431173Y434084D01*
Y434484D01*
X431923Y434534D01*
X432123D01*
Y434034D01*
X431923D01*
G37*
G36*
G01X429248Y415930D02*
X428488Y416280D01*
Y417180D01*
X429248Y417530D01*
X429423D01*
Y415930D01*
X429248D01*
G37*
G36*
G01X431717Y411426D02*
X430932Y411136D01*
X430296Y411772D01*
X430586Y412557D01*
X430709Y412681D01*
X431841Y411549D01*
X431717Y411426D01*
G37*
G36*
G01X432513Y407321D02*
X431753Y407671D01*
Y408571D01*
X432513Y408921D01*
X432688D01*
Y407321D01*
X432513D01*
G37*
G36*
G01X428823Y421034D02*
X428073Y421084D01*
Y421484D01*
X428823Y421534D01*
X429023D01*
Y421034D01*
X428823D01*
G37*
G36*
G01Y423634D02*
X428073Y423684D01*
Y424084D01*
X428823Y424134D01*
X429023D01*
Y423634D01*
X428823D01*
G37*
G36*
G01Y426234D02*
X428073Y426284D01*
Y426684D01*
X428823Y426734D01*
X429023D01*
Y426234D01*
X428823D01*
G37*
G36*
G01Y428834D02*
X428073Y428884D01*
Y429284D01*
X428823Y429334D01*
X429023D01*
Y428834D01*
X428823D01*
G37*
G36*
G01Y431434D02*
X428073Y431484D01*
Y431884D01*
X428823Y431934D01*
X429023D01*
Y431434D01*
X428823D01*
G37*
G36*
G01Y439234D02*
X428073Y439284D01*
Y439684D01*
X428823Y439734D01*
X429023D01*
Y439234D01*
X428823D01*
G37*
G36*
G01Y436634D02*
X428073Y436684D01*
Y437084D01*
X428823Y437134D01*
X429023D01*
Y436634D01*
X428823D01*
G37*
G36*
G01Y434034D02*
X428073Y434084D01*
Y434484D01*
X428823Y434534D01*
X429023D01*
Y434034D01*
X428823D01*
G37*
G36*
G01X429223Y422834D02*
X429973Y422784D01*
Y422384D01*
X429223Y422334D01*
X429023D01*
Y422834D01*
X429223D01*
G37*
G36*
G01Y425434D02*
X429973Y425384D01*
Y424984D01*
X429223Y424934D01*
X429023D01*
Y425434D01*
X429223D01*
G37*
G36*
G01Y428034D02*
X429973Y427984D01*
Y427584D01*
X429223Y427534D01*
X429023D01*
Y428034D01*
X429223D01*
G37*
G36*
G01Y430634D02*
X429973Y430584D01*
Y430184D01*
X429223Y430134D01*
X429023D01*
Y430634D01*
X429223D01*
G37*
G36*
G01Y433234D02*
X429973Y433184D01*
Y432784D01*
X429223Y432734D01*
X429023D01*
Y433234D01*
X429223D01*
G37*
G36*
G01Y438434D02*
X429973Y438384D01*
Y437984D01*
X429223Y437934D01*
X429023D01*
Y438434D01*
X429223D01*
G37*
G36*
G01Y435834D02*
X429973Y435784D01*
Y435384D01*
X429223Y435334D01*
X429023D01*
Y435834D01*
X429223D01*
G37*
G36*
G01X433448Y418130D02*
X434208Y417780D01*
Y416880D01*
X433448Y416530D01*
X433273D01*
Y418130D01*
X433448D01*
G37*
G36*
G01X434144Y414857D02*
X434928Y415147D01*
X435565Y414510D01*
X435275Y413726D01*
X435151Y413602D01*
X434020Y414733D01*
X434144Y414857D01*
G37*
G36*
G01X436073Y408881D02*
X436833Y408531D01*
Y407631D01*
X436073Y407281D01*
X435898D01*
Y408881D01*
X436073D01*
G37*
G36*
G01X433873Y422834D02*
X434623Y422784D01*
Y422384D01*
X433873Y422334D01*
X433673D01*
Y422834D01*
X433873D01*
G37*
G36*
G01Y425434D02*
X434623Y425384D01*
Y424984D01*
X433873Y424934D01*
X433673D01*
Y425434D01*
X433873D01*
G37*
G36*
G01Y428034D02*
X434623Y427984D01*
Y427584D01*
X433873Y427534D01*
X433673D01*
Y428034D01*
X433873D01*
G37*
G36*
G01Y430634D02*
X434623Y430584D01*
Y430184D01*
X433873Y430134D01*
X433673D01*
Y430634D01*
X433873D01*
G37*
G36*
G01Y433234D02*
X434623Y433184D01*
Y432784D01*
X433873Y432734D01*
X433673D01*
Y433234D01*
X433873D01*
G37*
G36*
G01Y438434D02*
X434623Y438384D01*
Y437984D01*
X433873Y437934D01*
X433673D01*
Y438434D01*
X433873D01*
G37*
G36*
G01Y435834D02*
X434623Y435784D01*
Y435384D01*
X433873Y435334D01*
X433673D01*
Y435834D01*
X433873D01*
G37*
G36*
G01X433473Y421034D02*
X432723Y421084D01*
Y421484D01*
X433473Y421534D01*
X433673D01*
Y421034D01*
X433473D01*
G37*
G36*
G01Y423634D02*
X432723Y423684D01*
Y424084D01*
X433473Y424134D01*
X433673D01*
Y423634D01*
X433473D01*
G37*
G36*
G01Y426234D02*
X432723Y426284D01*
Y426684D01*
X433473Y426734D01*
X433673D01*
Y426234D01*
X433473D01*
G37*
G36*
G01Y428834D02*
X432723Y428884D01*
Y429284D01*
X433473Y429334D01*
X433673D01*
Y428834D01*
X433473D01*
G37*
G36*
G01Y431434D02*
X432723Y431484D01*
Y431884D01*
X433473Y431934D01*
X433673D01*
Y431434D01*
X433473D01*
G37*
G36*
G01Y439234D02*
X432723Y439284D01*
Y439684D01*
X433473Y439734D01*
X433673D01*
Y439234D01*
X433473D01*
G37*
G36*
G01Y436634D02*
X432723Y436684D01*
Y437084D01*
X433473Y437134D01*
X433673D01*
Y436634D01*
X433473D01*
G37*
G36*
G01Y434034D02*
X432723Y434084D01*
Y434484D01*
X433473Y434534D01*
X433673D01*
Y434034D01*
X433473D01*
G37*
G36*
G01X449397Y413812D02*
X448637Y414162D01*
Y415062D01*
X449397Y415412D01*
X449572D01*
Y413812D01*
X449397D01*
G37*
G36*
G01Y409912D02*
X448637Y410262D01*
Y411162D01*
X449397Y411512D01*
X449572D01*
Y409912D01*
X449397D01*
G37*
G36*
G01X448972Y417776D02*
X448222Y417826D01*
Y418226D01*
X448972Y418276D01*
X449172D01*
Y417776D01*
X448972D01*
G37*
G36*
G01Y420376D02*
X448222Y420426D01*
Y420826D01*
X448972Y420876D01*
X449172D01*
Y420376D01*
X448972D01*
G37*
G36*
G01X449372Y419576D02*
X450122Y419526D01*
Y419126D01*
X449372Y419076D01*
X449172D01*
Y419576D01*
X449372D01*
G37*
G36*
G01X448972Y425576D02*
X448222Y425626D01*
Y426026D01*
X448972Y426076D01*
X449172D01*
Y425576D01*
X448972D01*
G37*
G36*
G01Y428176D02*
X448222Y428226D01*
Y428626D01*
X448972Y428676D01*
X449172D01*
Y428176D01*
X448972D01*
G37*
G36*
G01Y422976D02*
X448222Y423026D01*
Y423426D01*
X448972Y423476D01*
X449172D01*
Y422976D01*
X448972D01*
G37*
G36*
G01X449372Y427376D02*
X450122Y427326D01*
Y426926D01*
X449372Y426876D01*
X449172D01*
Y427376D01*
X449372D01*
G37*
G36*
G01Y429976D02*
X450122Y429926D01*
Y429526D01*
X449372Y429476D01*
X449172D01*
Y429976D01*
X449372D01*
G37*
G36*
G01Y424776D02*
X450122Y424726D01*
Y424326D01*
X449372Y424276D01*
X449172D01*
Y424776D01*
X449372D01*
G37*
G36*
G01Y422176D02*
X450122Y422126D01*
Y421726D01*
X449372Y421676D01*
X449172D01*
Y422176D01*
X449372D01*
G37*
G36*
G01X453357Y434849D02*
X453852Y434283D01*
X453569Y434001D01*
X453003Y434496D01*
X452862Y434637D01*
X453216Y434991D01*
X453357Y434849D01*
G37*
G36*
G01X451519Y433011D02*
X452014Y432445D01*
X451731Y432162D01*
X451165Y432657D01*
X451024Y432799D01*
X451377Y433152D01*
X451519Y433011D01*
G37*
G36*
G01X451801Y433859D02*
X451306Y434425D01*
X451589Y434708D01*
X452155Y434213D01*
X452296Y434071D01*
X451943Y433718D01*
X451801Y433859D01*
G37*
G36*
G01X449963Y432021D02*
X449468Y432586D01*
X449751Y432869D01*
X450316Y432374D01*
X450458Y432233D01*
X450104Y431879D01*
X449963Y432021D01*
G37*
G36*
G01X458872Y440365D02*
X459367Y439799D01*
X459085Y439516D01*
X458519Y440011D01*
X458377Y440152D01*
X458731Y440506D01*
X458872Y440365D01*
G37*
G36*
G01X460711Y442203D02*
X461206Y441637D01*
X460923Y441355D01*
X460357Y441850D01*
X460216Y441991D01*
X460570Y442345D01*
X460711Y442203D01*
G37*
G36*
G01X457034Y438526D02*
X457529Y437960D01*
X457246Y437678D01*
X456680Y438173D01*
X456539Y438314D01*
X456893Y438668D01*
X457034Y438526D01*
G37*
G36*
G01X455196Y436688D02*
X455690Y436122D01*
X455408Y435839D01*
X454842Y436334D01*
X454701Y436476D01*
X455054Y436829D01*
X455196Y436688D01*
G37*
G36*
G01X457317Y439375D02*
X456822Y439940D01*
X457105Y440223D01*
X457670Y439728D01*
X457812Y439587D01*
X457458Y439233D01*
X457317Y439375D01*
G37*
G36*
G01X459155Y441213D02*
X458660Y441779D01*
X458943Y442062D01*
X459509Y441567D01*
X459650Y441425D01*
X459297Y441072D01*
X459155Y441213D01*
G37*
G36*
G01X455478Y437536D02*
X454983Y438102D01*
X455266Y438385D01*
X455832Y437890D01*
X455973Y437748D01*
X455620Y437395D01*
X455478Y437536D01*
G37*
G36*
G01X453640Y435698D02*
X453145Y436263D01*
X453428Y436546D01*
X453993Y436051D01*
X454135Y435910D01*
X453781Y435556D01*
X453640Y435698D01*
G37*
G36*
G01X460994Y443052D02*
X460499Y443617D01*
X460782Y443900D01*
X461347Y443405D01*
X461489Y443264D01*
X461135Y442910D01*
X460994Y443052D01*
G37*
G36*
G01X462549Y444042D02*
X463044Y443476D01*
X462761Y443194D01*
X462195Y443689D01*
X462054Y443830D01*
X462408Y444184D01*
X462549Y444042D01*
G37*
G36*
G01X450497Y415412D02*
X451257Y415062D01*
Y414162D01*
X450497Y413812D01*
X450322D01*
Y415412D01*
X450497D01*
G37*
G36*
G01Y411512D02*
X451257Y411162D01*
Y410262D01*
X450497Y409912D01*
X450322D01*
Y411512D01*
X450497D01*
G37*
G36*
G01X450522Y417776D02*
X449772Y417826D01*
Y418226D01*
X450522Y418276D01*
X450722D01*
Y417776D01*
X450522D01*
G37*
G36*
G01X450922Y419576D02*
X451672Y419526D01*
Y419126D01*
X450922Y419076D01*
X450722D01*
Y419576D01*
X450922D01*
G37*
G36*
G01X450522Y420376D02*
X449772Y420426D01*
Y420826D01*
X450522Y420876D01*
X450722D01*
Y420376D01*
X450522D01*
G37*
G36*
G01X450922Y424776D02*
X451672Y424726D01*
Y424326D01*
X450922Y424276D01*
X450722D01*
Y424776D01*
X450922D01*
G37*
G36*
G01Y422176D02*
X451672Y422126D01*
Y421726D01*
X450922Y421676D01*
X450722D01*
Y422176D01*
X450922D01*
G37*
G36*
G01X454454Y433753D02*
X454949Y433187D01*
X454666Y432904D01*
X454100Y433399D01*
X453959Y433541D01*
X454312Y433894D01*
X454454Y433753D01*
G37*
G36*
G01X452615Y431914D02*
X453110Y431349D01*
X452827Y431066D01*
X452261Y431561D01*
X452120Y431702D01*
X452474Y432056D01*
X452615Y431914D01*
G37*
G36*
G01X452898Y432763D02*
X452403Y433328D01*
X452686Y433611D01*
X453251Y433116D01*
X453393Y432975D01*
X453039Y432621D01*
X452898Y432763D01*
G37*
G36*
G01X451059Y430924D02*
X450564Y431490D01*
X450847Y431773D01*
X451413Y431278D01*
X451554Y431136D01*
X451201Y430783D01*
X451059Y430924D01*
G37*
G36*
G01X450522Y425576D02*
X449772Y425626D01*
Y426026D01*
X450522Y426076D01*
X450722D01*
Y425576D01*
X450522D01*
G37*
G36*
G01Y428176D02*
X449772Y428226D01*
Y428626D01*
X450522Y428676D01*
X450722D01*
Y428176D01*
X450522D01*
G37*
G36*
G01Y422976D02*
X449772Y423026D01*
Y423426D01*
X450522Y423476D01*
X450722D01*
Y422976D01*
X450522D01*
G37*
G36*
G01X450922Y427376D02*
X451672Y427326D01*
Y426926D01*
X450922Y426876D01*
X450722D01*
Y427376D01*
X450922D01*
G37*
G36*
G01X459969Y439268D02*
X460464Y438702D01*
X460181Y438420D01*
X459615Y438915D01*
X459474Y439056D01*
X459828Y439410D01*
X459969Y439268D01*
G37*
G36*
G01X461807Y441107D02*
X462302Y440541D01*
X462020Y440258D01*
X461454Y440753D01*
X461312Y440894D01*
X461666Y441248D01*
X461807Y441107D01*
G37*
G36*
G01X463646Y442945D02*
X464141Y442379D01*
X463858Y442097D01*
X463292Y442592D01*
X463151Y442733D01*
X463504Y443086D01*
X463646Y442945D01*
G37*
G36*
G01X458130Y437430D02*
X458625Y436864D01*
X458343Y436581D01*
X457777Y437076D01*
X457636Y437218D01*
X457989Y437571D01*
X458130Y437430D01*
G37*
G36*
G01X456292Y435591D02*
X456787Y435025D01*
X456504Y434743D01*
X455938Y435238D01*
X455797Y435379D01*
X456151Y435733D01*
X456292Y435591D01*
G37*
G36*
G01X460252Y440117D02*
X459757Y440682D01*
X460040Y440965D01*
X460605Y440470D01*
X460747Y440329D01*
X460393Y439975D01*
X460252Y440117D01*
G37*
G36*
G01X462090Y441955D02*
X461595Y442521D01*
X461878Y442804D01*
X462444Y442309D01*
X462585Y442167D01*
X462232Y441814D01*
X462090Y441955D01*
G37*
G36*
G01X458413Y438278D02*
X457918Y438844D01*
X458201Y439127D01*
X458767Y438632D01*
X458908Y438490D01*
X458555Y438137D01*
X458413Y438278D01*
G37*
G36*
G01X456575Y436440D02*
X456080Y437005D01*
X456363Y437288D01*
X456928Y436793D01*
X457070Y436652D01*
X456716Y436298D01*
X456575Y436440D01*
G37*
G36*
G01X454736Y434601D02*
X454241Y435167D01*
X454524Y435450D01*
X455090Y434955D01*
X455231Y434813D01*
X454878Y434460D01*
X454736Y434601D01*
G37*
G36*
G01X463928Y443794D02*
X463433Y444360D01*
X463716Y444643D01*
X464282Y444148D01*
X464423Y444006D01*
X464070Y443653D01*
X463928Y443794D01*
G37*
G36*
G01X461797Y414312D02*
X461037Y414662D01*
Y415562D01*
X461797Y415912D01*
X461972D01*
Y414312D01*
X461797D01*
G37*
G36*
G01Y410412D02*
X461037Y410762D01*
Y411662D01*
X461797Y412012D01*
X461972D01*
Y410412D01*
X461797D01*
G37*
G36*
G01X461372Y417776D02*
X460622Y417826D01*
Y418226D01*
X461372Y418276D01*
X461572D01*
Y417776D01*
X461372D01*
G37*
G36*
G01Y420376D02*
X460622Y420426D01*
Y420826D01*
X461372Y420876D01*
X461572D01*
Y420376D01*
X461372D01*
G37*
G36*
G01X461772Y419576D02*
X462522Y419526D01*
Y419126D01*
X461772Y419076D01*
X461572D01*
Y419576D01*
X461772D01*
G37*
G36*
G01X461372Y422976D02*
X460622Y423026D01*
Y423426D01*
X461372Y423476D01*
X461572D01*
Y422976D01*
X461372D01*
G37*
G36*
G01X461772Y424776D02*
X462522Y424726D01*
Y424326D01*
X461772Y424276D01*
X461572D01*
Y424776D01*
X461772D01*
G37*
G36*
G01Y422176D02*
X462522Y422126D01*
Y421726D01*
X461772Y421676D01*
X461572D01*
Y422176D01*
X461772D01*
G37*
G36*
G01X467645Y431592D02*
X468140Y431026D01*
X467858Y430743D01*
X467292Y431238D01*
X467150Y431379D01*
X467504Y431733D01*
X467645Y431592D01*
G37*
G36*
G01X465807Y429753D02*
X466302Y429187D01*
X466019Y428905D01*
X465453Y429400D01*
X465312Y429541D01*
X465666Y429895D01*
X465807Y429753D01*
G37*
G36*
G01X463969Y427915D02*
X464463Y427349D01*
X464181Y427066D01*
X463615Y427561D01*
X463474Y427703D01*
X463827Y428056D01*
X463969Y427915D01*
G37*
G36*
G01X467928Y432440D02*
X467433Y433006D01*
X467716Y433289D01*
X468282Y432794D01*
X468423Y432652D01*
X468070Y432299D01*
X467928Y432440D01*
G37*
G36*
G01X466090Y430602D02*
X465595Y431167D01*
X465878Y431450D01*
X466443Y430955D01*
X466585Y430814D01*
X466231Y430460D01*
X466090Y430602D01*
G37*
G36*
G01X464251Y428763D02*
X463756Y429329D01*
X464039Y429612D01*
X464605Y429117D01*
X464746Y428975D01*
X464393Y428622D01*
X464251Y428763D01*
G37*
G36*
G01X462413Y426925D02*
X461918Y427490D01*
X462201Y427773D01*
X462766Y427278D01*
X462908Y427137D01*
X462554Y426783D01*
X462413Y426925D01*
G37*
G36*
G01X469484Y433430D02*
X469979Y432864D01*
X469696Y432582D01*
X469130Y433077D01*
X468989Y433218D01*
X469343Y433572D01*
X469484Y433430D01*
G37*
G36*
G01X471322Y435269D02*
X471817Y434703D01*
X471535Y434420D01*
X470969Y434915D01*
X470827Y435056D01*
X471181Y435410D01*
X471322Y435269D01*
G37*
G36*
G01X473161Y437107D02*
X473656Y436541D01*
X473373Y436259D01*
X472807Y436753D01*
X472666Y436895D01*
X473019Y437248D01*
X473161Y437107D01*
G37*
G36*
G01X469767Y434279D02*
X469272Y434844D01*
X469555Y435127D01*
X470120Y434632D01*
X470262Y434491D01*
X469908Y434137D01*
X469767Y434279D01*
G37*
G36*
G01X471605Y436117D02*
X471110Y436683D01*
X471393Y436966D01*
X471959Y436471D01*
X472100Y436329D01*
X471747Y435976D01*
X471605Y436117D01*
G37*
G36*
G01X473444Y437956D02*
X472949Y438521D01*
X473232Y438804D01*
X473797Y438309D01*
X473939Y438168D01*
X473585Y437814D01*
X473444Y437956D01*
G37*
G36*
G01X476449Y438950D02*
X476399Y438200D01*
X475999D01*
X475949Y438950D01*
Y439150D01*
X476449D01*
Y438950D01*
G37*
G36*
G01X477249Y439350D02*
X477299Y440100D01*
X477699D01*
X477749Y439350D01*
Y439150D01*
X477249D01*
Y439350D01*
G37*
G36*
G01X462897Y415912D02*
X463657Y415562D01*
Y414662D01*
X462897Y414312D01*
X462722D01*
Y415912D01*
X462897D01*
G37*
G36*
G01Y412012D02*
X463657Y411662D01*
Y410762D01*
X462897Y410412D01*
X462722D01*
Y412012D01*
X462897D01*
G37*
G36*
G01X462922Y417776D02*
X462172Y417826D01*
Y418226D01*
X462922Y418276D01*
X463122D01*
Y417776D01*
X462922D01*
G37*
G36*
G01X463322Y419576D02*
X464072Y419526D01*
Y419126D01*
X463322Y419076D01*
X463122D01*
Y419576D01*
X463322D01*
G37*
G36*
G01X462922Y420376D02*
X462172Y420426D01*
Y420826D01*
X462922Y420876D01*
X463122D01*
Y420376D01*
X462922D01*
G37*
G36*
G01X463322Y422176D02*
X464072Y422126D01*
Y421726D01*
X463322Y421676D01*
X463122D01*
Y422176D01*
X463322D01*
G37*
G36*
G01Y424776D02*
X464072Y424726D01*
Y424326D01*
X463322Y424276D01*
X463122D01*
Y424776D01*
X463322D01*
G37*
G36*
G01X462922Y422976D02*
X462172Y423026D01*
Y423426D01*
X462922Y423476D01*
X463122D01*
Y422976D01*
X462922D01*
G37*
G36*
G01X466903Y428657D02*
X467398Y428091D01*
X467116Y427808D01*
X466550Y428303D01*
X466409Y428445D01*
X466762Y428798D01*
X466903Y428657D01*
G37*
G36*
G01X465065Y426818D02*
X465560Y426252D01*
X465277Y425970D01*
X464711Y426465D01*
X464570Y426606D01*
X464924Y426960D01*
X465065Y426818D01*
G37*
G36*
G01X467186Y429505D02*
X466691Y430071D01*
X466974Y430354D01*
X467540Y429859D01*
X467681Y429717D01*
X467328Y429364D01*
X467186Y429505D01*
G37*
G36*
G01X465348Y427667D02*
X464853Y428232D01*
X465136Y428515D01*
X465701Y428020D01*
X465843Y427879D01*
X465489Y427525D01*
X465348Y427667D01*
G37*
G36*
G01X463509Y425828D02*
X463014Y426394D01*
X463297Y426677D01*
X463863Y426182D01*
X464004Y426040D01*
X463651Y425687D01*
X463509Y425828D01*
G37*
G36*
G01X468742Y430495D02*
X469237Y429929D01*
X468954Y429647D01*
X468388Y430142D01*
X468247Y430283D01*
X468601Y430637D01*
X468742Y430495D01*
G37*
G36*
G01X469025Y431344D02*
X468530Y431909D01*
X468813Y432192D01*
X469378Y431697D01*
X469520Y431556D01*
X469166Y431202D01*
X469025Y431344D01*
G37*
G36*
G01X472419Y434172D02*
X472914Y433606D01*
X472631Y433324D01*
X472065Y433819D01*
X471924Y433960D01*
X472277Y434313D01*
X472419Y434172D01*
G37*
G36*
G01X474257Y436011D02*
X474752Y435445D01*
X474470Y435162D01*
X473904Y435657D01*
X473762Y435798D01*
X474116Y436152D01*
X474257Y436011D01*
G37*
G36*
G01X470863Y433182D02*
X470368Y433748D01*
X470651Y434031D01*
X471217Y433536D01*
X471358Y433394D01*
X471005Y433041D01*
X470863Y433182D01*
G37*
G36*
G01X472702Y435021D02*
X472207Y435586D01*
X472490Y435869D01*
X473055Y435374D01*
X473197Y435233D01*
X472843Y434879D01*
X472702Y435021D01*
G37*
G36*
G01X474540Y436859D02*
X474045Y437425D01*
X474328Y437708D01*
X474894Y437213D01*
X475035Y437071D01*
X474682Y436718D01*
X474540Y436859D01*
G37*
G36*
G01X476449Y437400D02*
X476399Y436650D01*
X475999D01*
X475949Y437400D01*
Y437600D01*
X476449D01*
Y437400D01*
G37*
G36*
G01X470580Y432334D02*
X471075Y431768D01*
X470793Y431485D01*
X470227Y431980D01*
X470085Y432121D01*
X470439Y432475D01*
X470580Y432334D01*
G37*
G36*
G01X477249Y437800D02*
X477299Y438550D01*
X477699D01*
X477749Y437800D01*
Y437600D01*
X477249D01*
Y437800D01*
G37*
G36*
G01X445872Y417776D02*
X445122Y417826D01*
Y418226D01*
X445872Y418276D01*
X446072D01*
Y417776D01*
X445872D01*
G37*
G36*
G01Y420376D02*
X445122Y420426D01*
Y420826D01*
X445872Y420876D01*
X446072D01*
Y420376D01*
X445872D01*
G37*
G36*
G01Y425576D02*
X445122Y425626D01*
Y426026D01*
X445872Y426076D01*
X446072D01*
Y425576D01*
X445872D01*
G37*
G36*
G01Y428176D02*
X445122Y428226D01*
Y428626D01*
X445872Y428676D01*
X446072D01*
Y428176D01*
X445872D01*
G37*
G36*
G01Y430776D02*
X445122Y430826D01*
Y431226D01*
X445872Y431276D01*
X446072D01*
Y430776D01*
X445872D01*
G37*
G36*
G01Y422976D02*
X445122Y423026D01*
Y423426D01*
X445872Y423476D01*
X446072D01*
Y422976D01*
X445872D01*
G37*
G36*
G01X446297Y414304D02*
X445537Y414654D01*
Y415554D01*
X446297Y415904D01*
X446472D01*
Y414304D01*
X446297D01*
G37*
G36*
G01Y410804D02*
X445537Y411154D01*
Y412054D01*
X446297Y412404D01*
X446472D01*
Y410804D01*
X446297D01*
G37*
G36*
G01X446272Y419576D02*
X447022Y419526D01*
Y419126D01*
X446272Y419076D01*
X446072D01*
Y419576D01*
X446272D01*
G37*
G36*
G01X447770Y434214D02*
X447275Y434779D01*
X447558Y435062D01*
X448123Y434567D01*
X448265Y434426D01*
X447911Y434072D01*
X447770Y434214D01*
G37*
G36*
G01X447487Y433365D02*
X447982Y432800D01*
X447699Y432517D01*
X447134Y433012D01*
X446992Y433153D01*
X447346Y433507D01*
X447487Y433365D01*
G37*
G36*
G01X446272Y427376D02*
X447022Y427326D01*
Y426926D01*
X446272Y426876D01*
X446072D01*
Y427376D01*
X446272D01*
G37*
G36*
G01Y429976D02*
X447022Y429926D01*
Y429526D01*
X446272Y429476D01*
X446072D01*
Y429976D01*
X446272D01*
G37*
G36*
G01Y424776D02*
X447022Y424726D01*
Y424326D01*
X446272Y424276D01*
X446072D01*
Y424776D01*
X446272D01*
G37*
G36*
G01Y422176D02*
X447022Y422126D01*
Y421726D01*
X446272Y421676D01*
X446072D01*
Y422176D01*
X446272D01*
G37*
G36*
G01X453285Y439729D02*
X452790Y440295D01*
X453073Y440578D01*
X453639Y440083D01*
X453780Y439941D01*
X453427Y439588D01*
X453285Y439729D01*
G37*
G36*
G01X451447Y437891D02*
X450952Y438456D01*
X451235Y438739D01*
X451800Y438244D01*
X451942Y438103D01*
X451588Y437749D01*
X451447Y437891D01*
G37*
G36*
G01X449608Y436052D02*
X449113Y436618D01*
X449396Y436901D01*
X449962Y436406D01*
X450103Y436264D01*
X449750Y435911D01*
X449608Y436052D01*
G37*
G36*
G01X454841Y440719D02*
X455336Y440153D01*
X455053Y439871D01*
X454487Y440366D01*
X454346Y440507D01*
X454700Y440861D01*
X454841Y440719D01*
G37*
G36*
G01X456679Y442558D02*
X457174Y441992D01*
X456892Y441709D01*
X456326Y442204D01*
X456184Y442345D01*
X456538Y442699D01*
X456679Y442558D01*
G37*
G36*
G01X453003Y438881D02*
X453497Y438315D01*
X453215Y438032D01*
X452649Y438527D01*
X452508Y438669D01*
X452861Y439022D01*
X453003Y438881D01*
G37*
G36*
G01X451164Y437042D02*
X451659Y436476D01*
X451376Y436194D01*
X450810Y436689D01*
X450669Y436830D01*
X451023Y437184D01*
X451164Y437042D01*
G37*
G36*
G01X449326Y435204D02*
X449821Y434638D01*
X449538Y434355D01*
X448972Y434850D01*
X448831Y434992D01*
X449184Y435345D01*
X449326Y435204D01*
G37*
G36*
G01X455124Y441568D02*
X454629Y442133D01*
X454912Y442416D01*
X455477Y441921D01*
X455619Y441780D01*
X455265Y441426D01*
X455124Y441568D01*
G37*
G36*
G01X456962Y443406D02*
X456467Y443972D01*
X456750Y444255D01*
X457316Y443760D01*
X457457Y443618D01*
X457104Y443265D01*
X456962Y443406D01*
G37*
G36*
G01X458518Y444396D02*
X459013Y443830D01*
X458731Y443547D01*
X458165Y444042D01*
X458023Y444183D01*
X458377Y444537D01*
X458518Y444396D01*
G37*
G36*
G01X447397Y412404D02*
X448157Y412054D01*
Y411154D01*
X447397Y410804D01*
X447222D01*
Y412404D01*
X447397D01*
G37*
G36*
G01X447422Y417776D02*
X446672Y417826D01*
Y418226D01*
X447422Y418276D01*
X447622D01*
Y417776D01*
X447422D01*
G37*
G36*
G01X447397Y415904D02*
X448157Y415554D01*
Y414654D01*
X447397Y414304D01*
X447222D01*
Y415904D01*
X447397D01*
G37*
G36*
G01X447422Y420376D02*
X446672Y420426D01*
Y420826D01*
X447422Y420876D01*
X447622D01*
Y420376D01*
X447422D01*
G37*
G36*
G01X447822Y419576D02*
X448572Y419526D01*
Y419126D01*
X447822Y419076D01*
X447622D01*
Y419576D01*
X447822D01*
G37*
G36*
G01X447422Y425576D02*
X446672Y425626D01*
Y426026D01*
X447422Y426076D01*
X447622D01*
Y425576D01*
X447422D01*
G37*
G36*
G01Y428176D02*
X446672Y428226D01*
Y428626D01*
X447422Y428676D01*
X447622D01*
Y428176D01*
X447422D01*
G37*
G36*
G01Y430776D02*
X446672Y430826D01*
Y431226D01*
X447422Y431276D01*
X447622D01*
Y430776D01*
X447422D01*
G37*
G36*
G01Y422976D02*
X446672Y423026D01*
Y423426D01*
X447422Y423476D01*
X447622D01*
Y422976D01*
X447422D01*
G37*
G36*
G01X447822Y427376D02*
X448572Y427326D01*
Y426926D01*
X447822Y426876D01*
X447622D01*
Y427376D01*
X447822D01*
G37*
G36*
G01Y429976D02*
X448572Y429926D01*
Y429526D01*
X447822Y429476D01*
X447622D01*
Y429976D01*
X447822D01*
G37*
G36*
G01Y424776D02*
X448572Y424726D01*
Y424326D01*
X447822Y424276D01*
X447622D01*
Y424776D01*
X447822D01*
G37*
G36*
G01Y422176D02*
X448572Y422126D01*
Y421726D01*
X447822Y421676D01*
X447622D01*
Y422176D01*
X447822D01*
G37*
G36*
G01X450422Y434107D02*
X450917Y433542D01*
X450634Y433259D01*
X450068Y433754D01*
X449927Y433895D01*
X450281Y434249D01*
X450422Y434107D01*
G37*
G36*
G01X448584Y432269D02*
X449079Y431703D01*
X448796Y431420D01*
X448230Y431915D01*
X448089Y432057D01*
X448442Y432410D01*
X448584Y432269D01*
G37*
G36*
G01X448866Y433117D02*
X448371Y433683D01*
X448654Y433966D01*
X449220Y433471D01*
X449361Y433329D01*
X449008Y432976D01*
X448866Y433117D01*
G37*
G36*
G01X455937Y439623D02*
X456432Y439057D01*
X456150Y438774D01*
X455584Y439269D01*
X455443Y439411D01*
X455796Y439764D01*
X455937Y439623D01*
G37*
G36*
G01X457776Y441461D02*
X458271Y440895D01*
X457988Y440613D01*
X457422Y441108D01*
X457281Y441249D01*
X457635Y441603D01*
X457776Y441461D01*
G37*
G36*
G01X459614Y443300D02*
X460109Y442734D01*
X459827Y442451D01*
X459261Y442946D01*
X459119Y443087D01*
X459473Y443441D01*
X459614Y443300D01*
G37*
G36*
G01X454099Y437784D02*
X454594Y437218D01*
X454311Y436936D01*
X453745Y437431D01*
X453604Y437572D01*
X453958Y437926D01*
X454099Y437784D01*
G37*
G36*
G01X452261Y435946D02*
X452756Y435380D01*
X452473Y435097D01*
X451907Y435592D01*
X451766Y435734D01*
X452119Y436087D01*
X452261Y435946D01*
G37*
G36*
G01X456220Y440471D02*
X455725Y441037D01*
X456008Y441320D01*
X456574Y440825D01*
X456715Y440683D01*
X456362Y440330D01*
X456220Y440471D01*
G37*
G36*
G01X458059Y442310D02*
X457564Y442875D01*
X457847Y443158D01*
X458412Y442663D01*
X458554Y442522D01*
X458200Y442168D01*
X458059Y442310D01*
G37*
G36*
G01X454382Y438633D02*
X453887Y439198D01*
X454170Y439481D01*
X454735Y438986D01*
X454877Y438845D01*
X454523Y438491D01*
X454382Y438633D01*
G37*
G36*
G01X452543Y436794D02*
X452048Y437360D01*
X452331Y437643D01*
X452897Y437148D01*
X453038Y437006D01*
X452685Y436653D01*
X452543Y436794D01*
G37*
G36*
G01X450705Y434956D02*
X450210Y435521D01*
X450493Y435804D01*
X451058Y435309D01*
X451200Y435168D01*
X450846Y434814D01*
X450705Y434956D01*
G37*
G36*
G01X459898Y444148D02*
X459403Y444713D01*
X459686Y444996D01*
X460251Y444501D01*
X460393Y444360D01*
X460039Y444006D01*
X459898Y444148D01*
G37*
G36*
G01X458670Y414312D02*
X457910Y414662D01*
Y415562D01*
X458670Y415912D01*
X458845D01*
Y414312D01*
X458670D01*
G37*
G36*
G01Y410412D02*
X457910Y410762D01*
Y411662D01*
X458670Y412012D01*
X458845D01*
Y410412D01*
X458670D01*
G37*
G36*
G01X458272Y417776D02*
X457522Y417826D01*
Y418226D01*
X458272Y418276D01*
X458472D01*
Y417776D01*
X458272D01*
G37*
G36*
G01Y420376D02*
X457522Y420426D01*
Y420826D01*
X458272Y420876D01*
X458472D01*
Y420376D01*
X458272D01*
G37*
G36*
G01X458672Y419576D02*
X459422Y419526D01*
Y419126D01*
X458672Y419076D01*
X458472D01*
Y419576D01*
X458672D01*
G37*
G36*
G01X462058Y430956D02*
X461563Y431522D01*
X461846Y431805D01*
X462412Y431310D01*
X462553Y431168D01*
X462200Y430815D01*
X462058Y430956D01*
G37*
G36*
G01X460220Y429118D02*
X459725Y429683D01*
X460008Y429966D01*
X460573Y429471D01*
X460715Y429330D01*
X460361Y428976D01*
X460220Y429118D01*
G37*
G36*
G01X458272Y425576D02*
X457522Y425626D01*
Y426026D01*
X458272Y426076D01*
X458472D01*
Y425576D01*
X458272D01*
G37*
G36*
G01Y422976D02*
X457522Y423026D01*
Y423426D01*
X458272Y423476D01*
X458472D01*
Y422976D01*
X458272D01*
G37*
G36*
G01X458672Y424776D02*
X459422Y424726D01*
Y424326D01*
X458672Y424276D01*
X458472D01*
Y424776D01*
X458672D01*
G37*
G36*
G01Y422176D02*
X459422Y422126D01*
Y421726D01*
X458672Y421676D01*
X458472D01*
Y422176D01*
X458672D01*
G37*
G36*
G01X465452Y433785D02*
X465947Y433219D01*
X465665Y432936D01*
X465099Y433431D01*
X464957Y433572D01*
X465311Y433926D01*
X465452Y433785D01*
G37*
G36*
G01X463614Y431946D02*
X464109Y431380D01*
X463826Y431098D01*
X463260Y431593D01*
X463119Y431734D01*
X463473Y432088D01*
X463614Y431946D01*
G37*
G36*
G01X461776Y430108D02*
X462270Y429542D01*
X461988Y429259D01*
X461422Y429754D01*
X461281Y429896D01*
X461634Y430249D01*
X461776Y430108D01*
G37*
G36*
G01X459937Y428269D02*
X460432Y427703D01*
X460149Y427421D01*
X459583Y427916D01*
X459442Y428057D01*
X459796Y428411D01*
X459937Y428269D01*
G37*
G36*
G01X463897Y432795D02*
X463402Y433360D01*
X463685Y433643D01*
X464250Y433148D01*
X464392Y433007D01*
X464038Y432653D01*
X463897Y432795D01*
G37*
G36*
G01X467291Y435623D02*
X467786Y435057D01*
X467503Y434775D01*
X466937Y435270D01*
X466796Y435411D01*
X467150Y435765D01*
X467291Y435623D01*
G37*
G36*
G01X467574Y436472D02*
X467079Y437037D01*
X467362Y437320D01*
X467927Y436825D01*
X468069Y436684D01*
X467715Y436330D01*
X467574Y436472D01*
G37*
G36*
G01X465735Y434633D02*
X465240Y435199D01*
X465523Y435482D01*
X466089Y434987D01*
X466230Y434845D01*
X465877Y434492D01*
X465735Y434633D01*
G37*
G36*
G01X469129Y437462D02*
X469624Y436896D01*
X469342Y436613D01*
X468776Y437108D01*
X468634Y437249D01*
X468988Y437603D01*
X469129Y437462D01*
G37*
G36*
G01X469412Y438310D02*
X468917Y438876D01*
X469200Y439159D01*
X469766Y438664D01*
X469907Y438522D01*
X469554Y438169D01*
X469412Y438310D01*
G37*
G36*
G01X470968Y439300D02*
X471463Y438734D01*
X471180Y438452D01*
X470614Y438946D01*
X470473Y439088D01*
X470826Y439441D01*
X470968Y439300D01*
G37*
G36*
G01X472806Y441139D02*
X473301Y440573D01*
X473019Y440290D01*
X472453Y440785D01*
X472311Y440926D01*
X472665Y441280D01*
X472806Y441139D01*
G37*
G36*
G01X471251Y440149D02*
X470756Y440714D01*
X471039Y440997D01*
X471604Y440502D01*
X471746Y440361D01*
X471392Y440007D01*
X471251Y440149D01*
G37*
G36*
G01X474649Y442450D02*
X474699Y443200D01*
X475099D01*
X475149Y442450D01*
Y442250D01*
X474649D01*
Y442450D01*
G37*
G36*
G01X476449Y442050D02*
X476399Y441300D01*
X475999D01*
X475949Y442050D01*
Y442250D01*
X476449D01*
Y442050D01*
G37*
G36*
G01X477249Y442450D02*
X477299Y443200D01*
X477699D01*
X477749Y442450D01*
Y442250D01*
X477249D01*
Y442450D01*
G37*
G36*
G01X459770Y415912D02*
X460530Y415562D01*
Y414662D01*
X459770Y414312D01*
X459595D01*
Y415912D01*
X459770D01*
G37*
G36*
G01Y412012D02*
X460530Y411662D01*
Y410762D01*
X459770Y410412D01*
X459595D01*
Y412012D01*
X459770D01*
G37*
G36*
G01X459822Y417776D02*
X459072Y417826D01*
Y418226D01*
X459822Y418276D01*
X460022D01*
Y417776D01*
X459822D01*
G37*
G36*
G01Y420376D02*
X459072Y420426D01*
Y420826D01*
X459822Y420876D01*
X460022D01*
Y420376D01*
X459822D01*
G37*
G36*
G01X460222Y419576D02*
X460972Y419526D01*
Y419126D01*
X460222Y419076D01*
X460022D01*
Y419576D01*
X460222D01*
G37*
G36*
G01X459822Y422976D02*
X459072Y423026D01*
Y423426D01*
X459822Y423476D01*
X460022D01*
Y422976D01*
X459822D01*
G37*
G36*
G01Y425576D02*
X459072Y425626D01*
Y426026D01*
X459822Y426076D01*
X460022D01*
Y425576D01*
X459822D01*
G37*
G36*
G01X460222Y422176D02*
X460972Y422126D01*
Y421726D01*
X460222Y421676D01*
X460022D01*
Y422176D01*
X460222D01*
G37*
G36*
G01Y424776D02*
X460972Y424726D01*
Y424326D01*
X460222Y424276D01*
X460022D01*
Y424776D01*
X460222D01*
G37*
G36*
G01X464710Y430850D02*
X465205Y430284D01*
X464923Y430001D01*
X464357Y430496D01*
X464216Y430638D01*
X464569Y430991D01*
X464710Y430850D01*
G37*
G36*
G01X462872Y429011D02*
X463367Y428445D01*
X463084Y428163D01*
X462518Y428658D01*
X462377Y428799D01*
X462731Y429153D01*
X462872Y429011D01*
G37*
G36*
G01X461034Y427173D02*
X461529Y426607D01*
X461246Y426324D01*
X460680Y426819D01*
X460539Y426961D01*
X460892Y427314D01*
X461034Y427173D01*
G37*
G36*
G01X466549Y432688D02*
X467044Y432122D01*
X466761Y431840D01*
X466195Y432335D01*
X466054Y432476D01*
X466408Y432830D01*
X466549Y432688D01*
G37*
G36*
G01X464993Y431698D02*
X464498Y432264D01*
X464781Y432547D01*
X465347Y432052D01*
X465488Y431910D01*
X465135Y431557D01*
X464993Y431698D01*
G37*
G36*
G01X463155Y429860D02*
X462660Y430425D01*
X462943Y430708D01*
X463508Y430213D01*
X463650Y430072D01*
X463296Y429718D01*
X463155Y429860D01*
G37*
G36*
G01X461316Y428021D02*
X460821Y428587D01*
X461104Y428870D01*
X461670Y428375D01*
X461811Y428233D01*
X461458Y427880D01*
X461316Y428021D01*
G37*
G36*
G01X466832Y433537D02*
X466337Y434102D01*
X466620Y434385D01*
X467185Y433890D01*
X467327Y433749D01*
X466973Y433395D01*
X466832Y433537D01*
G37*
G36*
G01X468387Y434527D02*
X468882Y433961D01*
X468600Y433678D01*
X468034Y434173D01*
X467892Y434314D01*
X468246Y434668D01*
X468387Y434527D01*
G37*
G36*
G01X468670Y435375D02*
X468175Y435941D01*
X468458Y436224D01*
X469024Y435729D01*
X469165Y435587D01*
X468812Y435234D01*
X468670Y435375D01*
G37*
G36*
G01X470226Y436365D02*
X470721Y435799D01*
X470438Y435517D01*
X469872Y436012D01*
X469731Y436153D01*
X470084Y436506D01*
X470226Y436365D01*
G37*
G36*
G01X472064Y438204D02*
X472559Y437638D01*
X472277Y437355D01*
X471711Y437850D01*
X471569Y437991D01*
X471923Y438345D01*
X472064Y438204D01*
G37*
G36*
G01X473903Y440042D02*
X474398Y439476D01*
X474115Y439193D01*
X473549Y439688D01*
X473408Y439830D01*
X473761Y440183D01*
X473903Y440042D01*
G37*
G36*
G01X470509Y437214D02*
X470014Y437779D01*
X470297Y438062D01*
X470862Y437567D01*
X471004Y437426D01*
X470650Y437072D01*
X470509Y437214D01*
G37*
G36*
G01X472347Y439052D02*
X471852Y439618D01*
X472135Y439901D01*
X472701Y439406D01*
X472842Y439264D01*
X472489Y438911D01*
X472347Y439052D01*
G37*
G36*
G01X474649Y440900D02*
X474699Y441650D01*
X475099D01*
X475149Y440900D01*
Y440700D01*
X474649D01*
Y440900D01*
G37*
G36*
G01X476449Y440500D02*
X476399Y439750D01*
X475999D01*
X475949Y440500D01*
Y440700D01*
X476449D01*
Y440500D01*
G37*
G36*
G01X477249Y440900D02*
X477299Y441650D01*
X477699D01*
X477749Y440900D01*
Y440700D01*
X477249D01*
Y440900D01*
G37*
G36*
G01X469392Y411024D02*
X468632Y411374D01*
Y412274D01*
X469392Y412624D01*
X469592D01*
Y411024D01*
X469392D01*
G37*
G36*
G01X472123Y417741D02*
X472618Y417175D01*
X472336Y416892D01*
X471770Y417387D01*
X471628Y417528D01*
X471982Y417882D01*
X472123Y417741D01*
G37*
G36*
G01X470568Y416751D02*
X470073Y417316D01*
X470356Y417599D01*
X470921Y417104D01*
X471063Y416963D01*
X470709Y416609D01*
X470568Y416751D01*
G37*
G36*
G01X473962Y419579D02*
X474457Y419013D01*
X474174Y418731D01*
X473608Y419226D01*
X473467Y419367D01*
X473821Y419721D01*
X473962Y419579D01*
G37*
G36*
G01X474245Y420428D02*
X473750Y420993D01*
X474033Y421276D01*
X474598Y420781D01*
X474740Y420640D01*
X474386Y420286D01*
X474245Y420428D01*
G37*
G36*
G01X472406Y418589D02*
X471911Y419155D01*
X472194Y419438D01*
X472760Y418943D01*
X472901Y418801D01*
X472548Y418448D01*
X472406Y418589D01*
G37*
G36*
G01X475800Y421418D02*
X476295Y420852D01*
X476013Y420569D01*
X475447Y421064D01*
X475305Y421205D01*
X475659Y421559D01*
X475800Y421418D01*
G37*
G36*
G01X476083Y422266D02*
X475588Y422832D01*
X475871Y423115D01*
X476437Y422620D01*
X476578Y422478D01*
X476225Y422125D01*
X476083Y422266D01*
G37*
G36*
G01X477639Y423256D02*
X478134Y422690D01*
X477851Y422408D01*
X477285Y422902D01*
X477144Y423044D01*
X477497Y423397D01*
X477639Y423256D01*
G37*
G36*
G01X477922Y424105D02*
X477427Y424670D01*
X477710Y424953D01*
X478275Y424458D01*
X478417Y424317D01*
X478063Y423963D01*
X477922Y424105D01*
G37*
G36*
G01X470542Y412624D02*
X471302Y412274D01*
Y411374D01*
X470542Y411024D01*
X470342D01*
Y412624D01*
X470542D01*
G37*
G36*
G01X471664Y415654D02*
X471169Y416220D01*
X471452Y416503D01*
X472018Y416008D01*
X472159Y415866D01*
X471806Y415513D01*
X471664Y415654D01*
G37*
G36*
G01X473503Y417493D02*
X473008Y418058D01*
X473291Y418341D01*
X473856Y417846D01*
X473998Y417705D01*
X473644Y417351D01*
X473503Y417493D01*
G37*
G36*
G01X475058Y418483D02*
X475553Y417917D01*
X475271Y417634D01*
X474705Y418129D01*
X474563Y418270D01*
X474917Y418624D01*
X475058Y418483D01*
G37*
G36*
G01X475341Y419331D02*
X474846Y419897D01*
X475129Y420180D01*
X475695Y419685D01*
X475836Y419543D01*
X475483Y419190D01*
X475341Y419331D01*
G37*
G36*
G01X476897Y420321D02*
X477392Y419755D01*
X477109Y419473D01*
X476543Y419968D01*
X476402Y420109D01*
X476755Y420462D01*
X476897Y420321D01*
G37*
G36*
G01X477180Y421170D02*
X476685Y421735D01*
X476968Y422018D01*
X477533Y421523D01*
X477675Y421382D01*
X477321Y421028D01*
X477180Y421170D01*
G37*
G36*
G01X466192Y411968D02*
X465432Y412318D01*
Y413218D01*
X466192Y413568D01*
X466392D01*
Y411968D01*
X466192D01*
G37*
G36*
G01X468091Y418096D02*
X468586Y417530D01*
X468303Y417248D01*
X467737Y417743D01*
X467596Y417884D01*
X467950Y418238D01*
X468091Y418096D01*
G37*
G36*
G01X468374Y418945D02*
X467879Y419510D01*
X468162Y419793D01*
X468727Y419298D01*
X468869Y419157D01*
X468515Y418803D01*
X468374Y418945D01*
G37*
G36*
G01X470212Y420783D02*
X469717Y421349D01*
X470000Y421632D01*
X470566Y421137D01*
X470707Y420995D01*
X470354Y420642D01*
X470212Y420783D01*
G37*
G36*
G01X469929Y419935D02*
X470424Y419369D01*
X470142Y419086D01*
X469576Y419581D01*
X469434Y419722D01*
X469788Y420076D01*
X469929Y419935D01*
G37*
G36*
G01X471768Y421773D02*
X472263Y421207D01*
X471980Y420925D01*
X471414Y421420D01*
X471273Y421561D01*
X471627Y421915D01*
X471768Y421773D01*
G37*
G36*
G01X473889Y424460D02*
X473394Y425026D01*
X473677Y425309D01*
X474243Y424814D01*
X474384Y424672D01*
X474031Y424319D01*
X473889Y424460D01*
G37*
G36*
G01X473606Y423612D02*
X474101Y423046D01*
X473819Y422763D01*
X473253Y423258D01*
X473111Y423399D01*
X473465Y423753D01*
X473606Y423612D01*
G37*
G36*
G01X472051Y422622D02*
X471556Y423187D01*
X471839Y423470D01*
X472404Y422975D01*
X472546Y422834D01*
X472192Y422480D01*
X472051Y422622D01*
G37*
G36*
G01X475728Y426299D02*
X475233Y426864D01*
X475516Y427147D01*
X476081Y426652D01*
X476223Y426511D01*
X475869Y426157D01*
X475728Y426299D01*
G37*
G36*
G01X475445Y425450D02*
X475940Y424884D01*
X475657Y424602D01*
X475091Y425096D01*
X474950Y425238D01*
X475303Y425591D01*
X475445Y425450D01*
G37*
G36*
G01X467342Y413568D02*
X468102Y413218D01*
Y412318D01*
X467342Y411968D01*
X467142D01*
Y413568D01*
X467342D01*
G37*
G36*
G01X469470Y417848D02*
X468975Y418414D01*
X469258Y418697D01*
X469824Y418202D01*
X469965Y418060D01*
X469612Y417707D01*
X469470Y417848D01*
G37*
G36*
G01X471026Y418838D02*
X471521Y418272D01*
X471238Y417990D01*
X470672Y418485D01*
X470531Y418626D01*
X470885Y418980D01*
X471026Y418838D01*
G37*
G36*
G01X472864Y420677D02*
X473359Y420111D01*
X473077Y419828D01*
X472511Y420323D01*
X472369Y420464D01*
X472723Y420818D01*
X472864Y420677D01*
G37*
G36*
G01X471309Y419687D02*
X470814Y420252D01*
X471097Y420535D01*
X471662Y420040D01*
X471804Y419899D01*
X471450Y419545D01*
X471309Y419687D01*
G37*
G36*
G01X473147Y421525D02*
X472652Y422091D01*
X472935Y422374D01*
X473501Y421879D01*
X473642Y421737D01*
X473289Y421384D01*
X473147Y421525D01*
G37*
G36*
G01X474703Y422515D02*
X475198Y421949D01*
X474915Y421667D01*
X474349Y422162D01*
X474208Y422303D01*
X474561Y422656D01*
X474703Y422515D01*
G37*
G36*
G01X476541Y424354D02*
X477036Y423788D01*
X476754Y423505D01*
X476188Y424000D01*
X476046Y424141D01*
X476400Y424495D01*
X476541Y424354D01*
G37*
G36*
G01X474986Y423364D02*
X474491Y423929D01*
X474774Y424212D01*
X475339Y423717D01*
X475481Y423576D01*
X475127Y423222D01*
X474986Y423364D01*
G37*
G36*
G01X476824Y425202D02*
X476329Y425768D01*
X476612Y426051D01*
X477178Y425556D01*
X477319Y425414D01*
X476966Y425061D01*
X476824Y425202D01*
G37*
G36*
G01X453597Y415912D02*
X454357Y415562D01*
Y414662D01*
X453597Y414312D01*
X453422D01*
Y415912D01*
X453597D01*
G37*
G36*
G01Y412012D02*
X454357Y411662D01*
Y410762D01*
X453597Y410412D01*
X453422D01*
Y412012D01*
X453597D01*
G37*
G36*
G01X453622Y417776D02*
X452872Y417826D01*
Y418226D01*
X453622Y418276D01*
X453822D01*
Y417776D01*
X453622D01*
G37*
G36*
G01Y420376D02*
X452872Y420426D01*
Y420826D01*
X453622Y420876D01*
X453822D01*
Y420376D01*
X453622D01*
G37*
G36*
G01X454022Y419576D02*
X454772Y419526D01*
Y419126D01*
X454022Y419076D01*
X453822D01*
Y419576D01*
X454022D01*
G37*
G36*
G01X453622Y428176D02*
X452872Y428226D01*
Y428626D01*
X453622Y428676D01*
X453822D01*
Y428176D01*
X453622D01*
G37*
G36*
G01Y422976D02*
X452872Y423026D01*
Y423426D01*
X453622Y423476D01*
X453822D01*
Y422976D01*
X453622D01*
G37*
G36*
G01X454022Y427376D02*
X454772Y427326D01*
Y426926D01*
X454022Y426876D01*
X453822D01*
Y427376D01*
X454022D01*
G37*
G36*
G01Y424776D02*
X454772Y424726D01*
Y424326D01*
X454022Y424276D01*
X453822D01*
Y424776D01*
X454022D01*
G37*
G36*
G01Y422176D02*
X454772Y422126D01*
Y421726D01*
X454022Y421676D01*
X453822D01*
Y422176D01*
X454022D01*
G37*
G36*
G01X458485Y433398D02*
X458980Y432832D01*
X458697Y432550D01*
X458131Y433045D01*
X457990Y433186D01*
X458344Y433540D01*
X458485Y433398D01*
G37*
G36*
G01X456647Y431560D02*
X457142Y430994D01*
X456859Y430711D01*
X456293Y431206D01*
X456152Y431348D01*
X456505Y431701D01*
X456647Y431560D01*
G37*
G36*
G01X454808Y429721D02*
X455303Y429156D01*
X455020Y428873D01*
X454454Y429368D01*
X454313Y429509D01*
X454667Y429863D01*
X454808Y429721D01*
G37*
G36*
G01X458768Y434247D02*
X458273Y434812D01*
X458556Y435095D01*
X459121Y434600D01*
X459263Y434459D01*
X458909Y434105D01*
X458768Y434247D01*
G37*
G36*
G01X456929Y432408D02*
X456434Y432974D01*
X456717Y433257D01*
X457283Y432762D01*
X457424Y432620D01*
X457071Y432267D01*
X456929Y432408D01*
G37*
G36*
G01X455091Y430570D02*
X454596Y431135D01*
X454879Y431418D01*
X455444Y430923D01*
X455586Y430782D01*
X455232Y430428D01*
X455091Y430570D01*
G37*
G36*
G01X453622Y425576D02*
X452872Y425626D01*
Y426026D01*
X453622Y426076D01*
X453822D01*
Y425576D01*
X453622D01*
G37*
G36*
G01X465839Y440752D02*
X466334Y440186D01*
X466051Y439904D01*
X465485Y440399D01*
X465344Y440540D01*
X465697Y440893D01*
X465839Y440752D01*
G37*
G36*
G01X467677Y442591D02*
X468172Y442025D01*
X467890Y441742D01*
X467324Y442237D01*
X467182Y442378D01*
X467536Y442732D01*
X467677Y442591D01*
G37*
G36*
G01X464000Y438914D02*
X464495Y438348D01*
X464213Y438065D01*
X463647Y438560D01*
X463505Y438701D01*
X463859Y439055D01*
X464000Y438914D01*
G37*
G36*
G01X462162Y437075D02*
X462657Y436509D01*
X462374Y436227D01*
X461808Y436722D01*
X461667Y436863D01*
X462021Y437217D01*
X462162Y437075D01*
G37*
G36*
G01X460323Y435237D02*
X460818Y434671D01*
X460536Y434388D01*
X459970Y434883D01*
X459829Y435025D01*
X460182Y435378D01*
X460323Y435237D01*
G37*
G36*
G01X464283Y439762D02*
X463788Y440328D01*
X464071Y440611D01*
X464637Y440116D01*
X464778Y439974D01*
X464425Y439621D01*
X464283Y439762D01*
G37*
G36*
G01X466122Y441601D02*
X465627Y442166D01*
X465910Y442449D01*
X466475Y441954D01*
X466617Y441813D01*
X466263Y441459D01*
X466122Y441601D01*
G37*
G36*
G01X462445Y437924D02*
X461950Y438489D01*
X462233Y438772D01*
X462798Y438277D01*
X462940Y438136D01*
X462586Y437782D01*
X462445Y437924D01*
G37*
G36*
G01X460606Y436085D02*
X460111Y436651D01*
X460394Y436934D01*
X460960Y436439D01*
X461101Y436297D01*
X460748Y435944D01*
X460606Y436085D01*
G37*
G36*
G01X467960Y443439D02*
X467465Y444005D01*
X467748Y444288D01*
X468314Y443793D01*
X468455Y443651D01*
X468102Y443298D01*
X467960Y443439D01*
G37*
G36*
G01X469516Y444429D02*
X470011Y443863D01*
X469728Y443580D01*
X469162Y444075D01*
X469021Y444217D01*
X469374Y444570D01*
X469516Y444429D01*
G37*
G36*
G01X473742Y412240D02*
X474502Y411890D01*
Y410990D01*
X473742Y410640D01*
X473542D01*
Y412240D01*
X473742D01*
G37*
G36*
G01X475697Y415299D02*
X475202Y415864D01*
X475485Y416147D01*
X476050Y415652D01*
X476192Y415511D01*
X475838Y415157D01*
X475697Y415299D01*
G37*
G36*
G01X477252Y416289D02*
X477747Y415723D01*
X477465Y415440D01*
X476899Y415935D01*
X476757Y416076D01*
X477111Y416430D01*
X477252Y416289D01*
G37*
G36*
G01X477535Y417137D02*
X477040Y417703D01*
X477323Y417986D01*
X477889Y417491D01*
X478030Y417349D01*
X477677Y416996D01*
X477535Y417137D01*
G37*
G36*
G01X455597Y414308D02*
X454837Y414658D01*
Y415558D01*
X455597Y415908D01*
X455772D01*
Y414308D01*
X455597D01*
G37*
G36*
G01Y410408D02*
X454837Y410758D01*
Y411658D01*
X455597Y412008D01*
X455772D01*
Y410408D01*
X455597D01*
G37*
G36*
G01X455172Y417776D02*
X454422Y417826D01*
Y418226D01*
X455172Y418276D01*
X455372D01*
Y417776D01*
X455172D01*
G37*
G36*
G01Y420376D02*
X454422Y420426D01*
Y420826D01*
X455172Y420876D01*
X455372D01*
Y420376D01*
X455172D01*
G37*
G36*
G01X455572Y419576D02*
X456322Y419526D01*
Y419126D01*
X455572Y419076D01*
X455372D01*
Y419576D01*
X455572D01*
G37*
G36*
G01X461420Y434140D02*
X461915Y433574D01*
X461633Y433291D01*
X461067Y433786D01*
X460926Y433928D01*
X461279Y434281D01*
X461420Y434140D01*
G37*
G36*
G01X459582Y432301D02*
X460077Y431735D01*
X459794Y431453D01*
X459228Y431948D01*
X459087Y432089D01*
X459441Y432443D01*
X459582Y432301D01*
G37*
G36*
G01X457744Y430463D02*
X458239Y429897D01*
X457956Y429614D01*
X457390Y430109D01*
X457249Y430251D01*
X457602Y430604D01*
X457744Y430463D01*
G37*
G36*
G01X459865Y433150D02*
X459370Y433715D01*
X459653Y433998D01*
X460218Y433503D01*
X460360Y433362D01*
X460006Y433008D01*
X459865Y433150D01*
G37*
G36*
G01X458026Y431311D02*
X457531Y431877D01*
X457814Y432160D01*
X458380Y431665D01*
X458521Y431523D01*
X458168Y431170D01*
X458026Y431311D01*
G37*
G36*
G01X456188Y429473D02*
X455693Y430038D01*
X455976Y430321D01*
X456541Y429826D01*
X456683Y429685D01*
X456329Y429331D01*
X456188Y429473D01*
G37*
G36*
G01X455172Y425576D02*
X454422Y425626D01*
Y426026D01*
X455172Y426076D01*
X455372D01*
Y425576D01*
X455172D01*
G37*
G36*
G01Y422976D02*
X454422Y423026D01*
Y423426D01*
X455172Y423476D01*
X455372D01*
Y422976D01*
X455172D01*
G37*
G36*
G01X455572Y427376D02*
X456322Y427326D01*
Y426926D01*
X455572Y426876D01*
X455372D01*
Y427376D01*
X455572D01*
G37*
G36*
G01Y424776D02*
X456322Y424726D01*
Y424326D01*
X455572Y424276D01*
X455372D01*
Y424776D01*
X455572D01*
G37*
G36*
G01Y422176D02*
X456322Y422126D01*
Y421726D01*
X455572Y421676D01*
X455372D01*
Y422176D01*
X455572D01*
G37*
G36*
G01X466936Y439655D02*
X467431Y439089D01*
X467148Y438807D01*
X466582Y439302D01*
X466441Y439443D01*
X466794Y439796D01*
X466936Y439655D01*
G37*
G36*
G01X468774Y441494D02*
X469269Y440928D01*
X468987Y440645D01*
X468421Y441140D01*
X468279Y441281D01*
X468633Y441635D01*
X468774Y441494D01*
G37*
G36*
G01X465097Y437817D02*
X465592Y437251D01*
X465310Y436968D01*
X464744Y437463D01*
X464602Y437604D01*
X464956Y437958D01*
X465097Y437817D01*
G37*
G36*
G01X463259Y435978D02*
X463754Y435412D01*
X463471Y435130D01*
X462905Y435625D01*
X462764Y435766D01*
X463118Y436120D01*
X463259Y435978D01*
G37*
G36*
G01X465380Y438665D02*
X464885Y439231D01*
X465168Y439514D01*
X465734Y439019D01*
X465875Y438877D01*
X465522Y438524D01*
X465380Y438665D01*
G37*
G36*
G01X467219Y440504D02*
X466724Y441069D01*
X467007Y441352D01*
X467572Y440857D01*
X467714Y440716D01*
X467360Y440362D01*
X467219Y440504D01*
G37*
G36*
G01X463542Y436827D02*
X463047Y437392D01*
X463330Y437675D01*
X463895Y437180D01*
X464037Y437039D01*
X463683Y436685D01*
X463542Y436827D01*
G37*
G36*
G01X461703Y434988D02*
X461208Y435554D01*
X461491Y435837D01*
X462057Y435342D01*
X462198Y435200D01*
X461845Y434847D01*
X461703Y434988D01*
G37*
G36*
G01X469057Y442342D02*
X468562Y442908D01*
X468845Y443191D01*
X469411Y442696D01*
X469552Y442554D01*
X469199Y442201D01*
X469057Y442342D01*
G37*
G36*
G01X470613Y443332D02*
X471108Y442766D01*
X470825Y442483D01*
X470259Y442978D01*
X470118Y443120D01*
X470471Y443473D01*
X470613Y443332D01*
G37*
G36*
G01X470896Y444181D02*
X470401Y444746D01*
X470684Y445029D01*
X471249Y444534D01*
X471391Y444393D01*
X471037Y444039D01*
X470896Y444181D01*
G37*
G36*
G01X478349Y415192D02*
X478844Y414626D01*
X478562Y414343D01*
X477996Y414838D01*
X477854Y414979D01*
X478208Y415333D01*
X478349Y415192D01*
G37*
G36*
G01X452497Y414312D02*
X451737Y414662D01*
Y415562D01*
X452497Y415912D01*
X452672D01*
Y414312D01*
X452497D01*
G37*
G36*
G01Y410412D02*
X451737Y410762D01*
Y411662D01*
X452497Y412012D01*
X452672D01*
Y410412D01*
X452497D01*
G37*
G36*
G01X452072Y417776D02*
X451322Y417826D01*
Y418226D01*
X452072Y418276D01*
X452272D01*
Y417776D01*
X452072D01*
G37*
G36*
G01Y420376D02*
X451322Y420426D01*
Y420826D01*
X452072Y420876D01*
X452272D01*
Y420376D01*
X452072D01*
G37*
G36*
G01X452472Y419576D02*
X453222Y419526D01*
Y419126D01*
X452472Y419076D01*
X452272D01*
Y419576D01*
X452472D01*
G37*
G36*
G01X452072Y425576D02*
X451322Y425626D01*
Y426026D01*
X452072Y426076D01*
X452272D01*
Y425576D01*
X452072D01*
G37*
G36*
G01Y428176D02*
X451322Y428226D01*
Y428626D01*
X452072Y428676D01*
X452272D01*
Y428176D01*
X452072D01*
G37*
G36*
G01Y422976D02*
X451322Y423026D01*
Y423426D01*
X452072Y423476D01*
X452272D01*
Y422976D01*
X452072D01*
G37*
G36*
G01X452472Y427376D02*
X453222Y427326D01*
Y426926D01*
X452472Y426876D01*
X452272D01*
Y427376D01*
X452472D01*
G37*
G36*
G01Y424776D02*
X453222Y424726D01*
Y424326D01*
X452472Y424276D01*
X452272D01*
Y424776D01*
X452472D01*
G37*
G36*
G01Y422176D02*
X453222Y422126D01*
Y421726D01*
X452472Y421676D01*
X452272D01*
Y422176D01*
X452472D01*
G37*
G36*
G01X457389Y434495D02*
X457883Y433929D01*
X457601Y433646D01*
X457035Y434141D01*
X456894Y434283D01*
X457247Y434636D01*
X457389Y434495D01*
G37*
G36*
G01X455550Y432656D02*
X456045Y432090D01*
X455762Y431808D01*
X455196Y432303D01*
X455055Y432444D01*
X455409Y432798D01*
X455550Y432656D01*
G37*
G36*
G01X453712Y430818D02*
X454207Y430252D01*
X453924Y429969D01*
X453358Y430464D01*
X453217Y430606D01*
X453570Y430959D01*
X453712Y430818D01*
G37*
G36*
G01X455833Y433505D02*
X455338Y434070D01*
X455621Y434353D01*
X456186Y433858D01*
X456328Y433717D01*
X455974Y433363D01*
X455833Y433505D01*
G37*
G36*
G01X453994Y431666D02*
X453499Y432232D01*
X453782Y432515D01*
X454348Y432020D01*
X454489Y431878D01*
X454136Y431525D01*
X453994Y431666D01*
G37*
G36*
G01X462904Y440010D02*
X463399Y439444D01*
X463116Y439162D01*
X462550Y439657D01*
X462409Y439798D01*
X462763Y440152D01*
X462904Y440010D01*
G37*
G36*
G01X464742Y441849D02*
X465237Y441283D01*
X464955Y441000D01*
X464389Y441495D01*
X464247Y441636D01*
X464601Y441990D01*
X464742Y441849D01*
G37*
G36*
G01X466581Y443687D02*
X467076Y443121D01*
X466793Y442839D01*
X466227Y443333D01*
X466086Y443475D01*
X466439Y443828D01*
X466581Y443687D01*
G37*
G36*
G01X461065Y438172D02*
X461560Y437606D01*
X461278Y437323D01*
X460712Y437818D01*
X460570Y437959D01*
X460924Y438313D01*
X461065Y438172D01*
G37*
G36*
G01X459227Y436333D02*
X459722Y435767D01*
X459439Y435485D01*
X458873Y435980D01*
X458732Y436121D01*
X459086Y436475D01*
X459227Y436333D01*
G37*
G36*
G01X461348Y439020D02*
X460853Y439586D01*
X461136Y439869D01*
X461702Y439374D01*
X461843Y439232D01*
X461490Y438879D01*
X461348Y439020D01*
G37*
G36*
G01X463187Y440859D02*
X462692Y441424D01*
X462975Y441707D01*
X463540Y441212D01*
X463682Y441071D01*
X463328Y440717D01*
X463187Y440859D01*
G37*
G36*
G01X465025Y442697D02*
X464530Y443263D01*
X464813Y443546D01*
X465379Y443051D01*
X465520Y442909D01*
X465167Y442556D01*
X465025Y442697D01*
G37*
G36*
G01X459510Y437182D02*
X459015Y437747D01*
X459298Y438030D01*
X459863Y437535D01*
X460005Y437394D01*
X459651Y437040D01*
X459510Y437182D01*
G37*
G36*
G01X457671Y435343D02*
X457176Y435909D01*
X457459Y436192D01*
X458025Y435697D01*
X458166Y435555D01*
X457813Y435202D01*
X457671Y435343D01*
G37*
G36*
G01X468419Y445526D02*
X468914Y444960D01*
X468632Y444677D01*
X468066Y445172D01*
X467924Y445313D01*
X468278Y445667D01*
X468419Y445526D01*
G37*
G36*
G01X472592Y410640D02*
X471832Y410990D01*
Y411890D01*
X472592Y412240D01*
X472792D01*
Y410640D01*
X472592D01*
G37*
G36*
G01X476155Y417386D02*
X476650Y416820D01*
X476368Y416537D01*
X475802Y417032D01*
X475660Y417173D01*
X476014Y417527D01*
X476155Y417386D01*
G37*
G36*
G01X474600Y416396D02*
X474105Y416961D01*
X474388Y417244D01*
X474953Y416749D01*
X475095Y416608D01*
X474741Y416254D01*
X474600Y416396D01*
G37*
G36*
G01X476438Y418234D02*
X475943Y418800D01*
X476226Y419083D01*
X476792Y418588D01*
X476933Y418446D01*
X476580Y418093D01*
X476438Y418234D01*
G37*
G36*
G01X478277Y420073D02*
X477782Y420638D01*
X478065Y420921D01*
X478630Y420426D01*
X478772Y420285D01*
X478418Y419931D01*
X478277Y420073D01*
G37*
G36*
G01X477994Y419224D02*
X478489Y418658D01*
X478206Y418376D01*
X477640Y418871D01*
X477499Y419012D01*
X477852Y419365D01*
X477994Y419224D01*
G37*
G36*
G01X456697Y415908D02*
X457457Y415558D01*
Y414658D01*
X456697Y414308D01*
X456522D01*
Y415908D01*
X456697D01*
G37*
G36*
G01Y412008D02*
X457457Y411658D01*
Y410758D01*
X456697Y410408D01*
X456522D01*
Y412008D01*
X456697D01*
G37*
G36*
G01X456722Y417776D02*
X455972Y417826D01*
Y418226D01*
X456722Y418276D01*
X456922D01*
Y417776D01*
X456722D01*
G37*
G36*
G01Y420376D02*
X455972Y420426D01*
Y420826D01*
X456722Y420876D01*
X456922D01*
Y420376D01*
X456722D01*
G37*
G36*
G01X457122Y419576D02*
X457872Y419526D01*
Y419126D01*
X457122Y419076D01*
X456922D01*
Y419576D01*
X457122D01*
G37*
G36*
G01X456722Y425576D02*
X455972Y425626D01*
Y426026D01*
X456722Y426076D01*
X456922D01*
Y425576D01*
X456722D01*
G37*
G36*
G01Y422976D02*
X455972Y423026D01*
Y423426D01*
X456722Y423476D01*
X456922D01*
Y422976D01*
X456722D01*
G37*
G36*
G01X457122Y424776D02*
X457872Y424726D01*
Y424326D01*
X457122Y424276D01*
X456922D01*
Y424776D01*
X457122D01*
G37*
G36*
G01Y422176D02*
X457872Y422126D01*
Y421726D01*
X457122Y421676D01*
X456922D01*
Y422176D01*
X457122D01*
G37*
G36*
G01X464355Y434882D02*
X464850Y434316D01*
X464568Y434033D01*
X464002Y434528D01*
X463860Y434669D01*
X464214Y435023D01*
X464355Y434882D01*
G37*
G36*
G01X462517Y433043D02*
X463012Y432477D01*
X462729Y432195D01*
X462163Y432690D01*
X462022Y432831D01*
X462376Y433185D01*
X462517Y433043D01*
G37*
G36*
G01X460679Y431205D02*
X461173Y430639D01*
X460891Y430356D01*
X460325Y430851D01*
X460184Y430993D01*
X460537Y431346D01*
X460679Y431205D01*
G37*
G36*
G01X458840Y429366D02*
X459335Y428800D01*
X459052Y428518D01*
X458486Y429013D01*
X458345Y429154D01*
X458699Y429508D01*
X458840Y429366D01*
G37*
G36*
G01X462800Y433892D02*
X462305Y434457D01*
X462588Y434740D01*
X463153Y434245D01*
X463295Y434104D01*
X462941Y433750D01*
X462800Y433892D01*
G37*
G36*
G01X460961Y432053D02*
X460466Y432619D01*
X460749Y432902D01*
X461315Y432407D01*
X461456Y432265D01*
X461103Y431912D01*
X460961Y432053D01*
G37*
G36*
G01X459123Y430215D02*
X458628Y430780D01*
X458911Y431063D01*
X459476Y430568D01*
X459618Y430427D01*
X459264Y430073D01*
X459123Y430215D01*
G37*
G36*
G01X457284Y428376D02*
X456789Y428942D01*
X457072Y429225D01*
X457638Y428730D01*
X457779Y428588D01*
X457426Y428235D01*
X457284Y428376D01*
G37*
G36*
G01X468032Y438559D02*
X468527Y437993D01*
X468245Y437710D01*
X467679Y438205D01*
X467537Y438346D01*
X467891Y438700D01*
X468032Y438559D01*
G37*
G36*
G01X466194Y436720D02*
X466689Y436154D01*
X466406Y435872D01*
X465840Y436367D01*
X465699Y436508D01*
X466053Y436862D01*
X466194Y436720D01*
G37*
G36*
G01X466477Y437569D02*
X465982Y438134D01*
X466265Y438417D01*
X466830Y437922D01*
X466972Y437781D01*
X466618Y437427D01*
X466477Y437569D01*
G37*
G36*
G01X468315Y439407D02*
X467820Y439973D01*
X468103Y440256D01*
X468669Y439761D01*
X468810Y439619D01*
X468457Y439266D01*
X468315Y439407D01*
G37*
G36*
G01X464638Y435730D02*
X464143Y436296D01*
X464426Y436579D01*
X464992Y436084D01*
X465133Y435942D01*
X464780Y435589D01*
X464638Y435730D01*
G37*
G36*
G01X469871Y440397D02*
X470366Y439831D01*
X470083Y439549D01*
X469517Y440043D01*
X469376Y440185D01*
X469729Y440538D01*
X469871Y440397D01*
G37*
G36*
G01X471709Y442236D02*
X472204Y441670D01*
X471922Y441387D01*
X471356Y441882D01*
X471214Y442023D01*
X471568Y442377D01*
X471709Y442236D01*
G37*
G36*
G01X470154Y441246D02*
X469659Y441811D01*
X469942Y442094D01*
X470507Y441599D01*
X470649Y441458D01*
X470295Y441104D01*
X470154Y441246D01*
G37*
G36*
G01X471992Y443084D02*
X471497Y443650D01*
X471780Y443933D01*
X472346Y443438D01*
X472487Y443296D01*
X472134Y442943D01*
X471992Y443084D01*
G37*
G36*
G01X446419Y584138D02*
X446290Y584267D01*
Y585143D01*
X446289Y585144D01*
Y586311D01*
X445500Y587100D01*
Y592278D01*
X446285Y593063D01*
Y594140D01*
X446602Y594457D01*
X449695D01*
G02X450090Y593994I0J-400D01*
G03X452382Y592491I1483J-237D01*
G02X452997Y592154I215J-337D01*
G01Y584927D01*
X452208Y584138D01*
X446419D01*
G37*
G36*
G01X445787Y548991D02*
Y554722D01*
X446312Y555247D01*
Y556367D01*
X446602Y556657D01*
X449695D01*
G02X450090Y556194I0J-400D01*
G03X452382Y554691I1483J-237D01*
G02X452997Y554354I215J-337D01*
G01Y547127D01*
X452208Y546338D01*
X446602D01*
X445938Y547002D01*
G03X445787Y548991I-1058J920D01*
G37*
G36*
G01X429503Y584134D02*
G02X429194Y584787I1J400D01*
G03X429176Y586676I-1045J935D01*
G02X429469Y587348I293J272D01*
G01X432402D01*
Y588498D01*
X432855D01*
X432894Y588480D01*
G03Y591120I606J1320D01*
G01X432855Y591102D01*
X432402D01*
Y592573D01*
G03X432861Y593954I-908J1069D01*
G02X433251Y594443I390J89D01*
G01X436427D01*
G02X436817Y593958I-1J-400D01*
G03X439557I1370J-299D01*
G02X439947Y594443I391J85D01*
G01X442229D01*
X443026Y593646D01*
Y592484D01*
X442830Y592288D01*
X440282D01*
X439764Y591770D01*
X438774D01*
X438725Y591721D01*
Y587824D01*
X439256Y587293D01*
X442984D01*
X443026Y587251D01*
Y584875D01*
X442285Y584134D01*
X439543D01*
G02X439234Y584787I1J400D01*
G03X437144I-1045J935D01*
G02X436835Y584134I-310J-253D01*
G01X436196D01*
G02X435887Y584787I1J400D01*
G03X433797I-1045J935D01*
G02X433488Y584134I-310J-253D01*
G01X429503D01*
G37*
G36*
G01Y546334D02*
G02X429194Y546987I1J400D01*
G03X429176Y548876I-1045J935D01*
G02X429469Y549548I293J272D01*
G01X432402D01*
Y550698D01*
X432863D01*
X432902Y550680D01*
G03Y553320I606J1320D01*
G01X432863Y553302D01*
X432402D01*
Y554773D01*
G03X432861Y556154I-908J1069D01*
G02X433251Y556643I390J89D01*
G01X436427D01*
G02X436817Y556158I-1J-400D01*
G03X439557I1370J-299D01*
G02X439947Y556643I391J85D01*
G01X442229D01*
X443026Y555846D01*
Y554452D01*
X440256D01*
Y554002D01*
Y553952D01*
X438756D01*
Y553502D01*
Y550498D01*
Y550048D01*
X440256D01*
Y549998D01*
Y549548D01*
X443026D01*
Y547075D01*
X442285Y546334D01*
X439543D01*
G02X439234Y546987I1J400D01*
G03X437144I-1045J935D01*
G02X436835Y546334I-310J-253D01*
G01X436196D01*
G02X435887Y546987I1J400D01*
G03X433797I-1045J935D01*
G02X433488Y546334I-310J-253D01*
G01X429503D01*
G37*
G36*
G01X479370Y167013D02*
X479935Y167508D01*
X480218Y167225D01*
X479723Y166660D01*
X479582Y166518D01*
X479228Y166872D01*
X479370Y167013D01*
G37*
G36*
G01X478627Y169948D02*
X479193Y170443D01*
X479476Y170160D01*
X478981Y169594D01*
X478839Y169453D01*
X478486Y169806D01*
X478627Y169948D01*
G37*
G36*
G01X480466Y168110D02*
X481032Y168605D01*
X481315Y168322D01*
X480820Y167756D01*
X480678Y167615D01*
X480325Y167968D01*
X480466Y168110D01*
G37*
G36*
G01X479618Y168392D02*
X479052Y167897D01*
X478769Y168180D01*
X479264Y168746D01*
X479406Y168887D01*
X479759Y168534D01*
X479618Y168392D01*
G37*
G36*
G01X478088Y181017D02*
X478654Y181512D01*
X478936Y181229D01*
X478441Y180663D01*
X478300Y180522D01*
X477946Y180876D01*
X478088Y181017D01*
G37*
G36*
G01X479926Y179179D02*
X480492Y179674D01*
X480775Y179391D01*
X480280Y178825D01*
X480138Y178684D01*
X479785Y179037D01*
X479926Y179179D01*
G37*
G36*
G01X479078Y179461D02*
X478512Y178966D01*
X478229Y179249D01*
X478724Y179815D01*
X478866Y179956D01*
X479219Y179603D01*
X479078Y179461D01*
G37*
G36*
G01X482435Y178106D02*
X482485Y178856D01*
X482885D01*
X482935Y178106D01*
Y177906D01*
X482435D01*
Y178106D01*
G37*
G36*
G01X486835Y177706D02*
X486785Y176956D01*
X486385D01*
X486335Y177706D01*
Y177906D01*
X486835D01*
Y177706D01*
G37*
G36*
G01X484235D02*
X484185Y176956D01*
X483785D01*
X483735Y177706D01*
Y177906D01*
X484235D01*
Y177706D01*
G37*
G36*
G01X485035Y178106D02*
X485085Y178856D01*
X485485D01*
X485535Y178106D01*
Y177906D01*
X485035D01*
Y178106D01*
G37*
G36*
G01X492035Y177706D02*
X491985Y176956D01*
X491585D01*
X491535Y177706D01*
Y177906D01*
X492035D01*
Y177706D01*
G37*
G36*
G01X492835Y178106D02*
X492885Y178856D01*
X493285D01*
X493335Y178106D01*
Y177906D01*
X492835D01*
Y178106D01*
G37*
G36*
G01X490235D02*
X490285Y178856D01*
X490685D01*
X490735Y178106D01*
Y177906D01*
X490235D01*
Y178106D01*
G37*
G36*
G01X489435Y177706D02*
X489385Y176956D01*
X488985D01*
X488935Y177706D01*
Y177906D01*
X489435D01*
Y177706D01*
G37*
G36*
G01X487635Y178106D02*
X487685Y178856D01*
X488085D01*
X488135Y178106D01*
Y177906D01*
X487635D01*
Y178106D01*
G37*
G36*
G01X497235Y177706D02*
X497185Y176956D01*
X496785D01*
X496735Y177706D01*
Y177906D01*
X497235D01*
Y177706D01*
G37*
G36*
G01X499835D02*
X499785Y176956D01*
X499385D01*
X499335Y177706D01*
Y177906D01*
X499835D01*
Y177706D01*
G37*
G36*
G01X494635D02*
X494585Y176956D01*
X494185D01*
X494135Y177706D01*
Y177906D01*
X494635D01*
Y177706D01*
G37*
G36*
G01X495435Y178106D02*
X495485Y178856D01*
X495885D01*
X495935Y178106D01*
Y177906D01*
X495435D01*
Y178106D01*
G37*
G36*
G01X498035D02*
X498085Y178856D01*
X498485D01*
X498535Y178106D01*
Y177906D01*
X498035D01*
Y178106D01*
G37*
G36*
G01X502435Y177706D02*
X502385Y176956D01*
X501985D01*
X501935Y177706D01*
Y177906D01*
X502435D01*
Y177706D01*
G37*
G36*
G01X505035D02*
X504985Y176956D01*
X504585D01*
X504535Y177706D01*
Y177906D01*
X505035D01*
Y177706D01*
G37*
G36*
G01X500635Y178106D02*
X500685Y178856D01*
X501085D01*
X501135Y178106D01*
Y177906D01*
X500635D01*
Y178106D01*
G37*
G36*
G01X503235D02*
X503285Y178856D01*
X503685D01*
X503735Y178106D01*
Y177906D01*
X503235D01*
Y178106D01*
G37*
G36*
G01X505835D02*
X505885Y178856D01*
X506285D01*
X506335Y178106D01*
Y177906D01*
X505835D01*
Y178106D01*
G37*
G36*
G01X508842Y176607D02*
X508277Y176112D01*
X507994Y176395D01*
X508489Y176960D01*
X508630Y177102D01*
X508984Y176748D01*
X508842Y176607D01*
G37*
G36*
G01X509691Y176324D02*
X510257Y176819D01*
X510539Y176536D01*
X510045Y175970D01*
X509903Y175829D01*
X509550Y176182D01*
X509691Y176324D01*
G37*
G36*
G01X511529Y174485D02*
X512095Y174980D01*
X512378Y174698D01*
X511883Y174132D01*
X511742Y173990D01*
X511388Y174344D01*
X511529Y174485D01*
G37*
G36*
G01X512519Y172930D02*
X511954Y172435D01*
X511671Y172718D01*
X512166Y173283D01*
X512307Y173425D01*
X512661Y173071D01*
X512519Y172930D01*
G37*
G36*
G01X510681Y174768D02*
X510115Y174273D01*
X509832Y174556D01*
X510327Y175122D01*
X510469Y175263D01*
X510822Y174910D01*
X510681Y174768D01*
G37*
G36*
G01X513368Y172647D02*
X513934Y173142D01*
X514216Y172859D01*
X513721Y172293D01*
X513580Y172152D01*
X513226Y172506D01*
X513368Y172647D01*
G37*
G36*
G01X515206Y170808D02*
X515772Y171303D01*
X516055Y171021D01*
X515560Y170455D01*
X515419Y170313D01*
X515065Y170667D01*
X515206Y170808D01*
G37*
G36*
G01X514358Y171091D02*
X513792Y170596D01*
X513509Y170879D01*
X514004Y171445D01*
X514146Y171586D01*
X514499Y171233D01*
X514358Y171091D01*
G37*
G36*
G01X479184Y182114D02*
X479750Y182608D01*
X480033Y182326D01*
X479538Y181760D01*
X479396Y181619D01*
X479043Y181972D01*
X479184Y182114D01*
G37*
G36*
G01X481023Y180275D02*
X481589Y180770D01*
X481871Y180487D01*
X481376Y179921D01*
X481235Y179780D01*
X480881Y180134D01*
X481023Y180275D01*
G37*
G36*
G01X480174Y180558D02*
X479609Y180063D01*
X479326Y180346D01*
X479821Y180911D01*
X479962Y181053D01*
X480316Y180699D01*
X480174Y180558D01*
G37*
G36*
G01X482435Y179656D02*
X482485Y180406D01*
X482885D01*
X482935Y179656D01*
Y179456D01*
X482435D01*
Y179656D01*
G37*
G36*
G01X486835Y179256D02*
X486785Y178506D01*
X486385D01*
X486335Y179256D01*
Y179456D01*
X486835D01*
Y179256D01*
G37*
G36*
G01X484235D02*
X484185Y178506D01*
X483785D01*
X483735Y179256D01*
Y179456D01*
X484235D01*
Y179256D01*
G37*
G36*
G01X485035Y179656D02*
X485085Y180406D01*
X485485D01*
X485535Y179656D01*
Y179456D01*
X485035D01*
Y179656D01*
G37*
G36*
G01X492035Y179256D02*
X491985Y178506D01*
X491585D01*
X491535Y179256D01*
Y179456D01*
X492035D01*
Y179256D01*
G37*
G36*
G01X492835Y179656D02*
X492885Y180406D01*
X493285D01*
X493335Y179656D01*
Y179456D01*
X492835D01*
Y179656D01*
G37*
G36*
G01X490235D02*
X490285Y180406D01*
X490685D01*
X490735Y179656D01*
Y179456D01*
X490235D01*
Y179656D01*
G37*
G36*
G01X489435Y179256D02*
X489385Y178506D01*
X488985D01*
X488935Y179256D01*
Y179456D01*
X489435D01*
Y179256D01*
G37*
G36*
G01X487635Y179656D02*
X487685Y180406D01*
X488085D01*
X488135Y179656D01*
Y179456D01*
X487635D01*
Y179656D01*
G37*
G36*
G01X497235Y179256D02*
X497185Y178506D01*
X496785D01*
X496735Y179256D01*
Y179456D01*
X497235D01*
Y179256D01*
G37*
G36*
G01X499835D02*
X499785Y178506D01*
X499385D01*
X499335Y179256D01*
Y179456D01*
X499835D01*
Y179256D01*
G37*
G36*
G01X494635D02*
X494585Y178506D01*
X494185D01*
X494135Y179256D01*
Y179456D01*
X494635D01*
Y179256D01*
G37*
G36*
G01X495435Y179656D02*
X495485Y180406D01*
X495885D01*
X495935Y179656D01*
Y179456D01*
X495435D01*
Y179656D01*
G37*
G36*
G01X498035D02*
X498085Y180406D01*
X498485D01*
X498535Y179656D01*
Y179456D01*
X498035D01*
Y179656D01*
G37*
G36*
G01X502435Y179256D02*
X502385Y178506D01*
X501985D01*
X501935Y179256D01*
Y179456D01*
X502435D01*
Y179256D01*
G37*
G36*
G01X505035D02*
X504985Y178506D01*
X504585D01*
X504535Y179256D01*
Y179456D01*
X505035D01*
Y179256D01*
G37*
G36*
G01X507635D02*
X507585Y178506D01*
X507185D01*
X507135Y179256D01*
Y179456D01*
X507635D01*
Y179256D01*
G37*
G36*
G01X500635Y179656D02*
X500685Y180406D01*
X501085D01*
X501135Y179656D01*
Y179456D01*
X500635D01*
Y179656D01*
G37*
G36*
G01X503235D02*
X503285Y180406D01*
X503685D01*
X503735Y179656D01*
Y179456D01*
X503235D01*
Y179656D01*
G37*
G36*
G01X505835D02*
X505885Y180406D01*
X506285D01*
X506335Y179656D01*
Y179456D01*
X505835D01*
Y179656D01*
G37*
G36*
G01X511777Y175865D02*
X511212Y175370D01*
X510929Y175653D01*
X511424Y176218D01*
X511565Y176360D01*
X511919Y176006D01*
X511777Y175865D01*
G37*
G36*
G01X508949Y179259D02*
X509515Y179754D01*
X509798Y179471D01*
X509303Y178905D01*
X509161Y178764D01*
X508808Y179117D01*
X508949Y179259D01*
G37*
G36*
G01X509939Y177703D02*
X509373Y177208D01*
X509090Y177491D01*
X509585Y178057D01*
X509727Y178198D01*
X510080Y177845D01*
X509939Y177703D01*
G37*
G36*
G01X510787Y177420D02*
X511353Y177915D01*
X511636Y177633D01*
X511141Y177067D01*
X511000Y176925D01*
X510646Y177279D01*
X510787Y177420D01*
G37*
G36*
G01X516303Y171905D02*
X516869Y172400D01*
X517151Y172117D01*
X516656Y171551D01*
X516515Y171410D01*
X516161Y171764D01*
X516303Y171905D01*
G37*
G36*
G01X515454Y172188D02*
X514889Y171693D01*
X514606Y171976D01*
X515101Y172541D01*
X515242Y172683D01*
X515596Y172329D01*
X515454Y172188D01*
G37*
G36*
G01X518141Y170066D02*
X518707Y170561D01*
X518990Y170279D01*
X518495Y169713D01*
X518353Y169572D01*
X518000Y169925D01*
X518141Y170066D01*
G37*
G36*
G01X513616Y174026D02*
X513050Y173531D01*
X512767Y173814D01*
X513262Y174380D01*
X513404Y174521D01*
X513757Y174168D01*
X513616Y174026D01*
G37*
G36*
G01X514464Y173743D02*
X515030Y174238D01*
X515313Y173956D01*
X514818Y173390D01*
X514677Y173248D01*
X514323Y173602D01*
X514464Y173743D01*
G37*
G36*
G01X512626Y175582D02*
X513192Y176077D01*
X513474Y175794D01*
X512979Y175228D01*
X512838Y175087D01*
X512485Y175440D01*
X512626Y175582D01*
G37*
G36*
G01X484173Y191910D02*
X483607Y191415D01*
X483324Y191698D01*
X483819Y192264D01*
X483961Y192405D01*
X484314Y192052D01*
X484173Y191910D01*
G37*
G36*
G01X486835Y190106D02*
X486785Y189356D01*
X486385D01*
X486335Y190106D01*
Y190306D01*
X486835D01*
Y190106D01*
G37*
G36*
G01X482334Y193749D02*
X481769Y193254D01*
X481486Y193537D01*
X481981Y194102D01*
X482122Y194244D01*
X482476Y193890D01*
X482334Y193749D01*
G37*
G36*
G01X480496Y195587D02*
X479930Y195092D01*
X479647Y195375D01*
X480142Y195941D01*
X480284Y196082D01*
X480637Y195729D01*
X480496Y195587D01*
G37*
G36*
G01X483183Y193466D02*
X483749Y193961D01*
X484031Y193678D01*
X483536Y193112D01*
X483395Y192971D01*
X483041Y193325D01*
X483183Y193466D01*
G37*
G36*
G01X481344Y195304D02*
X481910Y195799D01*
X482193Y195517D01*
X481698Y194951D01*
X481557Y194809D01*
X481203Y195163D01*
X481344Y195304D01*
G37*
G36*
G01X479506Y197143D02*
X480072Y197638D01*
X480354Y197355D01*
X479859Y196789D01*
X479718Y196648D01*
X479365Y197001D01*
X479506Y197143D01*
G37*
G36*
G01X485021Y191627D02*
X485587Y192122D01*
X485870Y191840D01*
X485375Y191274D01*
X485233Y191133D01*
X484880Y191486D01*
X485021Y191627D01*
G37*
G36*
G01X489435Y190106D02*
X489385Y189356D01*
X488985D01*
X488935Y190106D01*
Y190306D01*
X489435D01*
Y190106D01*
G37*
G36*
G01X487635Y190506D02*
X487685Y191256D01*
X488085D01*
X488135Y190506D01*
Y190306D01*
X487635D01*
Y190506D01*
G37*
G36*
G01X492835D02*
X492885Y191256D01*
X493285D01*
X493335Y190506D01*
Y190306D01*
X492835D01*
Y190506D01*
G37*
G36*
G01X490235D02*
X490285Y191256D01*
X490685D01*
X490735Y190506D01*
Y190306D01*
X490235D01*
Y190506D01*
G37*
G36*
G01X492035Y190106D02*
X491985Y189356D01*
X491585D01*
X491535Y190106D01*
Y190306D01*
X492035D01*
Y190106D01*
G37*
G36*
G01X499835D02*
X499785Y189356D01*
X499385D01*
X499335Y190106D01*
Y190306D01*
X499835D01*
Y190106D01*
G37*
G36*
G01X497235D02*
X497185Y189356D01*
X496785D01*
X496735Y190106D01*
Y190306D01*
X497235D01*
Y190106D01*
G37*
G36*
G01X494635D02*
X494585Y189356D01*
X494185D01*
X494135Y190106D01*
Y190306D01*
X494635D01*
Y190106D01*
G37*
G36*
G01X498035Y190506D02*
X498085Y191256D01*
X498485D01*
X498535Y190506D01*
Y190306D01*
X498035D01*
Y190506D01*
G37*
G36*
G01X495435D02*
X495485Y191256D01*
X495885D01*
X495935Y190506D01*
Y190306D01*
X495435D01*
Y190506D01*
G37*
G36*
G01X500635D02*
X500685Y191256D01*
X501085D01*
X501135Y190506D01*
Y190306D01*
X500635D01*
Y190506D01*
G37*
G36*
G01X503235D02*
X503285Y191256D01*
X503685D01*
X503735Y190506D01*
Y190306D01*
X503235D01*
Y190506D01*
G37*
G36*
G01X505835D02*
X505885Y191256D01*
X506285D01*
X506335Y190506D01*
Y190306D01*
X505835D01*
Y190506D01*
G37*
G36*
G01X502435Y190106D02*
X502385Y189356D01*
X501985D01*
X501935Y190106D01*
Y190306D01*
X502435D01*
Y190106D01*
G37*
G36*
G01X505035D02*
X504985Y189356D01*
X504585D01*
X504535Y190106D01*
Y190306D01*
X505035D01*
Y190106D01*
G37*
G36*
G01X507635D02*
X507585Y189356D01*
X507185D01*
X507135Y190106D01*
Y190306D01*
X507635D01*
Y190106D01*
G37*
G36*
G01X508435Y190506D02*
X508485Y191256D01*
X508885D01*
X508935Y190506D01*
Y190306D01*
X508435D01*
Y190506D01*
G37*
G36*
G01X510235Y190106D02*
X510185Y189356D01*
X509785D01*
X509735Y190106D01*
Y190306D01*
X510235D01*
Y190106D01*
G37*
G36*
G01X511035Y190506D02*
X511085Y191256D01*
X511485D01*
X511535Y190506D01*
Y190306D01*
X511035D01*
Y190506D01*
G37*
G36*
G01X529494Y174065D02*
X530060Y174560D01*
X530342Y174277D01*
X529847Y173711D01*
X529706Y173570D01*
X529352Y173924D01*
X529494Y174065D01*
G37*
G36*
G01X514786Y188773D02*
X515352Y189268D01*
X515635Y188985D01*
X515140Y188419D01*
X514998Y188278D01*
X514645Y188631D01*
X514786Y188773D01*
G37*
G36*
G01X515776Y187217D02*
X515210Y186722D01*
X514927Y187005D01*
X515422Y187571D01*
X515564Y187712D01*
X515917Y187359D01*
X515776Y187217D01*
G37*
G36*
G01X513937Y189056D02*
X513372Y188561D01*
X513089Y188844D01*
X513584Y189409D01*
X513725Y189551D01*
X514079Y189197D01*
X513937Y189056D01*
G37*
G36*
G01X518463Y185096D02*
X519029Y185591D01*
X519311Y185308D01*
X518817Y184742D01*
X518675Y184601D01*
X518322Y184954D01*
X518463Y185096D01*
G37*
G36*
G01X516624Y186934D02*
X517190Y187429D01*
X517473Y187147D01*
X516978Y186581D01*
X516837Y186439D01*
X516483Y186793D01*
X516624Y186934D01*
G37*
G36*
G01X519453Y183540D02*
X518887Y183045D01*
X518604Y183328D01*
X519099Y183894D01*
X519241Y184035D01*
X519594Y183682D01*
X519453Y183540D01*
G37*
G36*
G01X517614Y185379D02*
X517049Y184884D01*
X516766Y185167D01*
X517261Y185732D01*
X517402Y185874D01*
X517756Y185520D01*
X517614Y185379D01*
G37*
G36*
G01X527655Y175904D02*
X528221Y176398D01*
X528504Y176116D01*
X528009Y175550D01*
X527867Y175409D01*
X527514Y175762D01*
X527655Y175904D01*
G37*
G36*
G01X526807Y176186D02*
X526241Y175691D01*
X525958Y175974D01*
X526453Y176540D01*
X526595Y176681D01*
X526948Y176328D01*
X526807Y176186D01*
G37*
G36*
G01X528645Y174348D02*
X528080Y173853D01*
X527797Y174136D01*
X528292Y174701D01*
X528433Y174843D01*
X528787Y174489D01*
X528645Y174348D01*
G37*
G36*
G01X523978Y179580D02*
X524544Y180075D01*
X524827Y179793D01*
X524332Y179227D01*
X524191Y179085D01*
X523837Y179439D01*
X523978Y179580D01*
G37*
G36*
G01X524968Y178025D02*
X524403Y177530D01*
X524120Y177813D01*
X524615Y178378D01*
X524756Y178520D01*
X525110Y178166D01*
X524968Y178025D01*
G37*
G36*
G01X525817Y177742D02*
X526383Y178237D01*
X526665Y177954D01*
X526170Y177388D01*
X526029Y177247D01*
X525675Y177601D01*
X525817Y177742D01*
G37*
G36*
G01X520301Y183257D02*
X520867Y183752D01*
X521150Y183470D01*
X520655Y182904D01*
X520514Y182762D01*
X520160Y183116D01*
X520301Y183257D01*
G37*
G36*
G01X521291Y181702D02*
X520726Y181207D01*
X520443Y181490D01*
X520938Y182055D01*
X521079Y182197D01*
X521433Y181843D01*
X521291Y181702D01*
G37*
G36*
G01X522140Y181419D02*
X522706Y181914D01*
X522988Y181631D01*
X522493Y181065D01*
X522352Y180924D01*
X521998Y181278D01*
X522140Y181419D01*
G37*
G36*
G01X523130Y179863D02*
X522564Y179368D01*
X522281Y179651D01*
X522776Y180217D01*
X522918Y180358D01*
X523271Y180005D01*
X523130Y179863D01*
G37*
G36*
G01X482441Y196401D02*
X483007Y196896D01*
X483289Y196613D01*
X482794Y196047D01*
X482653Y195906D01*
X482299Y196260D01*
X482441Y196401D01*
G37*
G36*
G01X481592Y196684D02*
X481027Y196189D01*
X480744Y196472D01*
X481239Y197037D01*
X481380Y197179D01*
X481734Y196825D01*
X481592Y196684D01*
G37*
G36*
G01X483431Y194845D02*
X482865Y194350D01*
X482582Y194633D01*
X483077Y195199D01*
X483219Y195340D01*
X483572Y194987D01*
X483431Y194845D01*
G37*
G36*
G01X480602Y198239D02*
X481168Y198734D01*
X481451Y198452D01*
X480956Y197886D01*
X480815Y197744D01*
X480461Y198098D01*
X480602Y198239D01*
G37*
G36*
G01X484279Y194562D02*
X484845Y195057D01*
X485128Y194775D01*
X484633Y194209D01*
X484492Y194067D01*
X484138Y194421D01*
X484279Y194562D01*
G37*
G36*
G01X486118Y192724D02*
X486684Y193219D01*
X486966Y192936D01*
X486471Y192370D01*
X486330Y192229D01*
X485976Y192583D01*
X486118Y192724D01*
G37*
G36*
G01X485269Y193007D02*
X484704Y192512D01*
X484421Y192795D01*
X484916Y193360D01*
X485057Y193502D01*
X485411Y193148D01*
X485269Y193007D01*
G37*
G36*
G01X479169Y201173D02*
X479839Y200823D01*
Y199953D01*
X479169Y199603D01*
X478994D01*
Y201173D01*
X479169D01*
G37*
G36*
G01X487635Y192056D02*
X487685Y192806D01*
X488085D01*
X488135Y192056D01*
Y191856D01*
X487635D01*
Y192056D01*
G37*
G36*
G01X489435Y191656D02*
X489385Y190906D01*
X488985D01*
X488935Y191656D01*
Y191856D01*
X489435D01*
Y191656D01*
G37*
G36*
G01X492835Y192056D02*
X492885Y192806D01*
X493285D01*
X493335Y192056D01*
Y191856D01*
X492835D01*
Y192056D01*
G37*
G36*
G01X490235D02*
X490285Y192806D01*
X490685D01*
X490735Y192056D01*
Y191856D01*
X490235D01*
Y192056D01*
G37*
G36*
G01X492035Y191656D02*
X491985Y190906D01*
X491585D01*
X491535Y191656D01*
Y191856D01*
X492035D01*
Y191656D01*
G37*
G36*
G01X495435Y192056D02*
X495485Y192806D01*
X495885D01*
X495935Y192056D01*
Y191856D01*
X495435D01*
Y192056D01*
G37*
G36*
G01X498035D02*
X498085Y192806D01*
X498485D01*
X498535Y192056D01*
Y191856D01*
X498035D01*
Y192056D01*
G37*
G36*
G01X497235Y191656D02*
X497185Y190906D01*
X496785D01*
X496735Y191656D01*
Y191856D01*
X497235D01*
Y191656D01*
G37*
G36*
G01X494635D02*
X494585Y190906D01*
X494185D01*
X494135Y191656D01*
Y191856D01*
X494635D01*
Y191656D01*
G37*
G36*
G01X499835D02*
X499785Y190906D01*
X499385D01*
X499335Y191656D01*
Y191856D01*
X499835D01*
Y191656D01*
G37*
G36*
G01X500635Y192056D02*
X500685Y192806D01*
X501085D01*
X501135Y192056D01*
Y191856D01*
X500635D01*
Y192056D01*
G37*
G36*
G01X503235D02*
X503285Y192806D01*
X503685D01*
X503735Y192056D01*
Y191856D01*
X503235D01*
Y192056D01*
G37*
G36*
G01X505835D02*
X505885Y192806D01*
X506285D01*
X506335Y192056D01*
Y191856D01*
X505835D01*
Y192056D01*
G37*
G36*
G01X502435Y191656D02*
X502385Y190906D01*
X501985D01*
X501935Y191656D01*
Y191856D01*
X502435D01*
Y191656D01*
G37*
G36*
G01X505035D02*
X504985Y190906D01*
X504585D01*
X504535Y191656D01*
Y191856D01*
X505035D01*
Y191656D01*
G37*
G36*
G01X507635D02*
X507585Y190906D01*
X507185D01*
X507135Y191656D01*
Y191856D01*
X507635D01*
Y191656D01*
G37*
G36*
G01X508435Y192056D02*
X508485Y192806D01*
X508885D01*
X508935Y192056D01*
Y191856D01*
X508435D01*
Y192056D01*
G37*
G36*
G01X511035D02*
X511085Y192806D01*
X511485D01*
X511535Y192056D01*
Y191856D01*
X511035D01*
Y192056D01*
G37*
G36*
G01X510235Y191656D02*
X510185Y190906D01*
X509785D01*
X509735Y191656D01*
Y191856D01*
X510235D01*
Y191656D01*
G37*
G36*
G01X516872Y188314D02*
X516307Y187819D01*
X516024Y188102D01*
X516519Y188667D01*
X516660Y188809D01*
X517014Y188455D01*
X516872Y188314D01*
G37*
G36*
G01X515034Y190152D02*
X514468Y189657D01*
X514185Y189940D01*
X514680Y190506D01*
X514822Y190647D01*
X515175Y190294D01*
X515034Y190152D01*
G37*
G36*
G01X515882Y189869D02*
X516448Y190364D01*
X516731Y190081D01*
X516236Y189516D01*
X516095Y189374D01*
X515741Y189728D01*
X515882Y189869D01*
G37*
G36*
G01X514044Y191708D02*
X514610Y192203D01*
X514893Y191920D01*
X514398Y191354D01*
X514256Y191213D01*
X513903Y191566D01*
X514044Y191708D01*
G37*
G36*
G01X517721Y188031D02*
X518287Y188526D01*
X518570Y188243D01*
X518075Y187677D01*
X517933Y187536D01*
X517580Y187889D01*
X517721Y188031D01*
G37*
G36*
G01X518711Y186475D02*
X518145Y185980D01*
X517862Y186263D01*
X518357Y186829D01*
X518499Y186970D01*
X518852Y186617D01*
X518711Y186475D01*
G37*
G36*
G01X519559Y186192D02*
X520125Y186687D01*
X520408Y186405D01*
X519913Y185839D01*
X519772Y185697D01*
X519418Y186051D01*
X519559Y186192D01*
G37*
G36*
G01X527903Y177283D02*
X527338Y176788D01*
X527055Y177071D01*
X527550Y177636D01*
X527691Y177778D01*
X528045Y177424D01*
X527903Y177283D01*
G37*
G36*
G01X529742Y175444D02*
X529176Y174949D01*
X528893Y175232D01*
X529388Y175798D01*
X529530Y175939D01*
X529883Y175586D01*
X529742Y175444D01*
G37*
G36*
G01X528752Y177000D02*
X529318Y177495D01*
X529600Y177212D01*
X529105Y176646D01*
X528964Y176505D01*
X528610Y176859D01*
X528752Y177000D01*
G37*
G36*
G01X526065Y179121D02*
X525499Y178626D01*
X525216Y178909D01*
X525711Y179475D01*
X525853Y179616D01*
X526206Y179263D01*
X526065Y179121D01*
G37*
G36*
G01X526913Y178838D02*
X527479Y179333D01*
X527762Y179051D01*
X527267Y178485D01*
X527125Y178344D01*
X526772Y178697D01*
X526913Y178838D01*
G37*
G36*
G01X530590Y175162D02*
X531156Y175657D01*
X531439Y175374D01*
X530944Y174808D01*
X530802Y174667D01*
X530449Y175020D01*
X530590Y175162D01*
G37*
G36*
G01X520549Y184637D02*
X519984Y184142D01*
X519701Y184425D01*
X520196Y184990D01*
X520337Y185132D01*
X520691Y184778D01*
X520549Y184637D01*
G37*
G36*
G01X521398Y184354D02*
X521964Y184849D01*
X522246Y184566D01*
X521751Y184000D01*
X521610Y183859D01*
X521257Y184212D01*
X521398Y184354D01*
G37*
G36*
G01X522388Y182798D02*
X521822Y182303D01*
X521539Y182586D01*
X522034Y183152D01*
X522176Y183293D01*
X522529Y182940D01*
X522388Y182798D01*
G37*
G36*
G01X524226Y180960D02*
X523661Y180465D01*
X523378Y180748D01*
X523873Y181313D01*
X524014Y181455D01*
X524368Y181101D01*
X524226Y180960D01*
G37*
G36*
G01X523236Y182515D02*
X523802Y183010D01*
X524085Y182728D01*
X523590Y182162D01*
X523449Y182020D01*
X523095Y182374D01*
X523236Y182515D01*
G37*
G36*
G01X525075Y180677D02*
X525641Y181172D01*
X525923Y180889D01*
X525428Y180323D01*
X525287Y180182D01*
X524933Y180536D01*
X525075Y180677D01*
G37*
G36*
G01X478723Y175430D02*
X478158Y174935D01*
X477875Y175218D01*
X478370Y175783D01*
X478511Y175925D01*
X478865Y175571D01*
X478723Y175430D01*
G37*
G36*
G01X481635Y174606D02*
X481585Y173856D01*
X481185D01*
X481135Y174606D01*
Y174806D01*
X481635D01*
Y174606D01*
G37*
G36*
G01X482435Y175006D02*
X482485Y175756D01*
X482885D01*
X482935Y175006D01*
Y174806D01*
X482435D01*
Y175006D01*
G37*
G36*
G01X479835D02*
X479885Y175756D01*
X480285D01*
X480335Y175006D01*
Y174806D01*
X479835D01*
Y175006D01*
G37*
G36*
G01X486835Y174606D02*
X486785Y173856D01*
X486385D01*
X486335Y174606D01*
Y174806D01*
X486835D01*
Y174606D01*
G37*
G36*
G01X484235D02*
X484185Y173856D01*
X483785D01*
X483735Y174606D01*
Y174806D01*
X484235D01*
Y174606D01*
G37*
G36*
G01X485035Y175006D02*
X485085Y175756D01*
X485485D01*
X485535Y175006D01*
Y174806D01*
X485035D01*
Y175006D01*
G37*
G36*
G01X490235D02*
X490285Y175756D01*
X490685D01*
X490735Y175006D01*
Y174806D01*
X490235D01*
Y175006D01*
G37*
G36*
G01X492835D02*
X492885Y175756D01*
X493285D01*
X493335Y175006D01*
Y174806D01*
X492835D01*
Y175006D01*
G37*
G36*
G01X492035Y174606D02*
X491985Y173856D01*
X491585D01*
X491535Y174606D01*
Y174806D01*
X492035D01*
Y174606D01*
G37*
G36*
G01X489435D02*
X489385Y173856D01*
X488985D01*
X488935Y174606D01*
Y174806D01*
X489435D01*
Y174606D01*
G37*
G36*
G01X487635Y175006D02*
X487685Y175756D01*
X488085D01*
X488135Y175006D01*
Y174806D01*
X487635D01*
Y175006D01*
G37*
G36*
G01X495435D02*
X495485Y175756D01*
X495885D01*
X495935Y175006D01*
Y174806D01*
X495435D01*
Y175006D01*
G37*
G36*
G01X498035D02*
X498085Y175756D01*
X498485D01*
X498535Y175006D01*
Y174806D01*
X498035D01*
Y175006D01*
G37*
G36*
G01X494635Y174606D02*
X494585Y173856D01*
X494185D01*
X494135Y174606D01*
Y174806D01*
X494635D01*
Y174606D01*
G37*
G36*
G01X497235D02*
X497185Y173856D01*
X496785D01*
X496735Y174606D01*
Y174806D01*
X497235D01*
Y174606D01*
G37*
G36*
G01X499835D02*
X499785Y173856D01*
X499385D01*
X499335Y174606D01*
Y174806D01*
X499835D01*
Y174606D01*
G37*
G36*
G01X502435D02*
X502385Y173856D01*
X501985D01*
X501935Y174606D01*
Y174806D01*
X502435D01*
Y174606D01*
G37*
G36*
G01X505035D02*
X504985Y173856D01*
X504585D01*
X504535Y174606D01*
Y174806D01*
X505035D01*
Y174606D01*
G37*
G36*
G01X500635Y175006D02*
X500685Y175756D01*
X501085D01*
X501135Y175006D01*
Y174806D01*
X500635D01*
Y175006D01*
G37*
G36*
G01X503235D02*
X503285Y175756D01*
X503685D01*
X503735Y175006D01*
Y174806D01*
X503235D01*
Y175006D01*
G37*
G36*
G01X505835D02*
X505885Y175756D01*
X506285D01*
X506335Y175006D01*
Y174806D01*
X505835D01*
Y175006D01*
G37*
G36*
G01X507498Y174131D02*
X508064Y174626D01*
X508346Y174343D01*
X507852Y173777D01*
X507710Y173636D01*
X507357Y173989D01*
X507498Y174131D01*
G37*
G36*
G01X509336Y172292D02*
X509902Y172787D01*
X510185Y172505D01*
X509690Y171939D01*
X509549Y171797D01*
X509195Y172151D01*
X509336Y172292D01*
G37*
G36*
G01X508488Y172575D02*
X507922Y172080D01*
X507639Y172363D01*
X508134Y172929D01*
X508276Y173070D01*
X508629Y172717D01*
X508488Y172575D01*
G37*
G36*
G01X510326Y170737D02*
X509761Y170242D01*
X509478Y170525D01*
X509973Y171090D01*
X510114Y171232D01*
X510468Y170878D01*
X510326Y170737D01*
G37*
G36*
G01X478830Y178082D02*
X479396Y178577D01*
X479678Y178294D01*
X479183Y177728D01*
X479042Y177587D01*
X478688Y177941D01*
X478830Y178082D01*
G37*
G36*
G01X479820Y176526D02*
X479254Y176031D01*
X478971Y176314D01*
X479466Y176880D01*
X479608Y177021D01*
X479961Y176668D01*
X479820Y176526D01*
G37*
G36*
G01X481635Y176156D02*
X481585Y175406D01*
X481185D01*
X481135Y176156D01*
Y176356D01*
X481635D01*
Y176156D01*
G37*
G36*
G01X482435Y176556D02*
X482485Y177306D01*
X482885D01*
X482935Y176556D01*
Y176356D01*
X482435D01*
Y176556D01*
G37*
G36*
G01X486835Y176156D02*
X486785Y175406D01*
X486385D01*
X486335Y176156D01*
Y176356D01*
X486835D01*
Y176156D01*
G37*
G36*
G01X484235D02*
X484185Y175406D01*
X483785D01*
X483735Y176156D01*
Y176356D01*
X484235D01*
Y176156D01*
G37*
G36*
G01X485035Y176556D02*
X485085Y177306D01*
X485485D01*
X485535Y176556D01*
Y176356D01*
X485035D01*
Y176556D01*
G37*
G36*
G01X492035Y176156D02*
X491985Y175406D01*
X491585D01*
X491535Y176156D01*
Y176356D01*
X492035D01*
Y176156D01*
G37*
G36*
G01X490235Y176556D02*
X490285Y177306D01*
X490685D01*
X490735Y176556D01*
Y176356D01*
X490235D01*
Y176556D01*
G37*
G36*
G01X492835D02*
X492885Y177306D01*
X493285D01*
X493335Y176556D01*
Y176356D01*
X492835D01*
Y176556D01*
G37*
G36*
G01X489435Y176156D02*
X489385Y175406D01*
X488985D01*
X488935Y176156D01*
Y176356D01*
X489435D01*
Y176156D01*
G37*
G36*
G01X487635Y176556D02*
X487685Y177306D01*
X488085D01*
X488135Y176556D01*
Y176356D01*
X487635D01*
Y176556D01*
G37*
G36*
G01X494635Y176156D02*
X494585Y175406D01*
X494185D01*
X494135Y176156D01*
Y176356D01*
X494635D01*
Y176156D01*
G37*
G36*
G01X497235D02*
X497185Y175406D01*
X496785D01*
X496735Y176156D01*
Y176356D01*
X497235D01*
Y176156D01*
G37*
G36*
G01X499835D02*
X499785Y175406D01*
X499385D01*
X499335Y176156D01*
Y176356D01*
X499835D01*
Y176156D01*
G37*
G36*
G01X495435Y176556D02*
X495485Y177306D01*
X495885D01*
X495935Y176556D01*
Y176356D01*
X495435D01*
Y176556D01*
G37*
G36*
G01X498035D02*
X498085Y177306D01*
X498485D01*
X498535Y176556D01*
Y176356D01*
X498035D01*
Y176556D01*
G37*
G36*
G01X502435Y176156D02*
X502385Y175406D01*
X501985D01*
X501935Y176156D01*
Y176356D01*
X502435D01*
Y176156D01*
G37*
G36*
G01X505035D02*
X504985Y175406D01*
X504585D01*
X504535Y176156D01*
Y176356D01*
X505035D01*
Y176156D01*
G37*
G36*
G01X500635Y176556D02*
X500685Y177306D01*
X501085D01*
X501135Y176556D01*
Y176356D01*
X500635D01*
Y176556D01*
G37*
G36*
G01X503235D02*
X503285Y177306D01*
X503685D01*
X503735Y176556D01*
Y176356D01*
X503235D01*
Y176556D01*
G37*
G36*
G01X505835D02*
X505885Y177306D01*
X506285D01*
X506335Y176556D01*
Y176356D01*
X505835D01*
Y176556D01*
G37*
G36*
G01X507746Y175510D02*
X507180Y175015D01*
X506897Y175298D01*
X507392Y175864D01*
X507534Y176005D01*
X507887Y175652D01*
X507746Y175510D01*
G37*
G36*
G01X508594Y175227D02*
X509160Y175722D01*
X509443Y175440D01*
X508948Y174874D01*
X508807Y174732D01*
X508453Y175086D01*
X508594Y175227D01*
G37*
G36*
G01X509584Y173672D02*
X509019Y173177D01*
X508736Y173460D01*
X509231Y174025D01*
X509372Y174167D01*
X509726Y173813D01*
X509584Y173672D01*
G37*
G36*
G01X510433Y173389D02*
X510999Y173884D01*
X511281Y173601D01*
X510786Y173035D01*
X510645Y172894D01*
X510292Y173247D01*
X510433Y173389D01*
G37*
G36*
G01X512271Y171550D02*
X512837Y172045D01*
X513120Y171763D01*
X512625Y171197D01*
X512484Y171055D01*
X512130Y171409D01*
X512271Y171550D01*
G37*
G36*
G01X511423Y171833D02*
X510857Y171338D01*
X510574Y171621D01*
X511069Y172187D01*
X511211Y172328D01*
X511564Y171975D01*
X511423Y171833D01*
G37*
G36*
G01X483818Y187879D02*
X483253Y187384D01*
X482970Y187667D01*
X483465Y188232D01*
X483606Y188374D01*
X483960Y188020D01*
X483818Y187879D01*
G37*
G36*
G01X486835Y187006D02*
X486785Y186256D01*
X486385D01*
X486335Y187006D01*
Y187206D01*
X486835D01*
Y187006D01*
G37*
G36*
G01X479151Y193111D02*
X479717Y193606D01*
X480000Y193324D01*
X479505Y192758D01*
X479364Y192616D01*
X479010Y192970D01*
X479151Y193111D01*
G37*
G36*
G01X480990Y191273D02*
X481556Y191768D01*
X481838Y191485D01*
X481343Y190919D01*
X481202Y190778D01*
X480848Y191132D01*
X480990Y191273D01*
G37*
G36*
G01X482828Y189434D02*
X483394Y189929D01*
X483677Y189647D01*
X483182Y189081D01*
X483040Y188940D01*
X482687Y189293D01*
X482828Y189434D01*
G37*
G36*
G01X480141Y191556D02*
X479576Y191061D01*
X479293Y191344D01*
X479788Y191909D01*
X479929Y192051D01*
X480283Y191697D01*
X480141Y191556D01*
G37*
G36*
G01X481980Y189717D02*
X481414Y189222D01*
X481131Y189505D01*
X481626Y190071D01*
X481768Y190212D01*
X482121Y189859D01*
X481980Y189717D01*
G37*
G36*
G01X489435Y187006D02*
X489385Y186256D01*
X488985D01*
X488935Y187006D01*
Y187206D01*
X489435D01*
Y187006D01*
G37*
G36*
G01X487635Y187406D02*
X487685Y188156D01*
X488085D01*
X488135Y187406D01*
Y187206D01*
X487635D01*
Y187406D01*
G37*
G36*
G01X492035Y187006D02*
X491985Y186256D01*
X491585D01*
X491535Y187006D01*
Y187206D01*
X492035D01*
Y187006D01*
G37*
G36*
G01X492835Y187406D02*
X492885Y188156D01*
X493285D01*
X493335Y187406D01*
Y187206D01*
X492835D01*
Y187406D01*
G37*
G36*
G01X490235D02*
X490285Y188156D01*
X490685D01*
X490735Y187406D01*
Y187206D01*
X490235D01*
Y187406D01*
G37*
G36*
G01X494635Y187006D02*
X494585Y186256D01*
X494185D01*
X494135Y187006D01*
Y187206D01*
X494635D01*
Y187006D01*
G37*
G36*
G01X497235D02*
X497185Y186256D01*
X496785D01*
X496735Y187006D01*
Y187206D01*
X497235D01*
Y187006D01*
G37*
G36*
G01X499835D02*
X499785Y186256D01*
X499385D01*
X499335Y187006D01*
Y187206D01*
X499835D01*
Y187006D01*
G37*
G36*
G01X495435Y187406D02*
X495485Y188156D01*
X495885D01*
X495935Y187406D01*
Y187206D01*
X495435D01*
Y187406D01*
G37*
G36*
G01X498035D02*
X498085Y188156D01*
X498485D01*
X498535Y187406D01*
Y187206D01*
X498035D01*
Y187406D01*
G37*
G36*
G01X502435Y187006D02*
X502385Y186256D01*
X501985D01*
X501935Y187006D01*
Y187206D01*
X502435D01*
Y187006D01*
G37*
G36*
G01X505035D02*
X504985Y186256D01*
X504585D01*
X504535Y187006D01*
Y187206D01*
X505035D01*
Y187006D01*
G37*
G36*
G01X507635D02*
X507585Y186256D01*
X507185D01*
X507135Y187006D01*
Y187206D01*
X507635D01*
Y187006D01*
G37*
G36*
G01X500635Y187406D02*
X500685Y188156D01*
X501085D01*
X501135Y187406D01*
Y187206D01*
X500635D01*
Y187406D01*
G37*
G36*
G01X503235D02*
X503285Y188156D01*
X503685D01*
X503735Y187406D01*
Y187206D01*
X503235D01*
Y187406D01*
G37*
G36*
G01X505835D02*
X505885Y188156D01*
X506285D01*
X506335Y187406D01*
Y187206D01*
X505835D01*
Y187406D01*
G37*
G36*
G01X508435D02*
X508485Y188156D01*
X508885D01*
X508935Y187406D01*
Y187206D01*
X508435D01*
Y187406D01*
G37*
G36*
G01X510235Y187006D02*
X510185Y186256D01*
X509785D01*
X509735Y187006D01*
Y187206D01*
X510235D01*
Y187006D01*
G37*
G36*
G01X527301Y171872D02*
X527867Y172367D01*
X528149Y172084D01*
X527654Y171518D01*
X527513Y171377D01*
X527159Y171731D01*
X527301Y171872D01*
G37*
G36*
G01X526452Y172155D02*
X525887Y171660D01*
X525604Y171943D01*
X526099Y172508D01*
X526240Y172650D01*
X526594Y172296D01*
X526452Y172155D01*
G37*
G36*
G01X525462Y173711D02*
X526028Y174205D01*
X526311Y173923D01*
X525816Y173357D01*
X525674Y173216D01*
X525321Y173569D01*
X525462Y173711D01*
G37*
G36*
G01X524614Y173993D02*
X524048Y173498D01*
X523765Y173781D01*
X524260Y174347D01*
X524402Y174488D01*
X524755Y174135D01*
X524614Y173993D01*
G37*
G36*
G01X516270Y182903D02*
X516836Y183398D01*
X517118Y183115D01*
X516624Y182549D01*
X516482Y182408D01*
X516129Y182761D01*
X516270Y182903D01*
G37*
G36*
G01X514431Y184741D02*
X514997Y185236D01*
X515280Y184954D01*
X514785Y184388D01*
X514644Y184246D01*
X514290Y184600D01*
X514431Y184741D01*
G37*
G36*
G01X512593Y186580D02*
X513159Y187075D01*
X513442Y186792D01*
X512947Y186226D01*
X512805Y186085D01*
X512452Y186438D01*
X512593Y186580D01*
G37*
G36*
G01X515421Y183186D02*
X514856Y182691D01*
X514573Y182974D01*
X515068Y183539D01*
X515209Y183681D01*
X515563Y183327D01*
X515421Y183186D01*
G37*
G36*
G01X513583Y185024D02*
X513017Y184529D01*
X512734Y184812D01*
X513229Y185378D01*
X513371Y185519D01*
X513724Y185166D01*
X513583Y185024D01*
G37*
G36*
G01X518108Y181064D02*
X518674Y181559D01*
X518957Y181277D01*
X518462Y180711D01*
X518321Y180569D01*
X517967Y180923D01*
X518108Y181064D01*
G37*
G36*
G01X519098Y179509D02*
X518533Y179014D01*
X518250Y179297D01*
X518745Y179862D01*
X518886Y180004D01*
X519240Y179650D01*
X519098Y179509D01*
G37*
G36*
G01X517260Y181347D02*
X516694Y180852D01*
X516411Y181135D01*
X516906Y181701D01*
X517048Y181842D01*
X517401Y181489D01*
X517260Y181347D01*
G37*
G36*
G01X523624Y175549D02*
X524190Y176044D01*
X524472Y175761D01*
X523977Y175195D01*
X523836Y175054D01*
X523482Y175408D01*
X523624Y175549D01*
G37*
G36*
G01X522775Y175832D02*
X522210Y175337D01*
X521927Y175620D01*
X522422Y176185D01*
X522563Y176327D01*
X522917Y175973D01*
X522775Y175832D01*
G37*
G36*
G01X519947Y179226D02*
X520513Y179721D01*
X520795Y179438D01*
X520300Y178872D01*
X520159Y178731D01*
X519805Y179085D01*
X519947Y179226D01*
G37*
G36*
G01X521785Y177387D02*
X522351Y177882D01*
X522634Y177600D01*
X522139Y177034D01*
X521998Y176892D01*
X521644Y177246D01*
X521785Y177387D01*
G37*
G36*
G01X520937Y177670D02*
X520371Y177175D01*
X520088Y177458D01*
X520583Y178024D01*
X520725Y178165D01*
X521078Y177812D01*
X520937Y177670D01*
G37*
G36*
G01X483076Y190814D02*
X482511Y190319D01*
X482228Y190602D01*
X482723Y191167D01*
X482864Y191309D01*
X483218Y190955D01*
X483076Y190814D01*
G37*
G36*
G01X483925Y190531D02*
X484491Y191026D01*
X484773Y190743D01*
X484278Y190177D01*
X484137Y190036D01*
X483783Y190390D01*
X483925Y190531D01*
G37*
G36*
G01X484915Y188975D02*
X484349Y188480D01*
X484066Y188763D01*
X484561Y189329D01*
X484703Y189470D01*
X485056Y189117D01*
X484915Y188975D01*
G37*
G36*
G01X486835Y188556D02*
X486785Y187806D01*
X486385D01*
X486335Y188556D01*
Y188756D01*
X486835D01*
Y188556D01*
G37*
G36*
G01X478409Y196046D02*
X478975Y196541D01*
X479258Y196259D01*
X478763Y195693D01*
X478622Y195551D01*
X478268Y195905D01*
X478409Y196046D01*
G37*
G36*
G01X480248Y194208D02*
X480814Y194703D01*
X481096Y194420D01*
X480601Y193854D01*
X480460Y193713D01*
X480106Y194067D01*
X480248Y194208D01*
G37*
G36*
G01X482086Y192369D02*
X482652Y192864D01*
X482935Y192582D01*
X482440Y192016D01*
X482299Y191874D01*
X481945Y192228D01*
X482086Y192369D01*
G37*
G36*
G01X479399Y194491D02*
X478834Y193996D01*
X478551Y194279D01*
X479046Y194844D01*
X479187Y194986D01*
X479541Y194632D01*
X479399Y194491D01*
G37*
G36*
G01X481238Y192652D02*
X480672Y192157D01*
X480389Y192440D01*
X480884Y193006D01*
X481026Y193147D01*
X481379Y192794D01*
X481238Y192652D01*
G37*
G36*
G01X489435Y188556D02*
X489385Y187806D01*
X488985D01*
X488935Y188556D01*
Y188756D01*
X489435D01*
Y188556D01*
G37*
G36*
G01X487635Y188956D02*
X487685Y189706D01*
X488085D01*
X488135Y188956D01*
Y188756D01*
X487635D01*
Y188956D01*
G37*
G36*
G01X492035Y188556D02*
X491985Y187806D01*
X491585D01*
X491535Y188556D01*
Y188756D01*
X492035D01*
Y188556D01*
G37*
G36*
G01X492835Y188956D02*
X492885Y189706D01*
X493285D01*
X493335Y188956D01*
Y188756D01*
X492835D01*
Y188956D01*
G37*
G36*
G01X490235D02*
X490285Y189706D01*
X490685D01*
X490735Y188956D01*
Y188756D01*
X490235D01*
Y188956D01*
G37*
G36*
G01X497235Y188556D02*
X497185Y187806D01*
X496785D01*
X496735Y188556D01*
Y188756D01*
X497235D01*
Y188556D01*
G37*
G36*
G01X494635D02*
X494585Y187806D01*
X494185D01*
X494135Y188556D01*
Y188756D01*
X494635D01*
Y188556D01*
G37*
G36*
G01X499835D02*
X499785Y187806D01*
X499385D01*
X499335Y188556D01*
Y188756D01*
X499835D01*
Y188556D01*
G37*
G36*
G01X495435Y188956D02*
X495485Y189706D01*
X495885D01*
X495935Y188956D01*
Y188756D01*
X495435D01*
Y188956D01*
G37*
G36*
G01X498035D02*
X498085Y189706D01*
X498485D01*
X498535Y188956D01*
Y188756D01*
X498035D01*
Y188956D01*
G37*
G36*
G01X502435Y188556D02*
X502385Y187806D01*
X501985D01*
X501935Y188556D01*
Y188756D01*
X502435D01*
Y188556D01*
G37*
G36*
G01X505035D02*
X504985Y187806D01*
X504585D01*
X504535Y188556D01*
Y188756D01*
X505035D01*
Y188556D01*
G37*
G36*
G01X507635D02*
X507585Y187806D01*
X507185D01*
X507135Y188556D01*
Y188756D01*
X507635D01*
Y188556D01*
G37*
G36*
G01X500635Y188956D02*
X500685Y189706D01*
X501085D01*
X501135Y188956D01*
Y188756D01*
X500635D01*
Y188956D01*
G37*
G36*
G01X503235D02*
X503285Y189706D01*
X503685D01*
X503735Y188956D01*
Y188756D01*
X503235D01*
Y188956D01*
G37*
G36*
G01X505835D02*
X505885Y189706D01*
X506285D01*
X506335Y188956D01*
Y188756D01*
X505835D01*
Y188956D01*
G37*
G36*
G01X512841Y187959D02*
X512275Y187464D01*
X511992Y187747D01*
X512487Y188313D01*
X512629Y188454D01*
X512982Y188101D01*
X512841Y187959D01*
G37*
G36*
G01X508435Y188956D02*
X508485Y189706D01*
X508885D01*
X508935Y188956D01*
Y188756D01*
X508435D01*
Y188956D01*
G37*
G36*
G01X510235Y188556D02*
X510185Y187806D01*
X509785D01*
X509735Y188556D01*
Y188756D01*
X510235D01*
Y188556D01*
G37*
G36*
G01X527549Y173251D02*
X526983Y172756D01*
X526700Y173039D01*
X527195Y173605D01*
X527337Y173746D01*
X527690Y173393D01*
X527549Y173251D01*
G37*
G36*
G01X528397Y172969D02*
X528963Y173464D01*
X529246Y173181D01*
X528751Y172615D01*
X528609Y172474D01*
X528256Y172827D01*
X528397Y172969D01*
G37*
G36*
G01X516518Y184282D02*
X515952Y183787D01*
X515669Y184070D01*
X516164Y184636D01*
X516306Y184777D01*
X516659Y184424D01*
X516518Y184282D01*
G37*
G36*
G01X514679Y186121D02*
X514114Y185626D01*
X513831Y185909D01*
X514326Y186474D01*
X514467Y186616D01*
X514821Y186262D01*
X514679Y186121D01*
G37*
G36*
G01X515528Y185838D02*
X516094Y186333D01*
X516377Y186050D01*
X515882Y185484D01*
X515740Y185343D01*
X515387Y185696D01*
X515528Y185838D01*
G37*
G36*
G01X513689Y187676D02*
X514255Y188171D01*
X514538Y187888D01*
X514043Y187323D01*
X513902Y187181D01*
X513548Y187535D01*
X513689Y187676D01*
G37*
G36*
G01X518356Y182444D02*
X517791Y181949D01*
X517508Y182232D01*
X518003Y182797D01*
X518144Y182939D01*
X518498Y182585D01*
X518356Y182444D01*
G37*
G36*
G01X519205Y182161D02*
X519771Y182656D01*
X520053Y182373D01*
X519558Y181807D01*
X519417Y181666D01*
X519064Y182019D01*
X519205Y182161D01*
G37*
G36*
G01X517366Y183999D02*
X517932Y184494D01*
X518215Y184212D01*
X517720Y183646D01*
X517579Y183504D01*
X517225Y183858D01*
X517366Y183999D01*
G37*
G36*
G01X520195Y180605D02*
X519629Y180110D01*
X519346Y180393D01*
X519841Y180959D01*
X519983Y181100D01*
X520336Y180747D01*
X520195Y180605D01*
G37*
G36*
G01X523872Y176928D02*
X523306Y176433D01*
X523023Y176716D01*
X523518Y177282D01*
X523660Y177423D01*
X524013Y177070D01*
X523872Y176928D01*
G37*
G36*
G01X525710Y175090D02*
X525145Y174595D01*
X524862Y174878D01*
X525357Y175443D01*
X525498Y175585D01*
X525852Y175231D01*
X525710Y175090D01*
G37*
G36*
G01X524720Y176645D02*
X525286Y177140D01*
X525569Y176858D01*
X525074Y176292D01*
X524932Y176151D01*
X524579Y176504D01*
X524720Y176645D01*
G37*
G36*
G01X526559Y174807D02*
X527125Y175302D01*
X527407Y175019D01*
X526912Y174453D01*
X526771Y174312D01*
X526417Y174666D01*
X526559Y174807D01*
G37*
G36*
G01X522033Y178767D02*
X521468Y178272D01*
X521185Y178555D01*
X521680Y179120D01*
X521821Y179262D01*
X522175Y178908D01*
X522033Y178767D01*
G37*
G36*
G01X522882Y178484D02*
X523448Y178979D01*
X523730Y178696D01*
X523235Y178130D01*
X523094Y177989D01*
X522740Y178343D01*
X522882Y178484D01*
G37*
G36*
G01X521043Y180322D02*
X521609Y180817D01*
X521892Y180535D01*
X521397Y179969D01*
X521256Y179827D01*
X520902Y180181D01*
X521043Y180322D01*
G37*
G36*
G01X482367Y182751D02*
X481802Y182256D01*
X481519Y182539D01*
X482014Y183104D01*
X482155Y183246D01*
X482509Y182892D01*
X482367Y182751D01*
G37*
G36*
G01X479539Y186145D02*
X480105Y186640D01*
X480387Y186357D01*
X479892Y185791D01*
X479751Y185650D01*
X479397Y186004D01*
X479539Y186145D01*
G37*
G36*
G01X480530Y184589D02*
X479964Y184094D01*
X479681Y184377D01*
X480176Y184943D01*
X480318Y185084D01*
X480671Y184731D01*
X480530Y184589D01*
G37*
G36*
G01X486835Y182356D02*
X486785Y181606D01*
X486385D01*
X486335Y182356D01*
Y182556D01*
X486835D01*
Y182356D01*
G37*
G36*
G01X484235D02*
X484185Y181606D01*
X483785D01*
X483735Y182356D01*
Y182556D01*
X484235D01*
Y182356D01*
G37*
G36*
G01X485035Y182756D02*
X485085Y183506D01*
X485485D01*
X485535Y182756D01*
Y182556D01*
X485035D01*
Y182756D01*
G37*
G36*
G01X481377Y184307D02*
X481943Y184801D01*
X482226Y184519D01*
X481731Y183953D01*
X481589Y183812D01*
X481236Y184165D01*
X481377Y184307D01*
G37*
G36*
G01X492035Y182356D02*
X491985Y181606D01*
X491585D01*
X491535Y182356D01*
Y182556D01*
X492035D01*
Y182356D01*
G37*
G36*
G01X492835Y182756D02*
X492885Y183506D01*
X493285D01*
X493335Y182756D01*
Y182556D01*
X492835D01*
Y182756D01*
G37*
G36*
G01X490235D02*
X490285Y183506D01*
X490685D01*
X490735Y182756D01*
Y182556D01*
X490235D01*
Y182756D01*
G37*
G36*
G01X489435Y182356D02*
X489385Y181606D01*
X488985D01*
X488935Y182356D01*
Y182556D01*
X489435D01*
Y182356D01*
G37*
G36*
G01X487635Y182756D02*
X487685Y183506D01*
X488085D01*
X488135Y182756D01*
Y182556D01*
X487635D01*
Y182756D01*
G37*
G36*
G01X499835Y182356D02*
X499785Y181606D01*
X499385D01*
X499335Y182356D01*
Y182556D01*
X499835D01*
Y182356D01*
G37*
G36*
G01X497235D02*
X497185Y181606D01*
X496785D01*
X496735Y182356D01*
Y182556D01*
X497235D01*
Y182356D01*
G37*
G36*
G01X494635D02*
X494585Y181606D01*
X494185D01*
X494135Y182356D01*
Y182556D01*
X494635D01*
Y182356D01*
G37*
G36*
G01X498035Y182756D02*
X498085Y183506D01*
X498485D01*
X498535Y182756D01*
Y182556D01*
X498035D01*
Y182756D01*
G37*
G36*
G01X495435D02*
X495485Y183506D01*
X495885D01*
X495935Y182756D01*
Y182556D01*
X495435D01*
Y182756D01*
G37*
G36*
G01X502435Y182356D02*
X502385Y181606D01*
X501985D01*
X501935Y182356D01*
Y182556D01*
X502435D01*
Y182356D01*
G37*
G36*
G01X505035D02*
X504985Y181606D01*
X504585D01*
X504535Y182356D01*
Y182556D01*
X505035D01*
Y182356D01*
G37*
G36*
G01X507635D02*
X507585Y181606D01*
X507185D01*
X507135Y182356D01*
Y182556D01*
X507635D01*
Y182356D01*
G37*
G36*
G01X500635Y182756D02*
X500685Y183506D01*
X501085D01*
X501135Y182756D01*
Y182556D01*
X500635D01*
Y182756D01*
G37*
G36*
G01X503235D02*
X503285Y183506D01*
X503685D01*
X503735Y182756D01*
Y182556D01*
X503235D01*
Y182756D01*
G37*
G36*
G01X505835D02*
X505885Y183506D01*
X506285D01*
X506335Y182756D01*
Y182556D01*
X505835D01*
Y182756D01*
G37*
G36*
G01X508435D02*
X508485Y183506D01*
X508885D01*
X508935Y182756D01*
Y182556D01*
X508435D01*
Y182756D01*
G37*
G36*
G01X511142Y181452D02*
X511708Y181947D01*
X511991Y181664D01*
X511496Y181098D01*
X511354Y180957D01*
X511001Y181310D01*
X511142Y181452D01*
G37*
G36*
G01X512132Y179896D02*
X511566Y179401D01*
X511283Y179684D01*
X511778Y180250D01*
X511920Y180391D01*
X512273Y180038D01*
X512132Y179896D01*
G37*
G36*
G01X510293Y181735D02*
X509728Y181240D01*
X509445Y181523D01*
X509940Y182088D01*
X510081Y182230D01*
X510435Y181876D01*
X510293Y181735D01*
G37*
G36*
G01X520334Y172259D02*
X520900Y172754D01*
X521183Y172472D01*
X520688Y171906D01*
X520546Y171765D01*
X520193Y172118D01*
X520334Y172259D01*
G37*
G36*
G01X519486Y172542D02*
X518920Y172047D01*
X518637Y172330D01*
X519132Y172896D01*
X519274Y173037D01*
X519627Y172684D01*
X519486Y172542D01*
G37*
G36*
G01X521324Y170704D02*
X520759Y170209D01*
X520476Y170492D01*
X520971Y171057D01*
X521112Y171199D01*
X521466Y170845D01*
X521324Y170704D01*
G37*
G36*
G01X518496Y174098D02*
X519062Y174593D01*
X519344Y174310D01*
X518849Y173744D01*
X518708Y173603D01*
X518354Y173957D01*
X518496Y174098D01*
G37*
G36*
G01X514819Y177775D02*
X515385Y178270D01*
X515667Y177987D01*
X515172Y177421D01*
X515031Y177280D01*
X514678Y177633D01*
X514819Y177775D01*
G37*
G36*
G01X512980Y179613D02*
X513546Y180108D01*
X513829Y179826D01*
X513334Y179260D01*
X513193Y179118D01*
X512839Y179472D01*
X512980Y179613D01*
G37*
G36*
G01X513970Y178058D02*
X513405Y177563D01*
X513122Y177846D01*
X513617Y178411D01*
X513758Y178553D01*
X514112Y178199D01*
X513970Y178058D01*
G37*
G36*
G01X516657Y175936D02*
X517223Y176431D01*
X517506Y176149D01*
X517011Y175583D01*
X516870Y175441D01*
X516516Y175795D01*
X516657Y175936D01*
G37*
G36*
G01X515809Y176219D02*
X515243Y175724D01*
X514960Y176007D01*
X515455Y176573D01*
X515597Y176714D01*
X515950Y176361D01*
X515809Y176219D01*
G37*
G36*
G01X517647Y174381D02*
X517082Y173886D01*
X516799Y174169D01*
X517294Y174734D01*
X517435Y174876D01*
X517789Y174522D01*
X517647Y174381D01*
G37*
G36*
G01X482474Y185403D02*
X483040Y185898D01*
X483322Y185615D01*
X482827Y185049D01*
X482686Y184908D01*
X482332Y185262D01*
X482474Y185403D01*
G37*
G36*
G01X478797Y189080D02*
X479363Y189575D01*
X479645Y189292D01*
X479150Y188726D01*
X479009Y188585D01*
X478655Y188939D01*
X478797Y189080D01*
G37*
G36*
G01X479787Y187524D02*
X479221Y187029D01*
X478938Y187312D01*
X479433Y187878D01*
X479575Y188019D01*
X479928Y187666D01*
X479787Y187524D01*
G37*
G36*
G01X481625Y185686D02*
X481060Y185191D01*
X480777Y185474D01*
X481272Y186039D01*
X481413Y186181D01*
X481767Y185827D01*
X481625Y185686D01*
G37*
G36*
G01X480635Y187241D02*
X481201Y187736D01*
X481484Y187454D01*
X480989Y186888D01*
X480847Y186747D01*
X480494Y187100D01*
X480635Y187241D01*
G37*
G36*
G01X485035Y184306D02*
X485085Y185056D01*
X485485D01*
X485535Y184306D01*
Y184106D01*
X485035D01*
Y184306D01*
G37*
G36*
G01X486835Y183906D02*
X486785Y183156D01*
X486385D01*
X486335Y183906D01*
Y184106D01*
X486835D01*
Y183906D01*
G37*
G36*
G01X492035D02*
X491985Y183156D01*
X491585D01*
X491535Y183906D01*
Y184106D01*
X492035D01*
Y183906D01*
G37*
G36*
G01X492835Y184306D02*
X492885Y185056D01*
X493285D01*
X493335Y184306D01*
Y184106D01*
X492835D01*
Y184306D01*
G37*
G36*
G01X490235D02*
X490285Y185056D01*
X490685D01*
X490735Y184306D01*
Y184106D01*
X490235D01*
Y184306D01*
G37*
G36*
G01X489435Y183906D02*
X489385Y183156D01*
X488985D01*
X488935Y183906D01*
Y184106D01*
X489435D01*
Y183906D01*
G37*
G36*
G01X487635Y184306D02*
X487685Y185056D01*
X488085D01*
X488135Y184306D01*
Y184106D01*
X487635D01*
Y184306D01*
G37*
G36*
G01X497235Y183906D02*
X497185Y183156D01*
X496785D01*
X496735Y183906D01*
Y184106D01*
X497235D01*
Y183906D01*
G37*
G36*
G01X494635D02*
X494585Y183156D01*
X494185D01*
X494135Y183906D01*
Y184106D01*
X494635D01*
Y183906D01*
G37*
G36*
G01X498035Y184306D02*
X498085Y185056D01*
X498485D01*
X498535Y184306D01*
Y184106D01*
X498035D01*
Y184306D01*
G37*
G36*
G01X495435D02*
X495485Y185056D01*
X495885D01*
X495935Y184306D01*
Y184106D01*
X495435D01*
Y184306D01*
G37*
G36*
G01X499835Y183906D02*
X499785Y183156D01*
X499385D01*
X499335Y183906D01*
Y184106D01*
X499835D01*
Y183906D01*
G37*
G36*
G01X507635D02*
X507585Y183156D01*
X507185D01*
X507135Y183906D01*
Y184106D01*
X507635D01*
Y183906D01*
G37*
G36*
G01X500635Y184306D02*
X500685Y185056D01*
X501085D01*
X501135Y184306D01*
Y184106D01*
X500635D01*
Y184306D01*
G37*
G36*
G01X503235D02*
X503285Y185056D01*
X503685D01*
X503735Y184306D01*
Y184106D01*
X503235D01*
Y184306D01*
G37*
G36*
G01X505835D02*
X505885Y185056D01*
X506285D01*
X506335Y184306D01*
Y184106D01*
X505835D01*
Y184306D01*
G37*
G36*
G01X502435Y183906D02*
X502385Y183156D01*
X501985D01*
X501935Y183906D01*
Y184106D01*
X502435D01*
Y183906D01*
G37*
G36*
G01X505035D02*
X504985Y183156D01*
X504585D01*
X504535Y183906D01*
Y184106D01*
X505035D01*
Y183906D01*
G37*
G36*
G01X508435Y184306D02*
X508485Y185056D01*
X508885D01*
X508935Y184306D01*
Y184106D01*
X508435D01*
Y184306D01*
G37*
G36*
G01X512238Y182548D02*
X512804Y183043D01*
X513087Y182761D01*
X512592Y182195D01*
X512451Y182053D01*
X512097Y182407D01*
X512238Y182548D01*
G37*
G36*
G01X513228Y180993D02*
X512663Y180498D01*
X512380Y180781D01*
X512875Y181346D01*
X513016Y181488D01*
X513370Y181134D01*
X513228Y180993D01*
G37*
G36*
G01X511390Y182831D02*
X510824Y182336D01*
X510541Y182619D01*
X511036Y183185D01*
X511178Y183326D01*
X511531Y182973D01*
X511390Y182831D01*
G37*
G36*
G01X521431Y173356D02*
X521997Y173851D01*
X522279Y173568D01*
X521784Y173002D01*
X521643Y172861D01*
X521289Y173215D01*
X521431Y173356D01*
G37*
G36*
G01X523269Y171518D02*
X523835Y172012D01*
X524118Y171730D01*
X523623Y171164D01*
X523481Y171023D01*
X523128Y171376D01*
X523269Y171518D01*
G37*
G36*
G01X522421Y171800D02*
X521855Y171305D01*
X521572Y171588D01*
X522067Y172154D01*
X522209Y172295D01*
X522562Y171942D01*
X522421Y171800D01*
G37*
G36*
G01X525107Y169680D02*
X525673Y170174D01*
X525956Y169892D01*
X525461Y169326D01*
X525319Y169185D01*
X524966Y169538D01*
X525107Y169680D01*
G37*
G36*
G01X524260Y169962D02*
X523694Y169467D01*
X523411Y169750D01*
X523906Y170316D01*
X524048Y170457D01*
X524401Y170104D01*
X524260Y169962D01*
G37*
G36*
G01X520582Y173639D02*
X520017Y173144D01*
X519734Y173427D01*
X520229Y173992D01*
X520370Y174134D01*
X520724Y173780D01*
X520582Y173639D01*
G37*
G36*
G01X515915Y178871D02*
X516481Y179366D01*
X516764Y179084D01*
X516269Y178518D01*
X516128Y178376D01*
X515774Y178730D01*
X515915Y178871D01*
G37*
G36*
G01X514077Y180710D02*
X514643Y181205D01*
X514925Y180922D01*
X514431Y180356D01*
X514289Y180215D01*
X513936Y180568D01*
X514077Y180710D01*
G37*
G36*
G01X516905Y177316D02*
X516340Y176821D01*
X516057Y177104D01*
X516552Y177669D01*
X516693Y177811D01*
X517047Y177457D01*
X516905Y177316D01*
G37*
G36*
G01X515067Y179154D02*
X514501Y178659D01*
X514218Y178942D01*
X514713Y179508D01*
X514855Y179649D01*
X515208Y179296D01*
X515067Y179154D01*
G37*
G36*
G01X517754Y177033D02*
X518320Y177528D01*
X518602Y177245D01*
X518107Y176679D01*
X517966Y176538D01*
X517612Y176892D01*
X517754Y177033D01*
G37*
G36*
G01X518744Y175477D02*
X518178Y174982D01*
X517895Y175265D01*
X518390Y175831D01*
X518532Y175972D01*
X518885Y175619D01*
X518744Y175477D01*
G37*
G36*
G01X519592Y175194D02*
X520158Y175689D01*
X520441Y175407D01*
X519946Y174841D01*
X519805Y174699D01*
X519451Y175053D01*
X519592Y175194D01*
G37*
G36*
G01X480280Y183211D02*
X480846Y183705D01*
X481129Y183423D01*
X480634Y182857D01*
X480492Y182716D01*
X480139Y183069D01*
X480280Y183211D01*
G37*
G36*
G01X479433Y183493D02*
X478867Y182998D01*
X478584Y183281D01*
X479079Y183847D01*
X479221Y183988D01*
X479574Y183635D01*
X479433Y183493D01*
G37*
G36*
G01X481271Y181655D02*
X480706Y181160D01*
X480423Y181443D01*
X480918Y182008D01*
X481059Y182150D01*
X481413Y181796D01*
X481271Y181655D01*
G37*
G36*
G01X478442Y185049D02*
X479008Y185544D01*
X479290Y185261D01*
X478795Y184695D01*
X478654Y184554D01*
X478300Y184908D01*
X478442Y185049D01*
G37*
G36*
G01X486835Y180806D02*
X486785Y180056D01*
X486385D01*
X486335Y180806D01*
Y181006D01*
X486835D01*
Y180806D01*
G37*
G36*
G01X484235D02*
X484185Y180056D01*
X483785D01*
X483735Y180806D01*
Y181006D01*
X484235D01*
Y180806D01*
G37*
G36*
G01X485035Y181206D02*
X485085Y181956D01*
X485485D01*
X485535Y181206D01*
Y181006D01*
X485035D01*
Y181206D01*
G37*
G36*
G01X492035Y180806D02*
X491985Y180056D01*
X491585D01*
X491535Y180806D01*
Y181006D01*
X492035D01*
Y180806D01*
G37*
G36*
G01X492835Y181206D02*
X492885Y181956D01*
X493285D01*
X493335Y181206D01*
Y181006D01*
X492835D01*
Y181206D01*
G37*
G36*
G01X490235D02*
X490285Y181956D01*
X490685D01*
X490735Y181206D01*
Y181006D01*
X490235D01*
Y181206D01*
G37*
G36*
G01X489435Y180806D02*
X489385Y180056D01*
X488985D01*
X488935Y180806D01*
Y181006D01*
X489435D01*
Y180806D01*
G37*
G36*
G01X487635Y181206D02*
X487685Y181956D01*
X488085D01*
X488135Y181206D01*
Y181006D01*
X487635D01*
Y181206D01*
G37*
G36*
G01X497235Y180806D02*
X497185Y180056D01*
X496785D01*
X496735Y180806D01*
Y181006D01*
X497235D01*
Y180806D01*
G37*
G36*
G01X499835D02*
X499785Y180056D01*
X499385D01*
X499335Y180806D01*
Y181006D01*
X499835D01*
Y180806D01*
G37*
G36*
G01X494635D02*
X494585Y180056D01*
X494185D01*
X494135Y180806D01*
Y181006D01*
X494635D01*
Y180806D01*
G37*
G36*
G01X498035Y181206D02*
X498085Y181956D01*
X498485D01*
X498535Y181206D01*
Y181006D01*
X498035D01*
Y181206D01*
G37*
G36*
G01X495435D02*
X495485Y181956D01*
X495885D01*
X495935Y181206D01*
Y181006D01*
X495435D01*
Y181206D01*
G37*
G36*
G01X502435Y180806D02*
X502385Y180056D01*
X501985D01*
X501935Y180806D01*
Y181006D01*
X502435D01*
Y180806D01*
G37*
G36*
G01X505035D02*
X504985Y180056D01*
X504585D01*
X504535Y180806D01*
Y181006D01*
X505035D01*
Y180806D01*
G37*
G36*
G01X507635D02*
X507585Y180056D01*
X507185D01*
X507135Y180806D01*
Y181006D01*
X507635D01*
Y180806D01*
G37*
G36*
G01X500635Y181206D02*
X500685Y181956D01*
X501085D01*
X501135Y181206D01*
Y181006D01*
X500635D01*
Y181206D01*
G37*
G36*
G01X503235D02*
X503285Y181956D01*
X503685D01*
X503735Y181206D01*
Y181006D01*
X503235D01*
Y181206D01*
G37*
G36*
G01X505835D02*
X505885Y181956D01*
X506285D01*
X506335Y181206D01*
Y181006D01*
X505835D01*
Y181206D01*
G37*
G36*
G01X508435D02*
X508485Y181956D01*
X508885D01*
X508935Y181206D01*
Y181006D01*
X508435D01*
Y181206D01*
G37*
G36*
G01X511884Y178517D02*
X512450Y179012D01*
X512732Y178729D01*
X512238Y178163D01*
X512096Y178022D01*
X511743Y178375D01*
X511884Y178517D01*
G37*
G36*
G01X510045Y180355D02*
X510611Y180850D01*
X510894Y180568D01*
X510399Y180002D01*
X510258Y179860D01*
X509904Y180214D01*
X510045Y180355D01*
G37*
G36*
G01X512874Y176961D02*
X512308Y176466D01*
X512025Y176749D01*
X512520Y177315D01*
X512662Y177456D01*
X513015Y177103D01*
X512874Y176961D01*
G37*
G36*
G01X511035Y178800D02*
X510470Y178305D01*
X510187Y178588D01*
X510682Y179153D01*
X510823Y179295D01*
X511177Y178941D01*
X511035Y178800D01*
G37*
G36*
G01X516551Y173284D02*
X515985Y172789D01*
X515702Y173072D01*
X516197Y173638D01*
X516339Y173779D01*
X516692Y173426D01*
X516551Y173284D01*
G37*
G36*
G01X517399Y173001D02*
X517965Y173496D01*
X518248Y173214D01*
X517753Y172648D01*
X517612Y172506D01*
X517258Y172860D01*
X517399Y173001D01*
G37*
G36*
G01X519238Y171163D02*
X519804Y171658D01*
X520086Y171375D01*
X519591Y170809D01*
X519450Y170668D01*
X519096Y171022D01*
X519238Y171163D01*
G37*
G36*
G01X518389Y171446D02*
X517824Y170951D01*
X517541Y171234D01*
X518036Y171799D01*
X518177Y171941D01*
X518531Y171587D01*
X518389Y171446D01*
G37*
G36*
G01X520228Y169608D02*
X519663Y169113D01*
X519380Y169396D01*
X519875Y169961D01*
X520016Y170103D01*
X520370Y169749D01*
X520228Y169608D01*
G37*
G36*
G01X513722Y176678D02*
X514288Y177173D01*
X514571Y176891D01*
X514076Y176325D01*
X513935Y176183D01*
X513581Y176537D01*
X513722Y176678D01*
G37*
G36*
G01X515561Y174840D02*
X516127Y175335D01*
X516409Y175052D01*
X515914Y174486D01*
X515773Y174345D01*
X515419Y174699D01*
X515561Y174840D01*
G37*
G36*
G01X514712Y175123D02*
X514147Y174628D01*
X513864Y174911D01*
X514359Y175476D01*
X514500Y175618D01*
X514854Y175264D01*
X514712Y175123D01*
G37*
G36*
G01X478055Y192015D02*
X478621Y192510D01*
X478903Y192227D01*
X478408Y191661D01*
X478267Y191520D01*
X477913Y191874D01*
X478055Y192015D01*
G37*
G36*
G01X481732Y188338D02*
X482298Y188833D01*
X482580Y188550D01*
X482085Y187984D01*
X481944Y187843D01*
X481590Y188197D01*
X481732Y188338D01*
G37*
G36*
G01X479893Y190176D02*
X480459Y190671D01*
X480742Y190389D01*
X480247Y189823D01*
X480106Y189681D01*
X479752Y190035D01*
X479893Y190176D01*
G37*
G36*
G01X482722Y186782D02*
X482156Y186287D01*
X481873Y186570D01*
X482368Y187136D01*
X482510Y187277D01*
X482863Y186924D01*
X482722Y186782D01*
G37*
G36*
G01X479045Y190459D02*
X478479Y189964D01*
X478196Y190247D01*
X478691Y190813D01*
X478833Y190954D01*
X479186Y190601D01*
X479045Y190459D01*
G37*
G36*
G01X480883Y188621D02*
X480318Y188126D01*
X480035Y188409D01*
X480530Y188974D01*
X480671Y189116D01*
X481025Y188762D01*
X480883Y188621D01*
G37*
G36*
G01X486835Y185456D02*
X486785Y184706D01*
X486385D01*
X486335Y185456D01*
Y185656D01*
X486835D01*
Y185456D01*
G37*
G36*
G01X485035Y185856D02*
X485085Y186606D01*
X485485D01*
X485535Y185856D01*
Y185656D01*
X485035D01*
Y185856D01*
G37*
G36*
G01X489435Y185456D02*
X489385Y184706D01*
X488985D01*
X488935Y185456D01*
Y185656D01*
X489435D01*
Y185456D01*
G37*
G36*
G01X487635Y185856D02*
X487685Y186606D01*
X488085D01*
X488135Y185856D01*
Y185656D01*
X487635D01*
Y185856D01*
G37*
G36*
G01X492035Y185456D02*
X491985Y184706D01*
X491585D01*
X491535Y185456D01*
Y185656D01*
X492035D01*
Y185456D01*
G37*
G36*
G01X492835Y185856D02*
X492885Y186606D01*
X493285D01*
X493335Y185856D01*
Y185656D01*
X492835D01*
Y185856D01*
G37*
G36*
G01X490235D02*
X490285Y186606D01*
X490685D01*
X490735Y185856D01*
Y185656D01*
X490235D01*
Y185856D01*
G37*
G36*
G01X499835Y185456D02*
X499785Y184706D01*
X499385D01*
X499335Y185456D01*
Y185656D01*
X499835D01*
Y185456D01*
G37*
G36*
G01X497235D02*
X497185Y184706D01*
X496785D01*
X496735Y185456D01*
Y185656D01*
X497235D01*
Y185456D01*
G37*
G36*
G01X494635D02*
X494585Y184706D01*
X494185D01*
X494135Y185456D01*
Y185656D01*
X494635D01*
Y185456D01*
G37*
G36*
G01X498035Y185856D02*
X498085Y186606D01*
X498485D01*
X498535Y185856D01*
Y185656D01*
X498035D01*
Y185856D01*
G37*
G36*
G01X495435D02*
X495485Y186606D01*
X495885D01*
X495935Y185856D01*
Y185656D01*
X495435D01*
Y185856D01*
G37*
G36*
G01X502435Y185456D02*
X502385Y184706D01*
X501985D01*
X501935Y185456D01*
Y185656D01*
X502435D01*
Y185456D01*
G37*
G36*
G01X505035D02*
X504985Y184706D01*
X504585D01*
X504535Y185456D01*
Y185656D01*
X505035D01*
Y185456D01*
G37*
G36*
G01X507635D02*
X507585Y184706D01*
X507185D01*
X507135Y185456D01*
Y185656D01*
X507635D01*
Y185456D01*
G37*
G36*
G01X500635Y185856D02*
X500685Y186606D01*
X501085D01*
X501135Y185856D01*
Y185656D01*
X500635D01*
Y185856D01*
G37*
G36*
G01X503235D02*
X503285Y186606D01*
X503685D01*
X503735Y185856D01*
Y185656D01*
X503235D01*
Y185856D01*
G37*
G36*
G01X505835D02*
X505885Y186606D01*
X506285D01*
X506335Y185856D01*
Y185656D01*
X505835D01*
Y185856D01*
G37*
G36*
G01X511496Y185483D02*
X512062Y185978D01*
X512345Y185695D01*
X511850Y185130D01*
X511709Y184988D01*
X511355Y185342D01*
X511496Y185483D01*
G37*
G36*
G01X512486Y183928D02*
X511921Y183433D01*
X511638Y183716D01*
X512133Y184281D01*
X512274Y184423D01*
X512628Y184069D01*
X512486Y183928D01*
G37*
G36*
G01X508435Y185856D02*
X508485Y186606D01*
X508885D01*
X508935Y185856D01*
Y185656D01*
X508435D01*
Y185856D01*
G37*
G36*
G01X510235Y185456D02*
X510185Y184706D01*
X509785D01*
X509735Y185456D01*
Y185656D01*
X510235D01*
Y185456D01*
G37*
G36*
G01X523517Y172897D02*
X522952Y172402D01*
X522669Y172685D01*
X523164Y173250D01*
X523305Y173392D01*
X523659Y173038D01*
X523517Y172897D01*
G37*
G36*
G01X525356Y171058D02*
X524790Y170563D01*
X524507Y170846D01*
X525002Y171412D01*
X525144Y171553D01*
X525497Y171200D01*
X525356Y171058D01*
G37*
G36*
G01X524366Y172614D02*
X524932Y173109D01*
X525214Y172826D01*
X524719Y172260D01*
X524578Y172119D01*
X524224Y172473D01*
X524366Y172614D01*
G37*
G36*
G01X513335Y183645D02*
X513901Y184140D01*
X514184Y183857D01*
X513689Y183291D01*
X513547Y183150D01*
X513194Y183503D01*
X513335Y183645D01*
G37*
G36*
G01X514325Y182089D02*
X513759Y181594D01*
X513476Y181877D01*
X513971Y182443D01*
X514113Y182584D01*
X514466Y182231D01*
X514325Y182089D01*
G37*
G36*
G01X516163Y180251D02*
X515598Y179756D01*
X515315Y180039D01*
X515810Y180604D01*
X515951Y180746D01*
X516305Y180392D01*
X516163Y180251D01*
G37*
G36*
G01X518002Y178412D02*
X517436Y177917D01*
X517153Y178200D01*
X517648Y178766D01*
X517790Y178907D01*
X518143Y178554D01*
X518002Y178412D01*
G37*
G36*
G01X518850Y178129D02*
X519416Y178624D01*
X519699Y178342D01*
X519204Y177776D01*
X519063Y177634D01*
X518709Y177988D01*
X518850Y178129D01*
G37*
G36*
G01X517012Y179968D02*
X517578Y180463D01*
X517860Y180180D01*
X517365Y179614D01*
X517224Y179473D01*
X516871Y179826D01*
X517012Y179968D01*
G37*
G36*
G01X515173Y181806D02*
X515739Y182301D01*
X516022Y182019D01*
X515527Y181453D01*
X515386Y181311D01*
X515032Y181665D01*
X515173Y181806D01*
G37*
G36*
G01X519840Y176574D02*
X519275Y176079D01*
X518992Y176362D01*
X519487Y176927D01*
X519628Y177069D01*
X519982Y176715D01*
X519840Y176574D01*
G37*
G36*
G01X521679Y174735D02*
X521113Y174240D01*
X520830Y174523D01*
X521325Y175089D01*
X521467Y175230D01*
X521820Y174877D01*
X521679Y174735D01*
G37*
G36*
G01X520689Y176291D02*
X521255Y176786D01*
X521537Y176503D01*
X521042Y175937D01*
X520901Y175796D01*
X520547Y176150D01*
X520689Y176291D01*
G37*
G36*
G01X522527Y174452D02*
X523093Y174947D01*
X523376Y174665D01*
X522881Y174099D01*
X522739Y173958D01*
X522386Y174311D01*
X522527Y174452D01*
G37*
G36*
G01X537543Y202999D02*
G02X537924Y203518I382J119D01*
G01X538540D01*
G03X538656Y203389I1219J980D01*
G01X538736Y203309D01*
Y200455D01*
X522754D01*
X521271Y201938D01*
Y202759D01*
X521589D01*
X521646Y202656D01*
G03X521652Y202646I162J91D01*
G03X521670Y202620I251J155D01*
G03X521775Y202554I152J125D01*
G03X521839Y202546I64J256D01*
G01X521975D01*
G03X522006Y202547I10J179D01*
G01X522007Y202595D01*
X522009Y202635D01*
X522014Y202663D01*
X522016Y202669D01*
G03X522017Y202681I-71J12D01*
G01Y202682D01*
G02X522057Y202833I883J-153D01*
G02X522149Y203020I890J-322D01*
G02X522309Y203199I841J-590D01*
G02X522484Y203311I542J-654D01*
G02X522729Y203388I436J-959D01*
G02X522861Y203397I179J-1653D01*
G02X523043Y203377I23J-631D01*
G02X523277Y203285I-236J-945D01*
G03X523377Y203216I565J711D01*
G02X523483Y203118I-2100J-2378D01*
G02X523535Y203055I-740J-664D01*
G02X523635Y202885I-562J-445D01*
G01X523656Y202828D01*
G02X523698Y202651I-660J-250D01*
G02X523705Y202546I-879J-111D01*
G02X523763Y202547I37J-438D01*
G03X523854Y202546I57J1067D01*
G01X523902D01*
X523915Y202549D01*
G03X523938Y202554I-27J178D01*
G01X523962Y202558D01*
X523974Y202566D01*
X523983Y202571D01*
X523984D01*
X523990Y202575D01*
X523994Y202577D01*
X524000Y202582D01*
X524010Y202589D01*
G03X524014Y202592I-8J15D01*
G03X524035Y202614I-115J131D01*
G03X524045Y202625I-62J66D01*
G03X524066Y202657I-88J80D01*
G01X524067Y202658D01*
X524077Y202680D01*
G03X524080Y202695I-175J43D01*
G03X524086Y202713I-158J63D01*
G01X524089Y202750D01*
G03X521662Y202921I-1233J-198D01*
G01X521618Y202780D01*
X521271D01*
Y203565D01*
X522718Y205012D01*
X524831D01*
X524860Y204983D01*
X525147D01*
X525158Y204994D01*
X525231Y205000D01*
G03X526239Y205533I-120J1447D01*
G01X528625D01*
G03X529368Y205119I996J914D01*
G01X529429Y205107D01*
X529553Y204983D01*
X531046D01*
X531653Y204376D01*
X531662Y204310D01*
G03X532815Y203157I1339J186D01*
G01X532881Y203148D01*
X532987Y203042D01*
X535155D01*
Y202827D01*
G03X535142Y202758I1222J-266D01*
G03X535171Y202646I187J-11D01*
G03X535189Y202619I255J150D01*
G03X535294Y202553I152J126D01*
G03X535361Y202546I61J258D01*
G01X535490D01*
G03X535527I19J180D01*
G01X535528Y202595D01*
X535530Y202635D01*
X535535Y202664D01*
G03X535538Y202682I-70J21D01*
G02X535578Y202833I882J-153D01*
G02X535670Y203020I889J-321D01*
G02X535769Y203140I839J-591D01*
G03X536165Y203368I-517J1356D01*
G02X536248Y203387I276J-1015D01*
G02X536381Y203396I179J-1652D01*
G02X536562Y203376I22J-630D01*
G02X536797Y203284I-234J-944D01*
G03X536897Y203215I565J712D01*
G02X537002Y203117I-2111J-2367D01*
G02X537053Y203054I-745J-656D01*
G02X537154Y202885I-558J-448D01*
G01X537175Y202828D01*
G02X537217Y202651I-659J-250D01*
G02X537224Y202545I-878J-111D01*
G02X537282Y202546I37J-437D01*
G03X537378I48J1068D01*
G01X537398D01*
G02X537422I12J-91D01*
G01Y202545D01*
X537435Y202548D01*
G03X537461Y202554I-28J179D01*
G01X537480Y202561D01*
X537488Y202563D01*
X537489D01*
Y202564D01*
X537491D01*
X537495Y202566D01*
X537496D01*
X537500Y202569D01*
G03X537507Y202572I-1J12D01*
G01X537514Y202576D01*
X537515D01*
G02X537526Y202586I318J-338D01*
G03X537534Y202591I-6J18D01*
G03X537556Y202613I-113J135D01*
G03X537566Y202624I-63J67D01*
G03X537587Y202657I-90J80D01*
G02X537594Y202673I168J-64D01*
G03X537600Y202694I-170J60D01*
G03X537605Y202707I-157J68D01*
G02X537607Y202723I136J-9D01*
G01X537610Y202750D01*
G03X537543Y202999I-1235J-199D01*
G37*
G36*
G01X655409Y156501D02*
Y158050D01*
X656319Y158960D01*
X659367D01*
X659931Y158396D01*
Y144114D01*
X659030Y143213D01*
Y139285D01*
X658456Y138711D01*
Y133556D01*
X658400Y133500D01*
X651199D01*
X649899Y134800D01*
X585900D01*
X572600Y148100D01*
Y153000D01*
X545638Y179962D01*
X529847D01*
X515197Y194612D01*
X505388D01*
X504600Y195400D01*
Y205100D01*
X509226D01*
X509234Y205099D01*
G03X509450I108J1348D01*
G01X509458Y205100D01*
X511049D01*
X511083Y205087D01*
G03X512101I509J1360D01*
G01X512135Y205100D01*
X515986D01*
X515994Y205099D01*
G03X516210I108J1348D01*
G01X516218Y205100D01*
X517804D01*
X517838Y205087D01*
G03X518866I514J1358D01*
G01X518900Y205100D01*
X519498D01*
X520138Y204460D01*
Y201587D01*
X521909Y199816D01*
X521977D01*
X522339Y199454D01*
X535646D01*
X542800Y192300D01*
X570298D01*
X602898Y159700D01*
X612035D01*
X614337Y157398D01*
X645302D01*
X647000Y155700D01*
X647934D01*
X647943Y155699D01*
G03X648239I148J1746D01*
G01X648248Y155700D01*
X652934D01*
X652943Y155699D01*
G03X653239I148J1746D01*
G01X653248Y155700D01*
X654608D01*
X655409Y156501D01*
G37*
G36*
G01X479802Y400578D02*
X479132Y400928D01*
X479131Y401798D01*
X479802Y402147D01*
X479976Y402148D01*
X479977Y400578D01*
X479802D01*
G37*
G36*
G01X481424Y404206D02*
X482094Y403856D01*
Y402986D01*
X481424Y402636D01*
X481249D01*
Y404206D01*
X481424D01*
G37*
G36*
G01X481694Y440513D02*
X482189Y439947D01*
X481907Y439664D01*
X481341Y440159D01*
X481199Y440300D01*
X481553Y440654D01*
X481694Y440513D01*
G37*
G36*
G01X481977Y441361D02*
X481482Y441927D01*
X481765Y442210D01*
X482331Y441715D01*
X482472Y441573D01*
X482119Y441220D01*
X481977Y441361D01*
G37*
G36*
G01X479049Y438950D02*
X478999Y438200D01*
X478599D01*
X478549Y438950D01*
Y439150D01*
X479049D01*
Y438950D01*
G37*
G36*
G01X483533Y442351D02*
X484028Y441785D01*
X483745Y441503D01*
X483179Y441998D01*
X483038Y442139D01*
X483392Y442493D01*
X483533Y442351D01*
G37*
G36*
G01X479049Y437400D02*
X478999Y436650D01*
X478599D01*
X478549Y437400D01*
Y437600D01*
X479049D01*
Y437400D01*
G37*
G36*
G01X482791Y439416D02*
X483286Y438850D01*
X483003Y438568D01*
X482437Y439063D01*
X482296Y439204D01*
X482650Y439558D01*
X482791Y439416D01*
G37*
G36*
G01X481235Y438426D02*
X480740Y438992D01*
X481023Y439275D01*
X481589Y438780D01*
X481730Y438638D01*
X481377Y438285D01*
X481235Y438426D01*
G37*
G36*
G01X484629Y441255D02*
X485124Y440689D01*
X484842Y440406D01*
X484276Y440901D01*
X484134Y441042D01*
X484488Y441396D01*
X484629Y441255D01*
G37*
G36*
G01X483074Y440265D02*
X482579Y440830D01*
X482862Y441113D01*
X483427Y440618D01*
X483569Y440477D01*
X483215Y440123D01*
X483074Y440265D01*
G37*
G36*
G01X479049Y440500D02*
X478999Y439750D01*
X478599D01*
X478549Y440500D01*
Y440700D01*
X479049D01*
Y440500D01*
G37*
G36*
G01X480982Y424351D02*
X480932Y423601D01*
X480532D01*
X480482Y424351D01*
Y424551D01*
X480982D01*
Y424351D01*
G37*
G36*
G01X479182Y424751D02*
X479232Y425501D01*
X479632D01*
X479682Y424751D01*
Y424551D01*
X479182D01*
Y424751D01*
G37*
G36*
G01X481782D02*
X481832Y425501D01*
X482232D01*
X482282Y424751D01*
Y424551D01*
X481782D01*
Y424751D01*
G37*
G36*
G01X484382D02*
X484432Y425501D01*
X484832D01*
X484882Y424751D01*
Y424551D01*
X484382D01*
Y424751D01*
G37*
G36*
G01X486982D02*
X487032Y425501D01*
X487432D01*
X487482Y424751D01*
Y424551D01*
X486982D01*
Y424751D01*
G37*
G36*
G01X489582D02*
X489632Y425501D01*
X490032D01*
X490082Y424751D01*
Y424551D01*
X489582D01*
Y424751D01*
G37*
G36*
G01X483582Y424351D02*
X483532Y423601D01*
X483132D01*
X483082Y424351D01*
Y424551D01*
X483582D01*
Y424351D01*
G37*
G36*
G01X486182D02*
X486132Y423601D01*
X485732D01*
X485682Y424351D01*
Y424551D01*
X486182D01*
Y424351D01*
G37*
G36*
G01X488782D02*
X488732Y423601D01*
X488332D01*
X488282Y424351D01*
Y424551D01*
X488782D01*
Y424351D01*
G37*
G36*
G01X491382D02*
X491332Y423601D01*
X490932D01*
X490882Y424351D01*
Y424551D01*
X491382D01*
Y424351D01*
G37*
G36*
G01X492182Y424751D02*
X492232Y425501D01*
X492632D01*
X492682Y424751D01*
Y424551D01*
X492182D01*
Y424751D01*
G37*
G36*
G01X499182Y424351D02*
X499132Y423601D01*
X498732D01*
X498682Y424351D01*
Y424551D01*
X499182D01*
Y424351D01*
G37*
G36*
G01X496582D02*
X496532Y423601D01*
X496132D01*
X496082Y424351D01*
Y424551D01*
X496582D01*
Y424351D01*
G37*
G36*
G01X493982D02*
X493932Y423601D01*
X493532D01*
X493482Y424351D01*
Y424551D01*
X493982D01*
Y424351D01*
G37*
G36*
G01X497382Y424751D02*
X497432Y425501D01*
X497832D01*
X497882Y424751D01*
Y424551D01*
X497382D01*
Y424751D01*
G37*
G36*
G01X494782D02*
X494832Y425501D01*
X495232D01*
X495282Y424751D01*
Y424551D01*
X494782D01*
Y424751D01*
G37*
G36*
G01X504382Y424351D02*
X504332Y423601D01*
X503932D01*
X503882Y424351D01*
Y424551D01*
X504382D01*
Y424351D01*
G37*
G36*
G01X501782D02*
X501732Y423601D01*
X501332D01*
X501282Y424351D01*
Y424551D01*
X501782D01*
Y424351D01*
G37*
G36*
G01X505182Y424751D02*
X505232Y425501D01*
X505632D01*
X505682Y424751D01*
Y424551D01*
X505182D01*
Y424751D01*
G37*
G36*
G01X502582D02*
X502632Y425501D01*
X503032D01*
X503082Y424751D01*
Y424551D01*
X502582D01*
Y424751D01*
G37*
G36*
G01X499982D02*
X500032Y425501D01*
X500432D01*
X500482Y424751D01*
Y424551D01*
X499982D01*
Y424751D01*
G37*
G36*
G01X506982Y424351D02*
X506932Y423601D01*
X506532D01*
X506482Y424351D01*
Y424551D01*
X506982D01*
Y424351D01*
G37*
G36*
G01X509582D02*
X509532Y423601D01*
X509132D01*
X509082Y424351D01*
Y424551D01*
X509582D01*
Y424351D01*
G37*
G36*
G01X507782Y424751D02*
X507832Y425501D01*
X508232D01*
X508282Y424751D01*
Y424551D01*
X507782D01*
Y424751D01*
G37*
G36*
G01X513338Y426785D02*
X512843Y427350D01*
X513126Y427633D01*
X513691Y427138D01*
X513833Y426997D01*
X513479Y426643D01*
X513338Y426785D01*
G37*
G36*
G01X513055Y425936D02*
X513550Y425370D01*
X513267Y425088D01*
X512701Y425583D01*
X512560Y425724D01*
X512914Y426078D01*
X513055Y425936D01*
G37*
G36*
G01X510382Y424751D02*
X510432Y425501D01*
X510832D01*
X510882Y424751D01*
Y424551D01*
X510382D01*
Y424751D01*
G37*
G36*
G01X515176Y428623D02*
X514681Y429189D01*
X514964Y429472D01*
X515530Y428977D01*
X515671Y428835D01*
X515318Y428482D01*
X515176Y428623D01*
G37*
G36*
G01X516732Y429613D02*
X517227Y429047D01*
X516944Y428765D01*
X516378Y429260D01*
X516237Y429401D01*
X516590Y429754D01*
X516732Y429613D01*
G37*
G36*
G01X514893Y427775D02*
X515388Y427209D01*
X515106Y426926D01*
X514540Y427421D01*
X514398Y427562D01*
X514752Y427916D01*
X514893Y427775D01*
G37*
G36*
G01X517015Y430462D02*
X516520Y431027D01*
X516803Y431310D01*
X517368Y430815D01*
X517510Y430674D01*
X517156Y430320D01*
X517015Y430462D01*
G37*
G36*
G01X518570Y431452D02*
X519065Y430886D01*
X518783Y430603D01*
X518217Y431098D01*
X518075Y431239D01*
X518429Y431593D01*
X518570Y431452D01*
G37*
G36*
G01X518853Y432300D02*
X518358Y432866D01*
X518641Y433149D01*
X519207Y432654D01*
X519348Y432512D01*
X518995Y432159D01*
X518853Y432300D01*
G37*
G36*
G01X480982Y422801D02*
X480932Y422051D01*
X480532D01*
X480482Y422801D01*
Y423001D01*
X480982D01*
Y422801D01*
G37*
G36*
G01X478735Y422160D02*
X479230Y421594D01*
X478948Y421311D01*
X478382Y421806D01*
X478240Y421947D01*
X478594Y422301D01*
X478735Y422160D01*
G37*
G36*
G01X481782Y423201D02*
X481832Y423951D01*
X482232D01*
X482282Y423201D01*
Y423001D01*
X481782D01*
Y423201D01*
G37*
G36*
G01X483582Y422801D02*
X483532Y422051D01*
X483132D01*
X483082Y422801D01*
Y423001D01*
X483582D01*
Y422801D01*
G37*
G36*
G01X486182D02*
X486132Y422051D01*
X485732D01*
X485682Y422801D01*
Y423001D01*
X486182D01*
Y422801D01*
G37*
G36*
G01X488782D02*
X488732Y422051D01*
X488332D01*
X488282Y422801D01*
Y423001D01*
X488782D01*
Y422801D01*
G37*
G36*
G01X484382Y423201D02*
X484432Y423951D01*
X484832D01*
X484882Y423201D01*
Y423001D01*
X484382D01*
Y423201D01*
G37*
G36*
G01X486982D02*
X487032Y423951D01*
X487432D01*
X487482Y423201D01*
Y423001D01*
X486982D01*
Y423201D01*
G37*
G36*
G01X489582D02*
X489632Y423951D01*
X490032D01*
X490082Y423201D01*
Y423001D01*
X489582D01*
Y423201D01*
G37*
G36*
G01X491382Y422801D02*
X491332Y422051D01*
X490932D01*
X490882Y422801D01*
Y423001D01*
X491382D01*
Y422801D01*
G37*
G36*
G01X499182D02*
X499132Y422051D01*
X498732D01*
X498682Y422801D01*
Y423001D01*
X499182D01*
Y422801D01*
G37*
G36*
G01X496582D02*
X496532Y422051D01*
X496132D01*
X496082Y422801D01*
Y423001D01*
X496582D01*
Y422801D01*
G37*
G36*
G01X493982D02*
X493932Y422051D01*
X493532D01*
X493482Y422801D01*
Y423001D01*
X493982D01*
Y422801D01*
G37*
G36*
G01X497382Y423201D02*
X497432Y423951D01*
X497832D01*
X497882Y423201D01*
Y423001D01*
X497382D01*
Y423201D01*
G37*
G36*
G01X494782D02*
X494832Y423951D01*
X495232D01*
X495282Y423201D01*
Y423001D01*
X494782D01*
Y423201D01*
G37*
G36*
G01X492182D02*
X492232Y423951D01*
X492632D01*
X492682Y423201D01*
Y423001D01*
X492182D01*
Y423201D01*
G37*
G36*
G01X504382Y422801D02*
X504332Y422051D01*
X503932D01*
X503882Y422801D01*
Y423001D01*
X504382D01*
Y422801D01*
G37*
G36*
G01X501782D02*
X501732Y422051D01*
X501332D01*
X501282Y422801D01*
Y423001D01*
X501782D01*
Y422801D01*
G37*
G36*
G01X506982D02*
X506932Y422051D01*
X506532D01*
X506482Y422801D01*
Y423001D01*
X506982D01*
Y422801D01*
G37*
G36*
G01X505182Y423201D02*
X505232Y423951D01*
X505632D01*
X505682Y423201D01*
Y423001D01*
X505182D01*
Y423201D01*
G37*
G36*
G01X502582D02*
X502632Y423951D01*
X503032D01*
X503082Y423201D01*
Y423001D01*
X502582D01*
Y423201D01*
G37*
G36*
G01X499982D02*
X500032Y423951D01*
X500432D01*
X500482Y423201D01*
Y423001D01*
X499982D01*
Y423201D01*
G37*
G36*
G01X509582Y422801D02*
X509532Y422051D01*
X509132D01*
X509082Y422801D01*
Y423001D01*
X509582D01*
Y422801D01*
G37*
G36*
G01X507782Y423201D02*
X507832Y423951D01*
X508232D01*
X508282Y423201D01*
Y423001D01*
X507782D01*
Y423201D01*
G37*
G36*
G01X512596Y423850D02*
X512101Y424415D01*
X512384Y424698D01*
X512949Y424203D01*
X513091Y424062D01*
X512737Y423708D01*
X512596Y423850D01*
G37*
G36*
G01X514151Y424840D02*
X514646Y424274D01*
X514364Y423991D01*
X513798Y424486D01*
X513656Y424627D01*
X514010Y424981D01*
X514151Y424840D01*
G37*
G36*
G01X510382Y423201D02*
X510432Y423951D01*
X510832D01*
X510882Y423201D01*
Y423001D01*
X510382D01*
Y423201D01*
G37*
G36*
G01X518111Y429365D02*
X517616Y429931D01*
X517899Y430214D01*
X518465Y429719D01*
X518606Y429577D01*
X518253Y429224D01*
X518111Y429365D01*
G37*
G36*
G01X516273Y427527D02*
X515778Y428092D01*
X516061Y428375D01*
X516626Y427880D01*
X516768Y427739D01*
X516414Y427385D01*
X516273Y427527D01*
G37*
G36*
G01X514434Y425688D02*
X513939Y426254D01*
X514222Y426537D01*
X514788Y426042D01*
X514929Y425900D01*
X514576Y425547D01*
X514434Y425688D01*
G37*
G36*
G01X519667Y430355D02*
X520162Y429789D01*
X519879Y429507D01*
X519313Y430001D01*
X519172Y430143D01*
X519525Y430496D01*
X519667Y430355D01*
G37*
G36*
G01X517828Y428517D02*
X518323Y427951D01*
X518041Y427668D01*
X517475Y428163D01*
X517333Y428304D01*
X517687Y428658D01*
X517828Y428517D01*
G37*
G36*
G01X515990Y426678D02*
X516485Y426112D01*
X516202Y425830D01*
X515636Y426325D01*
X515495Y426466D01*
X515849Y426820D01*
X515990Y426678D01*
G37*
G36*
G01X519950Y431204D02*
X519455Y431769D01*
X519738Y432052D01*
X520303Y431557D01*
X520445Y431416D01*
X520091Y431062D01*
X519950Y431204D01*
G37*
G36*
G01X521505Y432194D02*
X522000Y431628D01*
X521718Y431345D01*
X521152Y431840D01*
X521010Y431981D01*
X521364Y432335D01*
X521505Y432194D01*
G37*
G36*
G01X481563Y409433D02*
X481068Y409998D01*
X481351Y410281D01*
X481916Y409786D01*
X482058Y409645D01*
X481704Y409291D01*
X481563Y409433D01*
G37*
G36*
G01X481280Y408584D02*
X481775Y408018D01*
X481492Y407736D01*
X480926Y408231D01*
X480785Y408372D01*
X481139Y408726D01*
X481280Y408584D01*
G37*
G36*
G01X486982Y412351D02*
X487032Y413101D01*
X487432D01*
X487482Y412351D01*
Y412151D01*
X486982D01*
Y412351D01*
G37*
G36*
G01X488782Y411951D02*
X488732Y411201D01*
X488332D01*
X488282Y411951D01*
Y412151D01*
X488782D01*
Y411951D01*
G37*
G36*
G01X489582Y412351D02*
X489632Y413101D01*
X490032D01*
X490082Y412351D01*
Y412151D01*
X489582D01*
Y412351D01*
G37*
G36*
G01X486182Y411951D02*
X486132Y411201D01*
X485732D01*
X485682Y411951D01*
Y412151D01*
X486182D01*
Y411951D01*
G37*
G36*
G01X483118Y410423D02*
X483613Y409857D01*
X483331Y409574D01*
X482765Y410069D01*
X482623Y410210D01*
X482977Y410564D01*
X483118Y410423D01*
G37*
G36*
G01X483401Y411271D02*
X482906Y411837D01*
X483189Y412120D01*
X483755Y411625D01*
X483896Y411483D01*
X483543Y411130D01*
X483401Y411271D01*
G37*
G36*
G01X491382Y411951D02*
X491332Y411201D01*
X490932D01*
X490882Y411951D01*
Y412151D01*
X491382D01*
Y411951D01*
G37*
G36*
G01X493982D02*
X493932Y411201D01*
X493532D01*
X493482Y411951D01*
Y412151D01*
X493982D01*
Y411951D01*
G37*
G36*
G01X496582D02*
X496532Y411201D01*
X496132D01*
X496082Y411951D01*
Y412151D01*
X496582D01*
Y411951D01*
G37*
G36*
G01X499182D02*
X499132Y411201D01*
X498732D01*
X498682Y411951D01*
Y412151D01*
X499182D01*
Y411951D01*
G37*
G36*
G01X492182Y412351D02*
X492232Y413101D01*
X492632D01*
X492682Y412351D01*
Y412151D01*
X492182D01*
Y412351D01*
G37*
G36*
G01X494782D02*
X494832Y413101D01*
X495232D01*
X495282Y412351D01*
Y412151D01*
X494782D01*
Y412351D01*
G37*
G36*
G01X497382D02*
X497432Y413101D01*
X497832D01*
X497882Y412351D01*
Y412151D01*
X497382D01*
Y412351D01*
G37*
G36*
G01X501782Y411951D02*
X501732Y411201D01*
X501332D01*
X501282Y411951D01*
Y412151D01*
X501782D01*
Y411951D01*
G37*
G36*
G01X499982Y412351D02*
X500032Y413101D01*
X500432D01*
X500482Y412351D01*
Y412151D01*
X499982D01*
Y412351D01*
G37*
G36*
G01X505182D02*
X505232Y413101D01*
X505632D01*
X505682Y412351D01*
Y412151D01*
X505182D01*
Y412351D01*
G37*
G36*
G01X502582D02*
X502632Y413101D01*
X503032D01*
X503082Y412351D01*
Y412151D01*
X502582D01*
Y412351D01*
G37*
G36*
G01X506982Y411951D02*
X506932Y411201D01*
X506532D01*
X506482Y411951D01*
Y412151D01*
X506982D01*
Y411951D01*
G37*
G36*
G01X504382D02*
X504332Y411201D01*
X503932D01*
X503882Y411951D01*
Y412151D01*
X504382D01*
Y411951D01*
G37*
G36*
G01X509582D02*
X509532Y411201D01*
X509132D01*
X509082Y411951D01*
Y412151D01*
X509582D01*
Y411951D01*
G37*
G36*
G01X507782Y412351D02*
X507832Y413101D01*
X508232D01*
X508282Y412351D01*
Y412151D01*
X507782D01*
Y412351D01*
G37*
G36*
G01X514782Y411951D02*
X514732Y411201D01*
X514332D01*
X514282Y411951D01*
Y412151D01*
X514782D01*
Y411951D01*
G37*
G36*
G01X512182D02*
X512132Y411201D01*
X511732D01*
X511682Y411951D01*
Y412151D01*
X512182D01*
Y411951D01*
G37*
G36*
G01X515582Y412351D02*
X515632Y413101D01*
X516032D01*
X516082Y412351D01*
Y412151D01*
X515582D01*
Y412351D01*
G37*
G36*
G01X512982D02*
X513032Y413101D01*
X513432D01*
X513482Y412351D01*
Y412151D01*
X512982D01*
Y412351D01*
G37*
G36*
G01X510382D02*
X510432Y413101D01*
X510832D01*
X510882Y412351D01*
Y412151D01*
X510382D01*
Y412351D01*
G37*
G36*
G01X518434Y414335D02*
X517939Y414900D01*
X518222Y415183D01*
X518787Y414688D01*
X518929Y414547D01*
X518575Y414193D01*
X518434Y414335D01*
G37*
G36*
G01X518151Y413486D02*
X518646Y412920D01*
X518363Y412638D01*
X517797Y413133D01*
X517656Y413274D01*
X518010Y413628D01*
X518151Y413486D01*
G37*
G36*
G01X519989Y415325D02*
X520484Y414759D01*
X520202Y414476D01*
X519636Y414971D01*
X519495Y415113D01*
X519848Y415466D01*
X519989Y415325D01*
G37*
G36*
G01X520272Y416173D02*
X519777Y416739D01*
X520060Y417022D01*
X520626Y416527D01*
X520767Y416385D01*
X520414Y416032D01*
X520272Y416173D01*
G37*
G36*
G01X521828Y417163D02*
X522323Y416597D01*
X522040Y416315D01*
X521474Y416810D01*
X521333Y416951D01*
X521687Y417305D01*
X521828Y417163D01*
G37*
G36*
G01X522111Y418012D02*
X521616Y418577D01*
X521899Y418860D01*
X522464Y418365D01*
X522606Y418224D01*
X522252Y417870D01*
X522111Y418012D01*
G37*
G36*
G01X523949Y419850D02*
X523454Y420416D01*
X523737Y420699D01*
X524303Y420204D01*
X524444Y420062D01*
X524091Y419709D01*
X523949Y419850D01*
G37*
G36*
G01X523666Y419002D02*
X524161Y418436D01*
X523879Y418153D01*
X523313Y418648D01*
X523171Y418789D01*
X523525Y419143D01*
X523666Y419002D01*
G37*
G36*
G01X525505Y420840D02*
X526000Y420274D01*
X525717Y419992D01*
X525151Y420487D01*
X525010Y420628D01*
X525363Y420981D01*
X525505Y420840D01*
G37*
G36*
G01X525788Y421689D02*
X525293Y422254D01*
X525576Y422537D01*
X526141Y422042D01*
X526283Y421901D01*
X525929Y421547D01*
X525788Y421689D01*
G37*
G36*
G01X527344Y422679D02*
X527839Y422113D01*
X527556Y421831D01*
X526990Y422326D01*
X526849Y422467D01*
X527202Y422820D01*
X527344Y422679D01*
G37*
G36*
G01X527627Y423528D02*
X527132Y424093D01*
X527415Y424376D01*
X527980Y423881D01*
X528122Y423740D01*
X527768Y423386D01*
X527627Y423528D01*
G37*
G36*
G01X482660Y408336D02*
X482165Y408901D01*
X482448Y409184D01*
X483013Y408689D01*
X483155Y408548D01*
X482801Y408194D01*
X482660Y408336D01*
G37*
G36*
G01X486182Y410401D02*
X486132Y409651D01*
X485732D01*
X485682Y410401D01*
Y410601D01*
X486182D01*
Y410401D01*
G37*
G36*
G01X484215Y409326D02*
X484710Y408760D01*
X484428Y408477D01*
X483862Y408972D01*
X483720Y409113D01*
X484074Y409467D01*
X484215Y409326D01*
G37*
G36*
G01X484498Y410174D02*
X484003Y410740D01*
X484286Y411023D01*
X484852Y410528D01*
X484993Y410386D01*
X484640Y410033D01*
X484498Y410174D01*
G37*
G36*
G01X486982Y410801D02*
X487032Y411551D01*
X487432D01*
X487482Y410801D01*
Y410601D01*
X486982D01*
Y410801D01*
G37*
G36*
G01X489582D02*
X489632Y411551D01*
X490032D01*
X490082Y410801D01*
Y410601D01*
X489582D01*
Y410801D01*
G37*
G36*
G01X488782Y410401D02*
X488732Y409651D01*
X488332D01*
X488282Y410401D01*
Y410601D01*
X488782D01*
Y410401D01*
G37*
G36*
G01X491382D02*
X491332Y409651D01*
X490932D01*
X490882Y410401D01*
Y410601D01*
X491382D01*
Y410401D01*
G37*
G36*
G01X492182Y410801D02*
X492232Y411551D01*
X492632D01*
X492682Y410801D01*
Y410601D01*
X492182D01*
Y410801D01*
G37*
G36*
G01X494782D02*
X494832Y411551D01*
X495232D01*
X495282Y410801D01*
Y410601D01*
X494782D01*
Y410801D01*
G37*
G36*
G01X497382D02*
X497432Y411551D01*
X497832D01*
X497882Y410801D01*
Y410601D01*
X497382D01*
Y410801D01*
G37*
G36*
G01X499182Y410401D02*
X499132Y409651D01*
X498732D01*
X498682Y410401D01*
Y410601D01*
X499182D01*
Y410401D01*
G37*
G36*
G01X493982D02*
X493932Y409651D01*
X493532D01*
X493482Y410401D01*
Y410601D01*
X493982D01*
Y410401D01*
G37*
G36*
G01X496582D02*
X496532Y409651D01*
X496132D01*
X496082Y410401D01*
Y410601D01*
X496582D01*
Y410401D01*
G37*
G36*
G01X505182Y410801D02*
X505232Y411551D01*
X505632D01*
X505682Y410801D01*
Y410601D01*
X505182D01*
Y410801D01*
G37*
G36*
G01X502582D02*
X502632Y411551D01*
X503032D01*
X503082Y410801D01*
Y410601D01*
X502582D01*
Y410801D01*
G37*
G36*
G01X499982D02*
X500032Y411551D01*
X500432D01*
X500482Y410801D01*
Y410601D01*
X499982D01*
Y410801D01*
G37*
G36*
G01X504382Y410401D02*
X504332Y409651D01*
X503932D01*
X503882Y410401D01*
Y410601D01*
X504382D01*
Y410401D01*
G37*
G36*
G01X501782D02*
X501732Y409651D01*
X501332D01*
X501282Y410401D01*
Y410601D01*
X501782D01*
Y410401D01*
G37*
G36*
G01X506982D02*
X506932Y409651D01*
X506532D01*
X506482Y410401D01*
Y410601D01*
X506982D01*
Y410401D01*
G37*
G36*
G01X509582D02*
X509532Y409651D01*
X509132D01*
X509082Y410401D01*
Y410601D01*
X509582D01*
Y410401D01*
G37*
G36*
G01X507782Y410801D02*
X507832Y411551D01*
X508232D01*
X508282Y410801D01*
Y410601D01*
X507782D01*
Y410801D01*
G37*
G36*
G01X517692Y411400D02*
X517197Y411965D01*
X517480Y412248D01*
X518045Y411753D01*
X518187Y411612D01*
X517833Y411258D01*
X517692Y411400D01*
G37*
G36*
G01X519530Y413238D02*
X519035Y413804D01*
X519318Y414087D01*
X519884Y413592D01*
X520025Y413450D01*
X519672Y413097D01*
X519530Y413238D01*
G37*
G36*
G01X521369Y415077D02*
X520874Y415642D01*
X521157Y415925D01*
X521722Y415430D01*
X521864Y415289D01*
X521510Y414935D01*
X521369Y415077D01*
G37*
G36*
G01X519248Y412390D02*
X519742Y411824D01*
X519460Y411541D01*
X518894Y412036D01*
X518753Y412178D01*
X519106Y412531D01*
X519248Y412390D01*
G37*
G36*
G01X521086Y414228D02*
X521581Y413662D01*
X521298Y413380D01*
X520732Y413875D01*
X520591Y414016D01*
X520945Y414370D01*
X521086Y414228D01*
G37*
G36*
G01X522924Y416067D02*
X523419Y415501D01*
X523137Y415218D01*
X522571Y415713D01*
X522429Y415854D01*
X522783Y416208D01*
X522924Y416067D01*
G37*
G36*
G01X515582Y410801D02*
X515632Y411551D01*
X516032D01*
X516082Y410801D01*
Y410601D01*
X515582D01*
Y410801D01*
G37*
G36*
G01X512982D02*
X513032Y411551D01*
X513432D01*
X513482Y410801D01*
Y410601D01*
X512982D01*
Y410801D01*
G37*
G36*
G01X510382D02*
X510432Y411551D01*
X510832D01*
X510882Y410801D01*
Y410601D01*
X510382D01*
Y410801D01*
G37*
G36*
G01X514782Y410401D02*
X514732Y409651D01*
X514332D01*
X514282Y410401D01*
Y410601D01*
X514782D01*
Y410401D01*
G37*
G36*
G01X512182D02*
X512132Y409651D01*
X511732D01*
X511682Y410401D01*
Y410601D01*
X512182D01*
Y410401D01*
G37*
G36*
G01X523207Y416915D02*
X522712Y417481D01*
X522995Y417764D01*
X523561Y417269D01*
X523702Y417127D01*
X523349Y416774D01*
X523207Y416915D01*
G37*
G36*
G01X524763Y417905D02*
X525258Y417339D01*
X524975Y417057D01*
X524409Y417552D01*
X524268Y417693D01*
X524622Y418047D01*
X524763Y417905D01*
G37*
G36*
G01X525046Y418754D02*
X524551Y419319D01*
X524834Y419602D01*
X525399Y419107D01*
X525541Y418966D01*
X525187Y418612D01*
X525046Y418754D01*
G37*
G36*
G01X526602Y419744D02*
X527097Y419178D01*
X526814Y418896D01*
X526248Y419391D01*
X526107Y419532D01*
X526461Y419886D01*
X526602Y419744D01*
G37*
G36*
G01X526885Y420593D02*
X526390Y421158D01*
X526673Y421441D01*
X527238Y420946D01*
X527380Y420805D01*
X527026Y420451D01*
X526885Y420593D01*
G37*
G36*
G01X528441Y421583D02*
X528936Y421017D01*
X528653Y420735D01*
X528087Y421230D01*
X527946Y421371D01*
X528300Y421725D01*
X528441Y421583D01*
G37*
G36*
G01X528724Y422432D02*
X528229Y422997D01*
X528512Y423280D01*
X529077Y422785D01*
X529219Y422644D01*
X528865Y422290D01*
X528724Y422432D01*
G37*
G36*
G01X478382Y427451D02*
X478332Y426701D01*
X477932D01*
X477882Y427451D01*
Y427651D01*
X478382D01*
Y427451D01*
G37*
G36*
G01X480982D02*
X480932Y426701D01*
X480532D01*
X480482Y427451D01*
Y427651D01*
X480982D01*
Y427451D01*
G37*
G36*
G01X479182Y427851D02*
X479232Y428601D01*
X479632D01*
X479682Y427851D01*
Y427651D01*
X479182D01*
Y427851D01*
G37*
G36*
G01X481782D02*
X481832Y428601D01*
X482232D01*
X482282Y427851D01*
Y427651D01*
X481782D01*
Y427851D01*
G37*
G36*
G01X483582Y427451D02*
X483532Y426701D01*
X483132D01*
X483082Y427451D01*
Y427651D01*
X483582D01*
Y427451D01*
G37*
G36*
G01X486182D02*
X486132Y426701D01*
X485732D01*
X485682Y427451D01*
Y427651D01*
X486182D01*
Y427451D01*
G37*
G36*
G01X488782D02*
X488732Y426701D01*
X488332D01*
X488282Y427451D01*
Y427651D01*
X488782D01*
Y427451D01*
G37*
G36*
G01X484382Y427851D02*
X484432Y428601D01*
X484832D01*
X484882Y427851D01*
Y427651D01*
X484382D01*
Y427851D01*
G37*
G36*
G01X486982D02*
X487032Y428601D01*
X487432D01*
X487482Y427851D01*
Y427651D01*
X486982D01*
Y427851D01*
G37*
G36*
G01X489582D02*
X489632Y428601D01*
X490032D01*
X490082Y427851D01*
Y427651D01*
X489582D01*
Y427851D01*
G37*
G36*
G01X491382Y427451D02*
X491332Y426701D01*
X490932D01*
X490882Y427451D01*
Y427651D01*
X491382D01*
Y427451D01*
G37*
G36*
G01X493982D02*
X493932Y426701D01*
X493532D01*
X493482Y427451D01*
Y427651D01*
X493982D01*
Y427451D01*
G37*
G36*
G01X499182D02*
X499132Y426701D01*
X498732D01*
X498682Y427451D01*
Y427651D01*
X499182D01*
Y427451D01*
G37*
G36*
G01X496582D02*
X496532Y426701D01*
X496132D01*
X496082Y427451D01*
Y427651D01*
X496582D01*
Y427451D01*
G37*
G36*
G01X492182Y427851D02*
X492232Y428601D01*
X492632D01*
X492682Y427851D01*
Y427651D01*
X492182D01*
Y427851D01*
G37*
G36*
G01X494782D02*
X494832Y428601D01*
X495232D01*
X495282Y427851D01*
Y427651D01*
X494782D01*
Y427851D01*
G37*
G36*
G01X497382D02*
X497432Y428601D01*
X497832D01*
X497882Y427851D01*
Y427651D01*
X497382D01*
Y427851D01*
G37*
G36*
G01X505182D02*
X505232Y428601D01*
X505632D01*
X505682Y427851D01*
Y427651D01*
X505182D01*
Y427851D01*
G37*
G36*
G01X502582D02*
X502632Y428601D01*
X503032D01*
X503082Y427851D01*
Y427651D01*
X502582D01*
Y427851D01*
G37*
G36*
G01X499982D02*
X500032Y428601D01*
X500432D01*
X500482Y427851D01*
Y427651D01*
X499982D01*
Y427851D01*
G37*
G36*
G01X504382Y427451D02*
X504332Y426701D01*
X503932D01*
X503882Y427451D01*
Y427651D01*
X504382D01*
Y427451D01*
G37*
G36*
G01X501782D02*
X501732Y426701D01*
X501332D01*
X501282Y427451D01*
Y427651D01*
X501782D01*
Y427451D01*
G37*
G36*
G01X506982D02*
X506932Y426701D01*
X506532D01*
X506482Y427451D01*
Y427651D01*
X506982D01*
Y427451D01*
G37*
G36*
G01X507782Y427851D02*
X507832Y428601D01*
X508232D01*
X508282Y427851D01*
Y427651D01*
X507782D01*
Y427851D01*
G37*
G36*
G01X510862Y428129D02*
X511357Y427563D01*
X511074Y427281D01*
X510508Y427776D01*
X510367Y427917D01*
X510721Y428271D01*
X510862Y428129D01*
G37*
G36*
G01X512700Y429968D02*
X513195Y429402D01*
X512913Y429119D01*
X512347Y429614D01*
X512205Y429755D01*
X512559Y430109D01*
X512700Y429968D01*
G37*
G36*
G01X511145Y428978D02*
X510650Y429543D01*
X510933Y429826D01*
X511498Y429331D01*
X511640Y429190D01*
X511286Y428836D01*
X511145Y428978D01*
G37*
G36*
G01X509582Y427451D02*
X509532Y426701D01*
X509132D01*
X509082Y427451D01*
Y427651D01*
X509582D01*
Y427451D01*
G37*
G36*
G01X512983Y430816D02*
X512488Y431382D01*
X512771Y431665D01*
X513337Y431170D01*
X513478Y431028D01*
X513125Y430675D01*
X512983Y430816D01*
G37*
G36*
G01X514539Y431806D02*
X515034Y431240D01*
X514751Y430958D01*
X514185Y431453D01*
X514044Y431594D01*
X514397Y431947D01*
X514539Y431806D01*
G37*
G36*
G01X514822Y432655D02*
X514327Y433220D01*
X514610Y433503D01*
X515175Y433008D01*
X515317Y432867D01*
X514963Y432513D01*
X514822Y432655D01*
G37*
G36*
G01X480982Y425901D02*
X480932Y425151D01*
X480532D01*
X480482Y425901D01*
Y426101D01*
X480982D01*
Y425901D01*
G37*
G36*
G01X479182Y426301D02*
X479232Y427051D01*
X479632D01*
X479682Y426301D01*
Y426101D01*
X479182D01*
Y426301D01*
G37*
G36*
G01X481782D02*
X481832Y427051D01*
X482232D01*
X482282Y426301D01*
Y426101D01*
X481782D01*
Y426301D01*
G37*
G36*
G01X483582Y425901D02*
X483532Y425151D01*
X483132D01*
X483082Y425901D01*
Y426101D01*
X483582D01*
Y425901D01*
G37*
G36*
G01X486182D02*
X486132Y425151D01*
X485732D01*
X485682Y425901D01*
Y426101D01*
X486182D01*
Y425901D01*
G37*
G36*
G01X488782D02*
X488732Y425151D01*
X488332D01*
X488282Y425901D01*
Y426101D01*
X488782D01*
Y425901D01*
G37*
G36*
G01X484382Y426301D02*
X484432Y427051D01*
X484832D01*
X484882Y426301D01*
Y426101D01*
X484382D01*
Y426301D01*
G37*
G36*
G01X486982D02*
X487032Y427051D01*
X487432D01*
X487482Y426301D01*
Y426101D01*
X486982D01*
Y426301D01*
G37*
G36*
G01X489582D02*
X489632Y427051D01*
X490032D01*
X490082Y426301D01*
Y426101D01*
X489582D01*
Y426301D01*
G37*
G36*
G01X491382Y425901D02*
X491332Y425151D01*
X490932D01*
X490882Y425901D01*
Y426101D01*
X491382D01*
Y425901D01*
G37*
G36*
G01X493982D02*
X493932Y425151D01*
X493532D01*
X493482Y425901D01*
Y426101D01*
X493982D01*
Y425901D01*
G37*
G36*
G01X499182D02*
X499132Y425151D01*
X498732D01*
X498682Y425901D01*
Y426101D01*
X499182D01*
Y425901D01*
G37*
G36*
G01X496582D02*
X496532Y425151D01*
X496132D01*
X496082Y425901D01*
Y426101D01*
X496582D01*
Y425901D01*
G37*
G36*
G01X492182Y426301D02*
X492232Y427051D01*
X492632D01*
X492682Y426301D01*
Y426101D01*
X492182D01*
Y426301D01*
G37*
G36*
G01X494782D02*
X494832Y427051D01*
X495232D01*
X495282Y426301D01*
Y426101D01*
X494782D01*
Y426301D01*
G37*
G36*
G01X497382D02*
X497432Y427051D01*
X497832D01*
X497882Y426301D01*
Y426101D01*
X497382D01*
Y426301D01*
G37*
G36*
G01X504382Y425901D02*
X504332Y425151D01*
X503932D01*
X503882Y425901D01*
Y426101D01*
X504382D01*
Y425901D01*
G37*
G36*
G01X501782D02*
X501732Y425151D01*
X501332D01*
X501282Y425901D01*
Y426101D01*
X501782D01*
Y425901D01*
G37*
G36*
G01X505182Y426301D02*
X505232Y427051D01*
X505632D01*
X505682Y426301D01*
Y426101D01*
X505182D01*
Y426301D01*
G37*
G36*
G01X502582D02*
X502632Y427051D01*
X503032D01*
X503082Y426301D01*
Y426101D01*
X502582D01*
Y426301D01*
G37*
G36*
G01X499982D02*
X500032Y427051D01*
X500432D01*
X500482Y426301D01*
Y426101D01*
X499982D01*
Y426301D01*
G37*
G36*
G01X506982Y425901D02*
X506932Y425151D01*
X506532D01*
X506482Y425901D01*
Y426101D01*
X506982D01*
Y425901D01*
G37*
G36*
G01X509582D02*
X509532Y425151D01*
X509132D01*
X509082Y425901D01*
Y426101D01*
X509582D01*
Y425901D01*
G37*
G36*
G01X507782Y426301D02*
X507832Y427051D01*
X508232D01*
X508282Y426301D01*
Y426101D01*
X507782D01*
Y426301D01*
G37*
G36*
G01X512241Y427881D02*
X511746Y428447D01*
X512029Y428730D01*
X512595Y428235D01*
X512736Y428093D01*
X512383Y427740D01*
X512241Y427881D01*
G37*
G36*
G01X511958Y427033D02*
X512453Y426467D01*
X512171Y426184D01*
X511605Y426679D01*
X511463Y426820D01*
X511817Y427174D01*
X511958Y427033D01*
G37*
G36*
G01X513797Y428871D02*
X514292Y428305D01*
X514009Y428023D01*
X513443Y428518D01*
X513302Y428659D01*
X513656Y429013D01*
X513797Y428871D01*
G37*
G36*
G01X514080Y429720D02*
X513585Y430285D01*
X513868Y430568D01*
X514433Y430073D01*
X514575Y429932D01*
X514221Y429578D01*
X514080Y429720D01*
G37*
G36*
G01X515635Y430710D02*
X516130Y430144D01*
X515848Y429861D01*
X515282Y430356D01*
X515140Y430497D01*
X515494Y430851D01*
X515635Y430710D01*
G37*
G36*
G01X515918Y431558D02*
X515423Y432124D01*
X515706Y432407D01*
X516272Y431912D01*
X516413Y431770D01*
X516060Y431417D01*
X515918Y431558D01*
G37*
G36*
G01X517474Y432548D02*
X517969Y431982D01*
X517686Y431700D01*
X517120Y432194D01*
X516979Y432336D01*
X517332Y432689D01*
X517474Y432548D01*
G37*
G36*
G01X482764Y414454D02*
X483259Y413888D01*
X482976Y413606D01*
X482410Y414101D01*
X482269Y414242D01*
X482622Y414595D01*
X482764Y414454D01*
G37*
G36*
G01X480925Y412616D02*
X481420Y412050D01*
X481138Y411767D01*
X480572Y412262D01*
X480430Y412403D01*
X480784Y412757D01*
X480925Y412616D01*
G37*
G36*
G01X481208Y413464D02*
X480713Y414030D01*
X480996Y414313D01*
X481562Y413818D01*
X481703Y413676D01*
X481350Y413323D01*
X481208Y413464D01*
G37*
G36*
G01X479087Y410777D02*
X479582Y410211D01*
X479299Y409929D01*
X478733Y410424D01*
X478592Y410565D01*
X478946Y410919D01*
X479087Y410777D01*
G37*
G36*
G01X479370Y411626D02*
X478875Y412191D01*
X479158Y412474D01*
X479723Y411979D01*
X479865Y411838D01*
X479511Y411484D01*
X479370Y411626D01*
G37*
G36*
G01X486182Y415051D02*
X486132Y414301D01*
X485732D01*
X485682Y415051D01*
Y415251D01*
X486182D01*
Y415051D01*
G37*
G36*
G01X484382Y415451D02*
X484432Y416201D01*
X484832D01*
X484882Y415451D01*
Y415251D01*
X484382D01*
Y415451D01*
G37*
G36*
G01X488782Y415051D02*
X488732Y414301D01*
X488332D01*
X488282Y415051D01*
Y415251D01*
X488782D01*
Y415051D01*
G37*
G36*
G01X486982Y415451D02*
X487032Y416201D01*
X487432D01*
X487482Y415451D01*
Y415251D01*
X486982D01*
Y415451D01*
G37*
G36*
G01X489582D02*
X489632Y416201D01*
X490032D01*
X490082Y415451D01*
Y415251D01*
X489582D01*
Y415451D01*
G37*
G36*
G01X491382Y415051D02*
X491332Y414301D01*
X490932D01*
X490882Y415051D01*
Y415251D01*
X491382D01*
Y415051D01*
G37*
G36*
G01X499182D02*
X499132Y414301D01*
X498732D01*
X498682Y415051D01*
Y415251D01*
X499182D01*
Y415051D01*
G37*
G36*
G01X493982D02*
X493932Y414301D01*
X493532D01*
X493482Y415051D01*
Y415251D01*
X493982D01*
Y415051D01*
G37*
G36*
G01X496582D02*
X496532Y414301D01*
X496132D01*
X496082Y415051D01*
Y415251D01*
X496582D01*
Y415051D01*
G37*
G36*
G01X492182Y415451D02*
X492232Y416201D01*
X492632D01*
X492682Y415451D01*
Y415251D01*
X492182D01*
Y415451D01*
G37*
G36*
G01X494782D02*
X494832Y416201D01*
X495232D01*
X495282Y415451D01*
Y415251D01*
X494782D01*
Y415451D01*
G37*
G36*
G01X497382D02*
X497432Y416201D01*
X497832D01*
X497882Y415451D01*
Y415251D01*
X497382D01*
Y415451D01*
G37*
G36*
G01X504382Y415051D02*
X504332Y414301D01*
X503932D01*
X503882Y415051D01*
Y415251D01*
X504382D01*
Y415051D01*
G37*
G36*
G01X501782D02*
X501732Y414301D01*
X501332D01*
X501282Y415051D01*
Y415251D01*
X501782D01*
Y415051D01*
G37*
G36*
G01X505182Y415451D02*
X505232Y416201D01*
X505632D01*
X505682Y415451D01*
Y415251D01*
X505182D01*
Y415451D01*
G37*
G36*
G01X502582D02*
X502632Y416201D01*
X503032D01*
X503082Y415451D01*
Y415251D01*
X502582D01*
Y415451D01*
G37*
G36*
G01X499982D02*
X500032Y416201D01*
X500432D01*
X500482Y415451D01*
Y415251D01*
X499982D01*
Y415451D01*
G37*
G36*
G01X506982Y415051D02*
X506932Y414301D01*
X506532D01*
X506482Y415051D01*
Y415251D01*
X506982D01*
Y415051D01*
G37*
G36*
G01X509582D02*
X509532Y414301D01*
X509132D01*
X509082Y415051D01*
Y415251D01*
X509582D01*
Y415051D01*
G37*
G36*
G01X507782Y415451D02*
X507832Y416201D01*
X508232D01*
X508282Y415451D01*
Y415251D01*
X507782D01*
Y415451D01*
G37*
G36*
G01X515958Y415679D02*
X516453Y415113D01*
X516170Y414831D01*
X515604Y415326D01*
X515463Y415467D01*
X515817Y415821D01*
X515958Y415679D01*
G37*
G36*
G01X514782Y415051D02*
X514732Y414301D01*
X514332D01*
X514282Y415051D01*
Y415251D01*
X514782D01*
Y415051D01*
G37*
G36*
G01X512182D02*
X512132Y414301D01*
X511732D01*
X511682Y415051D01*
Y415251D01*
X512182D01*
Y415051D01*
G37*
G36*
G01X512982Y415451D02*
X513032Y416201D01*
X513432D01*
X513482Y415451D01*
Y415251D01*
X512982D01*
Y415451D01*
G37*
G36*
G01X510382D02*
X510432Y416201D01*
X510832D01*
X510882Y415451D01*
Y415251D01*
X510382D01*
Y415451D01*
G37*
G36*
G01X516241Y416528D02*
X515746Y417093D01*
X516029Y417376D01*
X516594Y416881D01*
X516736Y416740D01*
X516382Y416386D01*
X516241Y416528D01*
G37*
G36*
G01X517796Y417518D02*
X518291Y416952D01*
X518009Y416669D01*
X517443Y417164D01*
X517302Y417306D01*
X517655Y417659D01*
X517796Y417518D01*
G37*
G36*
G01X519918Y420205D02*
X519423Y420770D01*
X519706Y421053D01*
X520271Y420558D01*
X520413Y420417D01*
X520059Y420063D01*
X519918Y420205D01*
G37*
G36*
G01X518079Y418366D02*
X517584Y418932D01*
X517867Y419215D01*
X518433Y418720D01*
X518574Y418578D01*
X518221Y418225D01*
X518079Y418366D01*
G37*
G36*
G01X521473Y421195D02*
X521968Y420629D01*
X521686Y420346D01*
X521120Y420841D01*
X520978Y420982D01*
X521332Y421336D01*
X521473Y421195D01*
G37*
G36*
G01X519635Y419356D02*
X520130Y418790D01*
X519847Y418508D01*
X519281Y419003D01*
X519140Y419144D01*
X519494Y419498D01*
X519635Y419356D01*
G37*
G36*
G01X521756Y422043D02*
X521261Y422609D01*
X521544Y422892D01*
X522110Y422397D01*
X522251Y422255D01*
X521898Y421902D01*
X521756Y422043D01*
G37*
G36*
G01X525150Y424872D02*
X525645Y424306D01*
X525363Y424023D01*
X524797Y424518D01*
X524655Y424659D01*
X525009Y425013D01*
X525150Y424872D01*
G37*
G36*
G01X525433Y425720D02*
X524938Y426286D01*
X525221Y426569D01*
X525787Y426074D01*
X525928Y425932D01*
X525575Y425579D01*
X525433Y425720D01*
G37*
G36*
G01X523595Y423882D02*
X523100Y424447D01*
X523383Y424730D01*
X523948Y424235D01*
X524090Y424094D01*
X523736Y423740D01*
X523595Y423882D01*
G37*
G36*
G01X523312Y423033D02*
X523807Y422467D01*
X523524Y422185D01*
X522958Y422680D01*
X522817Y422821D01*
X523170Y423174D01*
X523312Y423033D01*
G37*
G36*
G01X482022Y411519D02*
X482517Y410953D01*
X482234Y410671D01*
X481668Y411166D01*
X481527Y411307D01*
X481881Y411661D01*
X482022Y411519D01*
G37*
G36*
G01X482305Y412368D02*
X481810Y412933D01*
X482093Y413216D01*
X482658Y412721D01*
X482800Y412580D01*
X482446Y412226D01*
X482305Y412368D01*
G37*
G36*
G01X480183Y409681D02*
X480678Y409115D01*
X480396Y408832D01*
X479830Y409327D01*
X479688Y409468D01*
X480042Y409822D01*
X480183Y409681D01*
G37*
G36*
G01X480466Y410529D02*
X479971Y411095D01*
X480254Y411378D01*
X480820Y410883D01*
X480961Y410741D01*
X480608Y410388D01*
X480466Y410529D01*
G37*
G36*
G01X484382Y413901D02*
X484432Y414651D01*
X484832D01*
X484882Y413901D01*
Y413701D01*
X484382D01*
Y413901D01*
G37*
G36*
G01X486982D02*
X487032Y414651D01*
X487432D01*
X487482Y413901D01*
Y413701D01*
X486982D01*
Y413901D01*
G37*
G36*
G01X488782Y413501D02*
X488732Y412751D01*
X488332D01*
X488282Y413501D01*
Y413701D01*
X488782D01*
Y413501D01*
G37*
G36*
G01X489582Y413901D02*
X489632Y414651D01*
X490032D01*
X490082Y413901D01*
Y413701D01*
X489582D01*
Y413901D01*
G37*
G36*
G01X486182Y413501D02*
X486132Y412751D01*
X485732D01*
X485682Y413501D01*
Y413701D01*
X486182D01*
Y413501D01*
G37*
G36*
G01X491382D02*
X491332Y412751D01*
X490932D01*
X490882Y413501D01*
Y413701D01*
X491382D01*
Y413501D01*
G37*
G36*
G01X499182D02*
X499132Y412751D01*
X498732D01*
X498682Y413501D01*
Y413701D01*
X499182D01*
Y413501D01*
G37*
G36*
G01X493982D02*
X493932Y412751D01*
X493532D01*
X493482Y413501D01*
Y413701D01*
X493982D01*
Y413501D01*
G37*
G36*
G01X496582D02*
X496532Y412751D01*
X496132D01*
X496082Y413501D01*
Y413701D01*
X496582D01*
Y413501D01*
G37*
G36*
G01X492182Y413901D02*
X492232Y414651D01*
X492632D01*
X492682Y413901D01*
Y413701D01*
X492182D01*
Y413901D01*
G37*
G36*
G01X494782D02*
X494832Y414651D01*
X495232D01*
X495282Y413901D01*
Y413701D01*
X494782D01*
Y413901D01*
G37*
G36*
G01X497382D02*
X497432Y414651D01*
X497832D01*
X497882Y413901D01*
Y413701D01*
X497382D01*
Y413901D01*
G37*
G36*
G01X504382Y413501D02*
X504332Y412751D01*
X503932D01*
X503882Y413501D01*
Y413701D01*
X504382D01*
Y413501D01*
G37*
G36*
G01X501782D02*
X501732Y412751D01*
X501332D01*
X501282Y413501D01*
Y413701D01*
X501782D01*
Y413501D01*
G37*
G36*
G01X505182Y413901D02*
X505232Y414651D01*
X505632D01*
X505682Y413901D01*
Y413701D01*
X505182D01*
Y413901D01*
G37*
G36*
G01X502582D02*
X502632Y414651D01*
X503032D01*
X503082Y413901D01*
Y413701D01*
X502582D01*
Y413901D01*
G37*
G36*
G01X499982D02*
X500032Y414651D01*
X500432D01*
X500482Y413901D01*
Y413701D01*
X499982D01*
Y413901D01*
G37*
G36*
G01X506982Y413501D02*
X506932Y412751D01*
X506532D01*
X506482Y413501D01*
Y413701D01*
X506982D01*
Y413501D01*
G37*
G36*
G01X509582D02*
X509532Y412751D01*
X509132D01*
X509082Y413501D01*
Y413701D01*
X509582D01*
Y413501D01*
G37*
G36*
G01X507782Y413901D02*
X507832Y414651D01*
X508232D01*
X508282Y413901D01*
Y413701D01*
X507782D01*
Y413901D01*
G37*
G36*
G01X514782Y413501D02*
X514732Y412751D01*
X514332D01*
X514282Y413501D01*
Y413701D01*
X514782D01*
Y413501D01*
G37*
G36*
G01X512182D02*
X512132Y412751D01*
X511732D01*
X511682Y413501D01*
Y413701D01*
X512182D01*
Y413501D01*
G37*
G36*
G01X512982Y413901D02*
X513032Y414651D01*
X513432D01*
X513482Y413901D01*
Y413701D01*
X512982D01*
Y413901D01*
G37*
G36*
G01X510382D02*
X510432Y414651D01*
X510832D01*
X510882Y413901D01*
Y413701D01*
X510382D01*
Y413901D01*
G37*
G36*
G01X517337Y415431D02*
X516842Y415997D01*
X517125Y416280D01*
X517691Y415785D01*
X517832Y415643D01*
X517479Y415290D01*
X517337Y415431D01*
G37*
G36*
G01X517055Y414583D02*
X517549Y414017D01*
X517267Y413734D01*
X516701Y414229D01*
X516560Y414371D01*
X516913Y414724D01*
X517055Y414583D01*
G37*
G36*
G01X518893Y416421D02*
X519388Y415855D01*
X519105Y415573D01*
X518539Y416068D01*
X518398Y416209D01*
X518752Y416563D01*
X518893Y416421D01*
G37*
G36*
G01X519176Y417270D02*
X518681Y417835D01*
X518964Y418118D01*
X519529Y417623D01*
X519671Y417482D01*
X519317Y417128D01*
X519176Y417270D01*
G37*
G36*
G01X520731Y418260D02*
X521226Y417694D01*
X520944Y417411D01*
X520378Y417906D01*
X520236Y418047D01*
X520590Y418401D01*
X520731Y418260D01*
G37*
G36*
G01X521014Y419108D02*
X520519Y419674D01*
X520802Y419957D01*
X521368Y419462D01*
X521509Y419320D01*
X521156Y418967D01*
X521014Y419108D01*
G37*
G36*
G01X522570Y420098D02*
X523065Y419532D01*
X522782Y419250D01*
X522216Y419745D01*
X522075Y419886D01*
X522429Y420240D01*
X522570Y420098D01*
G37*
G36*
G01X524691Y422785D02*
X524196Y423351D01*
X524479Y423634D01*
X525045Y423139D01*
X525186Y422997D01*
X524833Y422644D01*
X524691Y422785D01*
G37*
G36*
G01X522853Y420947D02*
X522358Y421512D01*
X522641Y421795D01*
X523206Y421300D01*
X523348Y421159D01*
X522994Y420805D01*
X522853Y420947D01*
G37*
G36*
G01X524408Y421937D02*
X524903Y421371D01*
X524621Y421088D01*
X524055Y421583D01*
X523913Y421724D01*
X524267Y422078D01*
X524408Y421937D01*
G37*
G36*
G01X526246Y423775D02*
X526741Y423209D01*
X526459Y422926D01*
X525893Y423421D01*
X525751Y423562D01*
X526105Y423916D01*
X526246Y423775D01*
G37*
G36*
G01X526529Y424623D02*
X526034Y425189D01*
X526317Y425472D01*
X526883Y424977D01*
X527024Y424835D01*
X526671Y424482D01*
X526529Y424623D01*
G37*
G36*
G01X479091Y418127D02*
X479586Y417561D01*
X479303Y417279D01*
X478737Y417774D01*
X478596Y417915D01*
X478949Y418268D01*
X479091Y418127D01*
G37*
G36*
G01X481782Y420101D02*
X481832Y420851D01*
X482232D01*
X482282Y420101D01*
Y419901D01*
X481782D01*
Y420101D01*
G37*
G36*
G01X479374Y418976D02*
X478879Y419541D01*
X479162Y419824D01*
X479727Y419329D01*
X479869Y419188D01*
X479515Y418834D01*
X479374Y418976D01*
G37*
G36*
G01X483582Y419701D02*
X483532Y418951D01*
X483132D01*
X483082Y419701D01*
Y419901D01*
X483582D01*
Y419701D01*
G37*
G36*
G01X486182D02*
X486132Y418951D01*
X485732D01*
X485682Y419701D01*
Y419901D01*
X486182D01*
Y419701D01*
G37*
G36*
G01X488782D02*
X488732Y418951D01*
X488332D01*
X488282Y419701D01*
Y419901D01*
X488782D01*
Y419701D01*
G37*
G36*
G01X484382Y420101D02*
X484432Y420851D01*
X484832D01*
X484882Y420101D01*
Y419901D01*
X484382D01*
Y420101D01*
G37*
G36*
G01X486982D02*
X487032Y420851D01*
X487432D01*
X487482Y420101D01*
Y419901D01*
X486982D01*
Y420101D01*
G37*
G36*
G01X489582D02*
X489632Y420851D01*
X490032D01*
X490082Y420101D01*
Y419901D01*
X489582D01*
Y420101D01*
G37*
G36*
G01X491382Y419701D02*
X491332Y418951D01*
X490932D01*
X490882Y419701D01*
Y419901D01*
X491382D01*
Y419701D01*
G37*
G36*
G01X493982D02*
X493932Y418951D01*
X493532D01*
X493482Y419701D01*
Y419901D01*
X493982D01*
Y419701D01*
G37*
G36*
G01X496582D02*
X496532Y418951D01*
X496132D01*
X496082Y419701D01*
Y419901D01*
X496582D01*
Y419701D01*
G37*
G36*
G01X499182D02*
X499132Y418951D01*
X498732D01*
X498682Y419701D01*
Y419901D01*
X499182D01*
Y419701D01*
G37*
G36*
G01X492182Y420101D02*
X492232Y420851D01*
X492632D01*
X492682Y420101D01*
Y419901D01*
X492182D01*
Y420101D01*
G37*
G36*
G01X494782D02*
X494832Y420851D01*
X495232D01*
X495282Y420101D01*
Y419901D01*
X494782D01*
Y420101D01*
G37*
G36*
G01X497382D02*
X497432Y420851D01*
X497832D01*
X497882Y420101D01*
Y419901D01*
X497382D01*
Y420101D01*
G37*
G36*
G01X504382Y419701D02*
X504332Y418951D01*
X503932D01*
X503882Y419701D01*
Y419901D01*
X504382D01*
Y419701D01*
G37*
G36*
G01X501782D02*
X501732Y418951D01*
X501332D01*
X501282Y419701D01*
Y419901D01*
X501782D01*
Y419701D01*
G37*
G36*
G01X505182Y420101D02*
X505232Y420851D01*
X505632D01*
X505682Y420101D01*
Y419901D01*
X505182D01*
Y420101D01*
G37*
G36*
G01X502582D02*
X502632Y420851D01*
X503032D01*
X503082Y420101D01*
Y419901D01*
X502582D01*
Y420101D01*
G37*
G36*
G01X499982D02*
X500032Y420851D01*
X500432D01*
X500482Y420101D01*
Y419901D01*
X499982D01*
Y420101D01*
G37*
G36*
G01X506982Y419701D02*
X506932Y418951D01*
X506532D01*
X506482Y419701D01*
Y419901D01*
X506982D01*
Y419701D01*
G37*
G36*
G01X509582D02*
X509532Y418951D01*
X509132D01*
X509082Y419701D01*
Y419901D01*
X509582D01*
Y419701D01*
G37*
G36*
G01X507782Y420101D02*
X507832Y420851D01*
X508232D01*
X508282Y420101D01*
Y419901D01*
X507782D01*
Y420101D01*
G37*
G36*
G01X514506Y420808D02*
X515001Y420242D01*
X514718Y419960D01*
X514152Y420455D01*
X514011Y420596D01*
X514365Y420950D01*
X514506Y420808D01*
G37*
G36*
G01X512182Y419701D02*
X512132Y418951D01*
X511732D01*
X511682Y419701D01*
Y419901D01*
X512182D01*
Y419701D01*
G37*
G36*
G01X510382Y420101D02*
X510432Y420851D01*
X510832D01*
X510882Y420101D01*
Y419901D01*
X510382D01*
Y420101D01*
G37*
G36*
G01X514789Y421657D02*
X514294Y422222D01*
X514577Y422505D01*
X515142Y422010D01*
X515284Y421869D01*
X514930Y421515D01*
X514789Y421657D01*
G37*
G36*
G01X516344Y422647D02*
X516839Y422081D01*
X516557Y421798D01*
X515991Y422293D01*
X515849Y422434D01*
X516203Y422788D01*
X516344Y422647D01*
G37*
G36*
G01X516627Y423495D02*
X516132Y424061D01*
X516415Y424344D01*
X516981Y423849D01*
X517122Y423707D01*
X516769Y423354D01*
X516627Y423495D01*
G37*
G36*
G01X518466Y425334D02*
X517971Y425899D01*
X518254Y426182D01*
X518819Y425687D01*
X518961Y425546D01*
X518607Y425192D01*
X518466Y425334D01*
G37*
G36*
G01X522143Y429011D02*
X521648Y429576D01*
X521931Y429859D01*
X522496Y429364D01*
X522638Y429223D01*
X522284Y428869D01*
X522143Y429011D01*
G37*
G36*
G01X520304Y427172D02*
X519809Y427738D01*
X520092Y428021D01*
X520658Y427526D01*
X520799Y427384D01*
X520446Y427031D01*
X520304Y427172D01*
G37*
G36*
G01X518183Y424485D02*
X518678Y423919D01*
X518395Y423637D01*
X517829Y424132D01*
X517688Y424273D01*
X518042Y424627D01*
X518183Y424485D01*
G37*
G36*
G01X520021Y426324D02*
X520516Y425758D01*
X520234Y425475D01*
X519668Y425970D01*
X519526Y426111D01*
X519880Y426465D01*
X520021Y426324D01*
G37*
G36*
G01X523698Y430001D02*
X524193Y429435D01*
X523911Y429152D01*
X523345Y429647D01*
X523203Y429788D01*
X523557Y430142D01*
X523698Y430001D01*
G37*
G36*
G01X521860Y428162D02*
X522355Y427596D01*
X522072Y427314D01*
X521506Y427808D01*
X521365Y427950D01*
X521718Y428303D01*
X521860Y428162D01*
G37*
G36*
G01X523981Y430849D02*
X523486Y431415D01*
X523769Y431698D01*
X524335Y431203D01*
X524476Y431061D01*
X524123Y430708D01*
X523981Y430849D01*
G37*
G36*
G01X480188Y417030D02*
X480683Y416464D01*
X480400Y416182D01*
X479834Y416677D01*
X479693Y416818D01*
X480046Y417171D01*
X480188Y417030D01*
G37*
G36*
G01X478632Y416040D02*
X478137Y416606D01*
X478420Y416889D01*
X478986Y416394D01*
X479127Y416252D01*
X478774Y415899D01*
X478632Y416040D01*
G37*
G36*
G01X480471Y417879D02*
X479976Y418444D01*
X480259Y418727D01*
X480824Y418232D01*
X480966Y418091D01*
X480612Y417737D01*
X480471Y417879D01*
G37*
G36*
G01X481782Y418551D02*
X481832Y419301D01*
X482232D01*
X482282Y418551D01*
Y418351D01*
X481782D01*
Y418551D01*
G37*
G36*
G01X483582Y418151D02*
X483532Y417401D01*
X483132D01*
X483082Y418151D01*
Y418351D01*
X483582D01*
Y418151D01*
G37*
G36*
G01X486182D02*
X486132Y417401D01*
X485732D01*
X485682Y418151D01*
Y418351D01*
X486182D01*
Y418151D01*
G37*
G36*
G01X488782D02*
X488732Y417401D01*
X488332D01*
X488282Y418151D01*
Y418351D01*
X488782D01*
Y418151D01*
G37*
G36*
G01X484382Y418551D02*
X484432Y419301D01*
X484832D01*
X484882Y418551D01*
Y418351D01*
X484382D01*
Y418551D01*
G37*
G36*
G01X486982D02*
X487032Y419301D01*
X487432D01*
X487482Y418551D01*
Y418351D01*
X486982D01*
Y418551D01*
G37*
G36*
G01X489582D02*
X489632Y419301D01*
X490032D01*
X490082Y418551D01*
Y418351D01*
X489582D01*
Y418551D01*
G37*
G36*
G01X491382Y418151D02*
X491332Y417401D01*
X490932D01*
X490882Y418151D01*
Y418351D01*
X491382D01*
Y418151D01*
G37*
G36*
G01X493982D02*
X493932Y417401D01*
X493532D01*
X493482Y418151D01*
Y418351D01*
X493982D01*
Y418151D01*
G37*
G36*
G01X496582D02*
X496532Y417401D01*
X496132D01*
X496082Y418151D01*
Y418351D01*
X496582D01*
Y418151D01*
G37*
G36*
G01X499182D02*
X499132Y417401D01*
X498732D01*
X498682Y418151D01*
Y418351D01*
X499182D01*
Y418151D01*
G37*
G36*
G01X492182Y418551D02*
X492232Y419301D01*
X492632D01*
X492682Y418551D01*
Y418351D01*
X492182D01*
Y418551D01*
G37*
G36*
G01X494782D02*
X494832Y419301D01*
X495232D01*
X495282Y418551D01*
Y418351D01*
X494782D01*
Y418551D01*
G37*
G36*
G01X497382D02*
X497432Y419301D01*
X497832D01*
X497882Y418551D01*
Y418351D01*
X497382D01*
Y418551D01*
G37*
G36*
G01X504382Y418151D02*
X504332Y417401D01*
X503932D01*
X503882Y418151D01*
Y418351D01*
X504382D01*
Y418151D01*
G37*
G36*
G01X501782D02*
X501732Y417401D01*
X501332D01*
X501282Y418151D01*
Y418351D01*
X501782D01*
Y418151D01*
G37*
G36*
G01X506982D02*
X506932Y417401D01*
X506532D01*
X506482Y418151D01*
Y418351D01*
X506982D01*
Y418151D01*
G37*
G36*
G01X505182Y418551D02*
X505232Y419301D01*
X505632D01*
X505682Y418551D01*
Y418351D01*
X505182D01*
Y418551D01*
G37*
G36*
G01X502582D02*
X502632Y419301D01*
X503032D01*
X503082Y418551D01*
Y418351D01*
X502582D01*
Y418551D01*
G37*
G36*
G01X499982D02*
X500032Y419301D01*
X500432D01*
X500482Y418551D01*
Y418351D01*
X499982D01*
Y418551D01*
G37*
G36*
G01X509582Y418151D02*
X509532Y417401D01*
X509132D01*
X509082Y418151D01*
Y418351D01*
X509582D01*
Y418151D01*
G37*
G36*
G01X512182D02*
X512132Y417401D01*
X511732D01*
X511682Y418151D01*
Y418351D01*
X512182D01*
Y418151D01*
G37*
G36*
G01X507782Y418551D02*
X507832Y419301D01*
X508232D01*
X508282Y418551D01*
Y418351D01*
X507782D01*
Y418551D01*
G37*
G36*
G01X515886Y420560D02*
X515391Y421125D01*
X515674Y421408D01*
X516239Y420913D01*
X516381Y420772D01*
X516027Y420418D01*
X515886Y420560D01*
G37*
G36*
G01X515603Y419711D02*
X516098Y419145D01*
X515815Y418863D01*
X515249Y419358D01*
X515108Y419499D01*
X515462Y419853D01*
X515603Y419711D01*
G37*
G36*
G01X512982Y418551D02*
X513032Y419301D01*
X513432D01*
X513482Y418551D01*
Y418351D01*
X512982D01*
Y418551D01*
G37*
G36*
G01X510382D02*
X510432Y419301D01*
X510832D01*
X510882Y418551D01*
Y418351D01*
X510382D01*
Y418551D01*
G37*
G36*
G01X517724Y422398D02*
X517229Y422964D01*
X517512Y423247D01*
X518078Y422752D01*
X518219Y422610D01*
X517866Y422257D01*
X517724Y422398D01*
G37*
G36*
G01X519563Y424237D02*
X519068Y424802D01*
X519351Y425085D01*
X519916Y424590D01*
X520058Y424449D01*
X519704Y424095D01*
X519563Y424237D01*
G37*
G36*
G01X525078Y429752D02*
X524583Y430318D01*
X524866Y430601D01*
X525432Y430106D01*
X525573Y429964D01*
X525220Y429611D01*
X525078Y429752D01*
G37*
G36*
G01X523240Y427914D02*
X522745Y428479D01*
X523028Y428762D01*
X523593Y428267D01*
X523735Y428126D01*
X523381Y427772D01*
X523240Y427914D01*
G37*
G36*
G01X521401Y426075D02*
X520906Y426641D01*
X521189Y426924D01*
X521755Y426429D01*
X521896Y426287D01*
X521543Y425934D01*
X521401Y426075D01*
G37*
G36*
G01X517441Y421550D02*
X517936Y420984D01*
X517654Y420701D01*
X517088Y421196D01*
X516946Y421337D01*
X517300Y421691D01*
X517441Y421550D01*
G37*
G36*
G01X519280Y423388D02*
X519775Y422822D01*
X519492Y422540D01*
X518926Y423035D01*
X518785Y423176D01*
X519139Y423530D01*
X519280Y423388D01*
G37*
G36*
G01X521118Y425227D02*
X521613Y424661D01*
X521331Y424378D01*
X520765Y424873D01*
X520623Y425014D01*
X520977Y425368D01*
X521118Y425227D01*
G37*
G36*
G01X524795Y428904D02*
X525290Y428338D01*
X525008Y428055D01*
X524442Y428550D01*
X524300Y428691D01*
X524654Y429045D01*
X524795Y428904D01*
G37*
G36*
G01X522957Y427065D02*
X523452Y426499D01*
X523169Y426217D01*
X522603Y426711D01*
X522462Y426853D01*
X522815Y427206D01*
X522957Y427065D01*
G37*
G36*
G01X480982Y421251D02*
X480932Y420501D01*
X480532D01*
X480482Y421251D01*
Y421451D01*
X480982D01*
Y421251D01*
G37*
G36*
G01X483582D02*
X483532Y420501D01*
X483132D01*
X483082Y421251D01*
Y421451D01*
X483582D01*
Y421251D01*
G37*
G36*
G01X486182D02*
X486132Y420501D01*
X485732D01*
X485682Y421251D01*
Y421451D01*
X486182D01*
Y421251D01*
G37*
G36*
G01X488782D02*
X488732Y420501D01*
X488332D01*
X488282Y421251D01*
Y421451D01*
X488782D01*
Y421251D01*
G37*
G36*
G01X491382D02*
X491332Y420501D01*
X490932D01*
X490882Y421251D01*
Y421451D01*
X491382D01*
Y421251D01*
G37*
G36*
G01X481782Y421651D02*
X481832Y422401D01*
X482232D01*
X482282Y421651D01*
Y421451D01*
X481782D01*
Y421651D01*
G37*
G36*
G01X484382D02*
X484432Y422401D01*
X484832D01*
X484882Y421651D01*
Y421451D01*
X484382D01*
Y421651D01*
G37*
G36*
G01X486982D02*
X487032Y422401D01*
X487432D01*
X487482Y421651D01*
Y421451D01*
X486982D01*
Y421651D01*
G37*
G36*
G01X489582D02*
X489632Y422401D01*
X490032D01*
X490082Y421651D01*
Y421451D01*
X489582D01*
Y421651D01*
G37*
G36*
G01X493982Y421251D02*
X493932Y420501D01*
X493532D01*
X493482Y421251D01*
Y421451D01*
X493982D01*
Y421251D01*
G37*
G36*
G01X496582D02*
X496532Y420501D01*
X496132D01*
X496082Y421251D01*
Y421451D01*
X496582D01*
Y421251D01*
G37*
G36*
G01X499182D02*
X499132Y420501D01*
X498732D01*
X498682Y421251D01*
Y421451D01*
X499182D01*
Y421251D01*
G37*
G36*
G01X506982D02*
X506932Y420501D01*
X506532D01*
X506482Y421251D01*
Y421451D01*
X506982D01*
Y421251D01*
G37*
G36*
G01X501782D02*
X501732Y420501D01*
X501332D01*
X501282Y421251D01*
Y421451D01*
X501782D01*
Y421251D01*
G37*
G36*
G01X504382D02*
X504332Y420501D01*
X503932D01*
X503882Y421251D01*
Y421451D01*
X504382D01*
Y421251D01*
G37*
G36*
G01X492182Y421651D02*
X492232Y422401D01*
X492632D01*
X492682Y421651D01*
Y421451D01*
X492182D01*
Y421651D01*
G37*
G36*
G01X494782D02*
X494832Y422401D01*
X495232D01*
X495282Y421651D01*
Y421451D01*
X494782D01*
Y421651D01*
G37*
G36*
G01X497382D02*
X497432Y422401D01*
X497832D01*
X497882Y421651D01*
Y421451D01*
X497382D01*
Y421651D01*
G37*
G36*
G01X505182D02*
X505232Y422401D01*
X505632D01*
X505682Y421651D01*
Y421451D01*
X505182D01*
Y421651D01*
G37*
G36*
G01X502582D02*
X502632Y422401D01*
X503032D01*
X503082Y421651D01*
Y421451D01*
X502582D01*
Y421651D01*
G37*
G36*
G01X499982D02*
X500032Y422401D01*
X500432D01*
X500482Y421651D01*
Y421451D01*
X499982D01*
Y421651D01*
G37*
G36*
G01X509582Y421251D02*
X509532Y420501D01*
X509132D01*
X509082Y421251D01*
Y421451D01*
X509582D01*
Y421251D01*
G37*
G36*
G01X512182D02*
X512132Y420501D01*
X511732D01*
X511682Y421251D01*
Y421451D01*
X512182D01*
Y421251D01*
G37*
G36*
G01X507782Y421651D02*
X507832Y422401D01*
X508232D01*
X508282Y421651D01*
Y421451D01*
X507782D01*
Y421651D01*
G37*
G36*
G01X513409Y421905D02*
X513904Y421339D01*
X513622Y421056D01*
X513056Y421551D01*
X512915Y421693D01*
X513268Y422046D01*
X513409Y421905D01*
G37*
G36*
G01X510382Y421651D02*
X510432Y422401D01*
X510832D01*
X510882Y421651D01*
Y421451D01*
X510382D01*
Y421651D01*
G37*
G36*
G01X513692Y422753D02*
X513197Y423319D01*
X513480Y423602D01*
X514046Y423107D01*
X514187Y422965D01*
X513834Y422612D01*
X513692Y422753D01*
G37*
G36*
G01X515531Y424592D02*
X515036Y425157D01*
X515319Y425440D01*
X515884Y424945D01*
X516026Y424804D01*
X515672Y424450D01*
X515531Y424592D01*
G37*
G36*
G01X517369Y426430D02*
X516874Y426996D01*
X517157Y427279D01*
X517723Y426784D01*
X517864Y426642D01*
X517511Y426289D01*
X517369Y426430D01*
G37*
G36*
G01X519208Y428269D02*
X518713Y428834D01*
X518996Y429117D01*
X519561Y428622D01*
X519703Y428481D01*
X519349Y428127D01*
X519208Y428269D01*
G37*
G36*
G01X515248Y423743D02*
X515743Y423177D01*
X515460Y422895D01*
X514894Y423390D01*
X514753Y423531D01*
X515107Y423885D01*
X515248Y423743D01*
G37*
G36*
G01X517086Y425582D02*
X517581Y425016D01*
X517299Y424733D01*
X516733Y425228D01*
X516591Y425369D01*
X516945Y425723D01*
X517086Y425582D01*
G37*
G36*
G01X518925Y427420D02*
X519420Y426854D01*
X519137Y426572D01*
X518571Y427067D01*
X518430Y427208D01*
X518783Y427561D01*
X518925Y427420D01*
G37*
G36*
G01X520763Y429259D02*
X521258Y428693D01*
X520976Y428410D01*
X520410Y428905D01*
X520268Y429046D01*
X520622Y429400D01*
X520763Y429259D01*
G37*
G36*
G01X521046Y430107D02*
X520551Y430673D01*
X520834Y430956D01*
X521400Y430461D01*
X521541Y430319D01*
X521188Y429966D01*
X521046Y430107D01*
G37*
G36*
G01X522602Y431097D02*
X523097Y430531D01*
X522814Y430248D01*
X522248Y430743D01*
X522107Y430885D01*
X522460Y431238D01*
X522602Y431097D01*
G37*
G36*
G01X522885Y431946D02*
X522390Y432511D01*
X522673Y432794D01*
X523238Y432299D01*
X523380Y432158D01*
X523026Y431804D01*
X522885Y431946D01*
G37*
G36*
G01X479446Y414095D02*
X479941Y413529D01*
X479659Y413246D01*
X479093Y413741D01*
X478951Y413882D01*
X479305Y414236D01*
X479446Y414095D01*
G37*
G36*
G01X479729Y414943D02*
X479234Y415509D01*
X479517Y415792D01*
X480083Y415297D01*
X480224Y415155D01*
X479871Y414802D01*
X479729Y414943D01*
G37*
G36*
G01X481285Y415933D02*
X481780Y415367D01*
X481497Y415085D01*
X480931Y415580D01*
X480790Y415721D01*
X481143Y416074D01*
X481285Y415933D01*
G37*
G36*
G01X483582Y416601D02*
X483532Y415851D01*
X483132D01*
X483082Y416601D01*
Y416801D01*
X483582D01*
Y416601D01*
G37*
G36*
G01X486182D02*
X486132Y415851D01*
X485732D01*
X485682Y416601D01*
Y416801D01*
X486182D01*
Y416601D01*
G37*
G36*
G01X484382Y417001D02*
X484432Y417751D01*
X484832D01*
X484882Y417001D01*
Y416801D01*
X484382D01*
Y417001D01*
G37*
G36*
G01X486982D02*
X487032Y417751D01*
X487432D01*
X487482Y417001D01*
Y416801D01*
X486982D01*
Y417001D01*
G37*
G36*
G01X489582D02*
X489632Y417751D01*
X490032D01*
X490082Y417001D01*
Y416801D01*
X489582D01*
Y417001D01*
G37*
G36*
G01X488782Y416601D02*
X488732Y415851D01*
X488332D01*
X488282Y416601D01*
Y416801D01*
X488782D01*
Y416601D01*
G37*
G36*
G01X491382D02*
X491332Y415851D01*
X490932D01*
X490882Y416601D01*
Y416801D01*
X491382D01*
Y416601D01*
G37*
G36*
G01X497382Y417001D02*
X497432Y417751D01*
X497832D01*
X497882Y417001D01*
Y416801D01*
X497382D01*
Y417001D01*
G37*
G36*
G01X496582Y416601D02*
X496532Y415851D01*
X496132D01*
X496082Y416601D01*
Y416801D01*
X496582D01*
Y416601D01*
G37*
G36*
G01X499182D02*
X499132Y415851D01*
X498732D01*
X498682Y416601D01*
Y416801D01*
X499182D01*
Y416601D01*
G37*
G36*
G01X493982D02*
X493932Y415851D01*
X493532D01*
X493482Y416601D01*
Y416801D01*
X493982D01*
Y416601D01*
G37*
G36*
G01X494782Y417001D02*
X494832Y417751D01*
X495232D01*
X495282Y417001D01*
Y416801D01*
X494782D01*
Y417001D01*
G37*
G36*
G01X492182D02*
X492232Y417751D01*
X492632D01*
X492682Y417001D01*
Y416801D01*
X492182D01*
Y417001D01*
G37*
G36*
G01X504382Y416601D02*
X504332Y415851D01*
X503932D01*
X503882Y416601D01*
Y416801D01*
X504382D01*
Y416601D01*
G37*
G36*
G01X501782D02*
X501732Y415851D01*
X501332D01*
X501282Y416601D01*
Y416801D01*
X501782D01*
Y416601D01*
G37*
G36*
G01X505182Y417001D02*
X505232Y417751D01*
X505632D01*
X505682Y417001D01*
Y416801D01*
X505182D01*
Y417001D01*
G37*
G36*
G01X502582D02*
X502632Y417751D01*
X503032D01*
X503082Y417001D01*
Y416801D01*
X502582D01*
Y417001D01*
G37*
G36*
G01X499982D02*
X500032Y417751D01*
X500432D01*
X500482Y417001D01*
Y416801D01*
X499982D01*
Y417001D01*
G37*
G36*
G01X506982Y416601D02*
X506932Y415851D01*
X506532D01*
X506482Y416601D01*
Y416801D01*
X506982D01*
Y416601D01*
G37*
G36*
G01X509582D02*
X509532Y415851D01*
X509132D01*
X509082Y416601D01*
Y416801D01*
X509582D01*
Y416601D01*
G37*
G36*
G01X507782Y417001D02*
X507832Y417751D01*
X508232D01*
X508282Y417001D01*
Y416801D01*
X507782D01*
Y417001D01*
G37*
G36*
G01X512182Y416601D02*
X512132Y415851D01*
X511732D01*
X511682Y416601D01*
Y416801D01*
X512182D01*
Y416601D01*
G37*
G36*
G01X512982Y417001D02*
X513032Y417751D01*
X513432D01*
X513482Y417001D01*
Y416801D01*
X512982D01*
Y417001D01*
G37*
G36*
G01X510382D02*
X510432Y417751D01*
X510832D01*
X510882Y417001D01*
Y416801D01*
X510382D01*
Y417001D01*
G37*
G36*
G01X515144Y417625D02*
X514649Y418190D01*
X514932Y418473D01*
X515497Y417978D01*
X515639Y417837D01*
X515285Y417483D01*
X515144Y417625D01*
G37*
G36*
G01X516699Y418615D02*
X517194Y418049D01*
X516912Y417766D01*
X516346Y418261D01*
X516205Y418403D01*
X516558Y418756D01*
X516699Y418615D01*
G37*
G36*
G01X516982Y419463D02*
X516487Y420029D01*
X516770Y420312D01*
X517336Y419817D01*
X517477Y419675D01*
X517124Y419322D01*
X516982Y419463D01*
G37*
G36*
G01X518538Y420453D02*
X519033Y419887D01*
X518750Y419605D01*
X518184Y420100D01*
X518043Y420241D01*
X518397Y420595D01*
X518538Y420453D01*
G37*
G36*
G01X522215Y424130D02*
X522710Y423564D01*
X522427Y423282D01*
X521861Y423777D01*
X521720Y423918D01*
X522073Y424271D01*
X522215Y424130D01*
G37*
G36*
G01X518821Y421302D02*
X518326Y421867D01*
X518609Y422150D01*
X519174Y421655D01*
X519316Y421514D01*
X518962Y421160D01*
X518821Y421302D01*
G37*
G36*
G01X520659Y423140D02*
X520164Y423706D01*
X520447Y423989D01*
X521013Y423494D01*
X521154Y423352D01*
X520801Y422999D01*
X520659Y423140D01*
G37*
G36*
G01X524336Y426817D02*
X523841Y427383D01*
X524124Y427666D01*
X524690Y427171D01*
X524831Y427029D01*
X524478Y426676D01*
X524336Y426817D01*
G37*
G36*
G01X522498Y424979D02*
X522003Y425544D01*
X522286Y425827D01*
X522851Y425332D01*
X522993Y425191D01*
X522639Y424837D01*
X522498Y424979D01*
G37*
G36*
G01X520376Y422292D02*
X520871Y421726D01*
X520589Y421443D01*
X520023Y421938D01*
X519881Y422079D01*
X520235Y422433D01*
X520376Y422292D01*
G37*
G36*
G01X525892Y427807D02*
X526387Y427241D01*
X526104Y426958D01*
X525538Y427453D01*
X525397Y427595D01*
X525750Y427948D01*
X525892Y427807D01*
G37*
G36*
G01X524053Y425969D02*
X524548Y425403D01*
X524266Y425120D01*
X523700Y425615D01*
X523558Y425756D01*
X523912Y426110D01*
X524053Y425969D01*
G37*
G36*
G01X526175Y428656D02*
X525680Y429221D01*
X525963Y429504D01*
X526528Y429009D01*
X526670Y428868D01*
X526316Y428514D01*
X526175Y428656D01*
G37*
G36*
G01X608100Y-21000D02*
X607048Y-19948D01*
Y-15164D01*
X607051Y-15147D01*
G03X607074Y-14877I-1541J267D01*
G01Y-9901D01*
G03X607051Y-9631I-1564J3D01*
G01X607048Y-9614D01*
Y-9165D01*
X606305Y-8422D01*
X606021D01*
X605991Y-8412D01*
G03X605029I-481J-1489D01*
G01X604999Y-8422D01*
X597559D01*
X597250Y-8113D01*
Y-3884D01*
X597827Y-3307D01*
X599416D01*
X600387Y-2336D01*
Y9131D01*
X602761Y11505D01*
Y14499D01*
X602243Y15017D01*
X597858D01*
X597250Y15625D01*
Y18380D01*
X597718Y18848D01*
X600310D01*
X600364Y18902D01*
Y28421D01*
X599416Y29369D01*
X597869D01*
X597250Y29988D01*
Y34165D01*
X597632Y34547D01*
X599437D01*
X600323Y35433D01*
Y47067D01*
X602756Y49500D01*
Y52559D01*
X602276Y53039D01*
X597529D01*
X597250Y53318D01*
Y56372D01*
X597542Y56664D01*
X607018D01*
X607110Y56756D01*
Y66274D01*
X606801Y66583D01*
X606791Y66597D01*
G03X606408Y66980I-1281J-898D01*
G01X606394Y66990D01*
X606173Y67211D01*
X605913D01*
X605889Y67217D01*
G03X605131I-379J-1518D01*
G01X605107Y67211D01*
X597538D01*
X597250Y67499D01*
Y72183D01*
X597446Y72379D01*
X599563D01*
X600323Y73139D01*
Y85644D01*
X602737Y88058D01*
Y91260D01*
X602843Y91316D01*
G03X600787Y92135I-680J1283D01*
G02X600408Y91607I-379J-128D01*
G01X597776D01*
X597250Y92133D01*
Y98581D01*
X598611Y99942D01*
X601947D01*
X607202Y105198D01*
X612938D01*
X613700Y105960D01*
X621260D01*
X624100Y108800D01*
Y111400D01*
X625600Y112900D01*
X661600D01*
X663100Y111400D01*
Y91385D01*
G02X662625Y90992I-400J0D01*
G03Y88140I-273J-1426D01*
G02X663100Y87747I75J-393D01*
G01Y86540D01*
X663090Y86510D01*
G03Y85612I1381J-449D01*
G01X663100Y85582D01*
Y70429D01*
X661795Y69124D01*
Y49528D01*
X660311Y48044D01*
Y45239D01*
X656291Y41219D01*
Y37373D01*
X657082Y36582D01*
X658079D01*
X658297Y36364D01*
Y33353D01*
X657994Y33050D01*
X650973D01*
X650130Y32207D01*
X649973Y32364D01*
G03X647761Y30152I-1106J-1106D01*
G01X648036Y29877D01*
Y29204D01*
X643000Y24168D01*
Y17382D01*
G02X642302Y17115I-400J0D01*
G03Y9041I-4509J-4037D01*
G02X643000Y8774I298J-267D01*
G01Y5535D01*
X642394Y4929D01*
Y-926D01*
G02X641734Y-1229I-400J1D01*
G03X642302Y-9859I-3941J-4593D01*
G02X643000Y-10126I298J-267D01*
G01Y-19000D01*
X641000Y-21000D01*
X608100D01*
G37*
G36*
G01X651765Y161200D02*
X651363Y161602D01*
X616078D01*
X589200Y188480D01*
Y224800D01*
X594781Y230381D01*
X622818D01*
X624880Y228319D01*
Y212858D01*
X640788Y196950D01*
X663050D01*
X664000Y196000D01*
Y183000D01*
X665000Y182000D01*
X695500D01*
X696500Y183000D01*
Y196451D01*
X697312Y197263D01*
X708991D01*
X709005Y197261D01*
G03X709395I195J1439D01*
G01X709409Y197263D01*
X715897D01*
X715937Y197244D01*
G03X717177I620J1313D01*
G01X717217Y197263D01*
X734695D01*
X742331Y189627D01*
X767716D01*
X768696Y188647D01*
Y177511D01*
X767656Y176471D01*
X752440D01*
X752411Y176500D01*
X736019D01*
X734800Y175281D01*
Y166583D01*
X734233Y166016D01*
Y165391D01*
X734223Y165360D01*
G03Y164440I1377J-460D01*
G01X734233Y164409D01*
Y163831D01*
X734800Y163264D01*
Y162000D01*
X734000Y161200D01*
X651765D01*
G37*
G36*
G01X562534Y325502D02*
G03I-568J0D01*
G37*
G36*
G01X562539Y317320D02*
G03I-568J0D01*
G37*
G36*
G01X565966Y479316D02*
X581260D01*
X584077Y476499D01*
Y454843D01*
X590472Y448448D01*
Y443072D01*
X582720Y435320D01*
X572793D01*
X564733Y443380D01*
Y478083D01*
X565966Y479316D01*
G37*
G36*
G01X613574Y449332D02*
X610788Y452118D01*
X610740D01*
X610297Y452560D01*
G03X607774Y452118I-1106J-1106D01*
G01X591286D01*
X587485Y455918D01*
Y477585D01*
X595639Y485739D01*
X604529D01*
X604560Y485729D01*
G03X605792I616J1852D01*
G01X605823Y485739D01*
X606146D01*
X606850Y485035D01*
Y471350D01*
X606900Y471300D01*
Y467454D01*
X606738Y467423D01*
G03X606966Y464546I274J-1426D01*
G02X607330Y464009I-12J-400D01*
G03X609906Y462369I1470J-533D01*
G01X611838Y464300D01*
X615787D01*
X616904Y463184D01*
X619059D01*
G03X621964Y463990I1341J806D01*
G01Y464300D01*
X625955D01*
X625989Y464334D01*
G02X626666Y463983I283J-283D01*
G03X628255Y465572I1923J-334D01*
G02X627904Y466249I-68J394D01*
G01X629286Y467631D01*
X629368D01*
G03X631311Y469574I-9J1952D01*
G01Y469656D01*
X632982Y471327D01*
X633048Y471337D01*
G03X634703Y472992I-277J1932D01*
G01X634713Y473058D01*
X636964Y475309D01*
G02X637629Y475147I283J-282D01*
G03X640226Y474514I1491J473D01*
G01X641564Y475852D01*
Y479648D01*
X641434Y479779D01*
X642411Y480756D01*
X662744D01*
X677377Y466123D01*
X681623D01*
X685273Y462473D01*
Y459086D01*
X684436Y458248D01*
Y450248D01*
X683519Y449332D01*
X613574D01*
G37*
G36*
G01X569451Y490658D02*
X566338Y493771D01*
Y510599D01*
X567598Y511859D01*
X570520D01*
G03X572170I825J1255D01*
G01X573922D01*
G03X576410I1244J841D01*
G01X579197D01*
G03X581335I1069J1055D01*
G01X586204D01*
X587983Y510080D01*
Y494068D01*
X584573Y490658D01*
X569451D01*
G37*
G36*
G01X644500Y592937D02*
Y571616D01*
X644498Y571615D01*
Y565885D01*
X644500Y565884D01*
Y565650D01*
X645650Y564500D01*
X660600D01*
X661424Y563676D01*
Y563600D01*
X662800Y562224D01*
Y528877D01*
X664800Y526876D01*
Y524101D01*
X665076Y523825D01*
X667852D01*
X670500Y521177D01*
Y518400D01*
X670302Y518202D01*
X668398D01*
X668200Y518400D01*
Y518900D01*
X667100Y520000D01*
X667052D01*
Y520052D01*
X664148D01*
X664000Y520200D01*
Y520900D01*
X662481Y522419D01*
X646800D01*
X645200Y520819D01*
Y506400D01*
X637800Y499000D01*
X618300D01*
X612600Y493300D01*
X599000D01*
X597900Y494400D01*
Y505734D01*
X601066Y508900D01*
Y510568D01*
X601878Y511380D01*
X602366D01*
X602788Y511802D01*
Y514468D01*
X602652Y514604D01*
Y514702D01*
X602554D01*
X602528Y514728D01*
X601748D01*
X601066Y515410D01*
X598543D01*
X597600Y516353D01*
Y518671D01*
X598174Y519245D01*
X599896D01*
X600481Y518660D01*
Y517522D01*
X601521Y516482D01*
X606232D01*
X607305Y517555D01*
Y529450D01*
X605681Y531074D01*
X601358D01*
X600643Y531789D01*
Y547908D01*
X602434Y549698D01*
X602552D01*
Y552702D01*
X602480D01*
X601748Y553433D01*
X598575D01*
X597600Y554408D01*
Y556955D01*
X598010Y557365D01*
X600253D01*
X600782Y557894D01*
Y573768D01*
X600741Y573809D01*
Y586109D01*
X602130Y587498D01*
X602552D01*
Y590502D01*
X601052D01*
Y591002D01*
X598012D01*
X597600Y591414D01*
Y594717D01*
X597849Y594966D01*
X599668D01*
X600318Y594316D01*
Y593244D01*
X601716Y591846D01*
X606201D01*
X607761Y593406D01*
Y604715D01*
X606006Y606470D01*
X603536D01*
X601033Y608973D01*
Y622965D01*
X602268Y624200D01*
X636600D01*
X644500Y616300D01*
Y595863D01*
X644324Y595841D01*
G03Y592959I176J-1441D01*
G01X644500Y592937D01*
G37*
G36*
G01X667602Y13685D02*
Y15215D01*
X667248Y15569D01*
Y15570D01*
X667246D01*
X666815Y16002D01*
X659285D01*
X659283Y16000D01*
X658283Y17000D01*
X658002D01*
Y17002D01*
X652998D01*
Y17000D01*
X652800D01*
X652250Y16450D01*
X650500D01*
X650000Y16950D01*
Y20100D01*
X650900Y21000D01*
X658500D01*
X662500Y17000D01*
X662950D01*
X663150Y16800D01*
X665950D01*
X666150Y17000D01*
X667100D01*
X667600Y17500D01*
Y23600D01*
X668400Y24400D01*
X674200D01*
X674800Y23800D01*
Y17160D01*
X674825Y17135D01*
Y15915D01*
X674690Y15780D01*
Y8765D01*
X674348Y8423D01*
X668033D01*
X667702Y8755D01*
Y13315D01*
X667600Y13416D01*
Y13684D01*
X667602Y13685D01*
G37*
G36*
G01X662600Y2700D02*
X662000Y3300D01*
Y10600D01*
X664500Y13100D01*
X666500D01*
X666700Y12900D01*
Y3896D01*
G03X665552Y2765I10465J-11770D01*
G01X665493Y2700D01*
X662600D01*
G37*
G36*
G01X648501Y7072D02*
X648382Y7191D01*
Y13732D01*
X648650Y14000D01*
X652998D01*
Y13998D01*
X658002D01*
Y14000D01*
X658700D01*
X659700Y15000D01*
X666400D01*
X666600Y14800D01*
Y14102D01*
X664085D01*
X663959Y13975D01*
X663875D01*
X661000Y11100D01*
Y11016D01*
X660998Y11015D01*
Y10898D01*
X657172Y7072D01*
X648501D01*
G37*
G36*
G01X661742Y37920D02*
X658476D01*
X658384Y38012D01*
Y41128D01*
X662152Y44896D01*
Y48357D01*
X662967Y49172D01*
X666878D01*
X667442Y48608D01*
Y46689D01*
X664105Y43352D01*
X664102D01*
X661921Y41171D01*
Y38099D01*
X661742Y37920D01*
G37*
G36*
G01X637166Y113974D02*
X635252Y115889D01*
Y118368D01*
X635382Y118498D01*
Y119652D01*
X634456Y120578D01*
X630884D01*
X623100Y128361D01*
Y131942D01*
X623902Y132744D01*
X649527D01*
X649981Y132290D01*
X650078D01*
X650080Y132288D01*
X658988D01*
X660057Y133357D01*
Y142812D01*
X660934Y143689D01*
Y159176D01*
X661457Y159700D01*
X733600D01*
X734098Y160198D01*
X734415D01*
X735802Y161585D01*
Y163679D01*
X735234Y164246D01*
Y165601D01*
X735802Y166168D01*
Y173958D01*
X737144Y175300D01*
X759507D01*
X765118Y169689D01*
X779871D01*
G03X786507I3318J13578D01*
G01X811219D01*
X815562Y165346D01*
Y139567D01*
X811859Y135864D01*
X756164D01*
X755000Y134700D01*
Y128200D01*
X750800Y124000D01*
X739200D01*
X735000Y128200D01*
Y134700D01*
X734999Y134701D01*
Y135263D01*
X734291Y135971D01*
X694106D01*
X688640Y130505D01*
Y116251D01*
X686363Y113974D01*
X637166D01*
G37*
G36*
G01X639470Y201010D02*
X634599Y205881D01*
Y231438D01*
X634592Y231444D01*
Y234424D01*
X635412Y235244D01*
X638833D01*
X640250Y236661D01*
Y245978D01*
X638502Y247726D01*
Y247752D01*
X638476D01*
X638467Y247761D01*
X635456D01*
X635360Y247857D01*
Y251259D01*
X635608Y251507D01*
X638652D01*
X639093Y251066D01*
Y250434D01*
X639098Y250429D01*
Y249909D01*
X640223Y248784D01*
X642188D01*
X642288Y248684D01*
Y247537D01*
X643225Y246600D01*
X654900D01*
X655700Y245800D01*
Y203160D01*
X653550Y201010D01*
X639470D01*
G37*
G36*
G01X659248Y255752D02*
X658852Y256148D01*
Y269852D01*
X659248Y270248D01*
X673252D01*
X673348Y270152D01*
Y256348D01*
X672752Y255752D01*
X659248D01*
G37*
G36*
G01X633234Y233893D02*
X629473D01*
X629074Y234292D01*
Y249102D01*
X629418Y249446D01*
X633675D01*
X634252Y248869D01*
Y246329D01*
X634844Y245737D01*
X638498D01*
X638556Y245679D01*
Y237310D01*
X638516Y237270D01*
X635232D01*
X633578Y235616D01*
Y234237D01*
X633234Y233893D01*
G37*
G36*
G01X654450Y330320D02*
X655930Y331800D01*
X678630D01*
X679940Y330490D01*
Y307050D01*
X678770Y305880D01*
X655990D01*
X654450Y307420D01*
Y330320D01*
G37*
G36*
G01X654423Y290986D02*
X656503D01*
X657104Y290385D01*
Y289122D01*
X657633Y288593D01*
X659446D01*
X659636Y288403D01*
Y286555D01*
X659543Y286462D01*
X655537D01*
X654300Y287699D01*
Y290863D01*
X654423Y290986D01*
G37*
G36*
G01X642800Y293500D02*
X641700Y294600D01*
Y299100D01*
X642300Y299700D01*
X651300D01*
X651700Y300100D01*
Y302900D01*
X651900Y303100D01*
X652500D01*
X652800Y302800D01*
Y294000D01*
X652300Y293500D01*
X652002D01*
Y293502D01*
X649998D01*
Y293500D01*
X648502D01*
Y293502D01*
X646498D01*
Y293500D01*
X645336D01*
X645302Y293512D01*
G03X644298I-502J-1362D01*
G01X644264Y293500D01*
X642800D01*
G37*
G36*
G01X639000Y361600D02*
X634800Y365800D01*
Y407200D01*
X635100Y407500D01*
X635998D01*
Y407498D01*
X638002D01*
Y407500D01*
X639498D01*
Y407498D01*
X641502D01*
Y407500D01*
X657800D01*
X673054Y392246D01*
Y366711D01*
X667943Y361600D01*
X639000D01*
G37*
G36*
G01X696800Y409771D02*
X691118D01*
Y409772D01*
X690896D01*
X686962Y413706D01*
X680994D01*
X679664Y415036D01*
Y421248D01*
X672348Y428564D01*
X671422D01*
X671419Y428565D01*
G03X671366Y428566I-56J-1564D01*
G01X653849D01*
X653525Y428890D01*
X653523D01*
X652664Y429748D01*
Y435548D01*
X649424Y438788D01*
G03X646709Y441002I-1334J1136D01*
G01X643885D01*
X641559Y438675D01*
G02X641282Y438669I-142J142D01*
G03X641351Y436598I-982J-1069D01*
G01X642315D01*
X644715Y438998D01*
X645820D01*
G02X646103Y438316I0J-400D01*
G01X642887Y435100D01*
X641950D01*
X641227Y434377D01*
X630993D01*
X629270Y436100D01*
Y443430D01*
X631676Y445836D01*
X684448D01*
X687564Y448952D01*
Y456952D01*
X687941Y457328D01*
X693015D01*
X693640Y456702D01*
Y455528D01*
X693730Y455438D01*
Y443369D01*
X695160Y441940D01*
X700265D01*
X700423Y442098D01*
X705477D01*
X705490Y442110D01*
X708810D01*
X710945Y444245D01*
Y455161D01*
X712269Y456485D01*
X713915D01*
X714400Y456000D01*
Y448000D01*
X723900D01*
X725118Y446782D01*
Y438390D01*
X724139Y437411D01*
X716093D01*
X714400Y435718D01*
Y427000D01*
X723552Y417848D01*
Y416047D01*
X722405Y414900D01*
X705200D01*
X704200Y413900D01*
X700929D01*
X696800Y409771D01*
G37*
G36*
G01X618452Y411890D02*
Y424646D01*
X621506Y427700D01*
X644528D01*
X647100Y425128D01*
X669949D01*
X675333Y419742D01*
Y410299D01*
X673793Y408759D01*
X642195D01*
X641946Y409008D01*
X621334D01*
X618452Y411890D01*
G37*
G36*
G01X678000Y467200D02*
X663300Y481900D01*
X656200D01*
X655000Y483100D01*
Y484500D01*
X655818Y485318D01*
X657824D01*
X662506Y490000D01*
X671500D01*
X673700Y487800D01*
X684800D01*
X684898Y487702D01*
Y484889D01*
X692136Y477652D01*
Y467200D01*
X678000D01*
G37*
G36*
G01X650761Y508196D02*
X649234Y509723D01*
Y519082D01*
X649495Y519343D01*
X662651D01*
X663973Y518021D01*
X666911D01*
X667100Y517832D01*
Y512603D01*
X666006Y511509D01*
Y510432D01*
X663770Y508196D01*
X660613D01*
G02X660243Y508748I0J400D01*
G03X657557I-1343J552D01*
G02X657187Y508196I-370J-152D01*
G01X650761D01*
G37*
G36*
G01X650599Y580493D02*
X650099Y580993D01*
Y584493D01*
X651099Y585493D01*
X657696D01*
X657936Y585254D01*
Y584726D01*
X660099Y582562D01*
Y581493D01*
X659602Y580996D01*
X653545D01*
X653516Y580967D01*
Y580966D01*
X653043Y580493D01*
X650599D01*
G37*
G36*
G01X646250Y565550D02*
X645500Y566300D01*
Y571200D01*
X646200Y571900D01*
X659621D01*
X662121Y574400D01*
Y574515D01*
X664504Y576898D01*
X666702D01*
X666900Y576700D01*
Y566200D01*
X666249Y565550D01*
X646250D01*
G37*
G36*
G01X648200Y573500D02*
Y578000D01*
X649000Y578800D01*
X652700D01*
X653600Y577900D01*
X659100D01*
X660193Y578993D01*
X667099D01*
Y577900D01*
X664000D01*
X663553Y577453D01*
Y577447D01*
X659060Y572954D01*
X648746D01*
X648200Y573500D01*
G37*
G36*
G01X715813Y-16911D02*
X713369Y-14467D01*
X712934D01*
Y-8610D01*
X712988Y-8556D01*
X715429D01*
X715439Y-8546D01*
X715648D01*
X716479Y-7715D01*
X717844D01*
X720437Y-5122D01*
Y-2650D01*
X720650Y-2437D01*
Y-63D01*
X720437Y150D01*
Y1052D01*
X719937Y1552D01*
X712737D01*
X712437Y1852D01*
Y8152D01*
X713037Y8752D01*
X728248D01*
X728500Y8500D01*
Y2052D01*
X728000Y1552D01*
X723753D01*
X723752Y1554D01*
X722222D01*
X722221Y1552D01*
X721937D01*
X721387Y1002D01*
Y-6998D01*
X720437Y-7948D01*
Y-8246D01*
X720436D01*
Y-13139D01*
X720742Y-13445D01*
Y-16489D01*
X720320Y-16911D01*
X715813D01*
G37*
G36*
G01X690818Y18869D02*
X691346Y18341D01*
Y16181D01*
G03Y14419I1154J-881D01*
G01Y11841D01*
X689423Y9918D01*
X686578D01*
X686055Y10441D01*
Y18513D01*
X686411Y18869D01*
X690818D01*
G37*
G36*
G01X735800Y-10400D02*
X733189D01*
X724438Y-1650D01*
Y550D01*
X728415D01*
X728516Y652D01*
X735748D01*
X736500Y-100D01*
Y-9700D01*
X735800Y-10400D01*
G37*
G36*
G01X723508Y-17748D02*
X722764Y-17004D01*
Y-13702D01*
X723416Y-13050D01*
X723438D01*
Y-8046D01*
X723437D01*
Y-7348D01*
X722437Y-6348D01*
Y352D01*
X722637Y552D01*
X723337D01*
X723437Y452D01*
Y-2122D01*
X729939Y-8624D01*
Y-13536D01*
X729753Y-13722D01*
Y-17292D01*
X729297Y-17748D01*
X723508D01*
G37*
G36*
G01X680994Y26774D02*
X678359Y29409D01*
Y31500D01*
X678610Y31751D01*
X681498D01*
Y31748D01*
X683502D01*
Y31751D01*
X684998D01*
Y31748D01*
X686728D01*
X687833Y30643D01*
Y27042D01*
X687751Y26960D01*
X685412D01*
X685226Y26774D01*
X680994D01*
G37*
G36*
G01X717366Y32275D02*
X714137Y35504D01*
X708701D01*
X707322Y36883D01*
X706817D01*
X704000Y39700D01*
Y43500D01*
X703500Y44000D01*
X700916D01*
X700915Y44002D01*
X700598D01*
X700300Y44300D01*
Y49500D01*
X700500Y49700D01*
X709100D01*
X709400Y50000D01*
X714500D01*
X715242Y50742D01*
X717528D01*
X718890Y52104D01*
Y53222D01*
X718898Y53230D01*
Y54392D01*
X719004Y54498D01*
X724002D01*
Y54546D01*
X726498D01*
Y54498D01*
X731486D01*
X731700Y54285D01*
Y47844D01*
X730466Y46610D01*
X724274D01*
X723128Y45464D01*
Y40448D01*
X723164Y40412D01*
X724661D01*
X725120Y39953D01*
Y32999D01*
X724396Y32275D01*
X717366D01*
G37*
G36*
G01X715246Y52254D02*
X714497Y53003D01*
X709349D01*
X709000Y53352D01*
Y61500D01*
X708500Y62000D01*
X694500D01*
X694156Y62344D01*
Y65913D01*
X693974Y66095D01*
Y67378D01*
X694610Y68014D01*
X696138D01*
Y68031D01*
X696695D01*
X697175Y68512D01*
Y70708D01*
X696030Y71853D01*
X673647D01*
X672000Y73500D01*
Y88379D01*
G03Y89999I-1205J810D01*
G01Y111400D01*
X673500Y112900D01*
X687600D01*
X689098Y111402D01*
Y102226D01*
X689100Y102225D01*
Y100100D01*
X688500Y99500D01*
Y91600D01*
X689138Y90962D01*
X693524D01*
X694485Y91923D01*
Y92422D01*
X696666Y94603D01*
X704330D01*
X707027Y97300D01*
X713261D01*
X713512Y97049D01*
Y95185D01*
X713303Y94976D01*
X708465D01*
X705910Y92420D01*
X696708D01*
X696561Y92274D01*
X696274D01*
X695500Y91500D01*
Y89400D01*
X697462Y87438D01*
X702961D01*
X707200Y83199D01*
X709473D01*
G03X709647I87J1449D01*
G01X710249D01*
X711436Y84386D01*
X714210D01*
X717672Y80924D01*
Y80875D01*
X717016Y80218D01*
G02X716387Y80301I-283J283D01*
G03X714140Y78512I-1257J-727D01*
G01X714142Y78510D01*
X714319Y78333D01*
Y78077D01*
X712748Y76506D01*
Y74871D01*
X713912Y73707D01*
X715491D01*
X719432Y77648D01*
X720948D01*
X727500Y71096D01*
Y64500D01*
X724539Y61539D01*
Y57972D01*
X724085Y57518D01*
X719018D01*
X719002Y57502D01*
X718998D01*
Y57498D01*
X717529Y56029D01*
Y52338D01*
X717445Y52254D01*
X715246D01*
G37*
G36*
G01X691200Y43600D02*
X690600Y44200D01*
Y48400D01*
X690100Y48900D01*
X686900D01*
X686800Y49000D01*
Y50100D01*
X686900Y50200D01*
X698600D01*
X699100Y49700D01*
Y44002D01*
X698085D01*
X697684Y43600D01*
X691200D01*
G37*
G36*
G01X683200Y50350D02*
X679139D01*
X673544Y44756D01*
X673194Y44406D01*
X673185D01*
X671210Y42430D01*
X667993D01*
X667510Y41947D01*
Y41705D01*
Y38902D01*
X667305Y38698D01*
X664252D01*
X663931Y39019D01*
Y41565D01*
X669000Y46634D01*
Y65000D01*
X674500Y70500D01*
X676182D01*
G02X676579Y70050I0J-400D01*
G03X679461I1441J-180D01*
G02X679858Y70500I397J50D01*
G01X685725D01*
X685914Y70311D01*
Y67247D01*
X687159Y66002D01*
X688498D01*
X688500Y66000D01*
X692500D01*
X693150Y65350D01*
Y61350D01*
X693350Y61150D01*
X693934D01*
X694085Y60998D01*
X707998D01*
Y52937D01*
X708150Y52786D01*
Y52350D01*
X708400Y52100D01*
X708836D01*
X708934Y52002D01*
X712198D01*
X712200Y52000D01*
Y51002D01*
X708985D01*
X708934Y50950D01*
X699266D01*
X699015Y51202D01*
X691422D01*
X689636Y52988D01*
X689512D01*
X689500Y53000D01*
X685850D01*
X683200Y50350D01*
G37*
G36*
G01X741100Y-18200D02*
X737731Y-14831D01*
Y8192D01*
X737082Y8841D01*
Y29082D01*
X738137Y30137D01*
X738415D01*
X738581Y29971D01*
X738596Y29929D01*
G03X741704Y26508I5693J2049D01*
G03X742071Y37607I2589J5470D01*
G03X739703Y35925I2217J-5629D01*
G02X739000Y36186I-303J261D01*
G01Y46670D01*
G02X739703Y46931I400J0D01*
G03X744859Y44853I4588J3947D01*
G03X744464Y56928I-566J6025D01*
G03X741101Y56021I-172J-6050D01*
G01X741052Y55991D01*
X739698D01*
X737432Y58257D01*
Y73952D01*
X734588Y76796D01*
X734111D01*
X734083Y76804D01*
G03X733259I-412J-1392D01*
G01X733231Y76796D01*
X727904D01*
X724510Y80190D01*
Y94627D01*
X724887Y95004D01*
X729808D01*
X731804Y97000D01*
X732494D01*
G02X732763Y96304I0J-400D01*
G03X732364Y94768I977J-1074D01*
G02X731968Y94241I-379J-127D01*
G03X733286Y93252I-59J-1451D01*
G02X733682Y93779I379J127D01*
G03X734717Y96304I58J1451D01*
G02X734986Y97000I269J296D01*
G01X745600D01*
X752800Y104200D01*
X764600D01*
X765213Y103587D01*
X765161Y103463D01*
G03X765500Y101847I1339J-563D01*
G01Y95000D01*
X765000Y94500D01*
X763809D01*
X763797Y94687D01*
G03X759556Y95045I-2147J-137D01*
G02X759337Y94892I-195J45D01*
G03X759000Y94912I-334J-2781D01*
G01X753100D01*
G03X752477Y89380I0J-2801D01*
G01X752533Y89367D01*
X753300Y88600D01*
Y87200D01*
X753700Y86800D01*
Y83800D01*
X754500Y83000D01*
X754960D01*
X755024Y82989D01*
X755039Y82984D01*
G03X755975Y82989I461J1377D01*
G01X756007Y83000D01*
X762115D01*
G02X762390Y82309I0J-400D01*
G03X764310I960J-1089D01*
G02X764585Y83000I275J291D01*
G01X766600D01*
X767130Y82470D01*
Y78833D01*
G03X767500Y77454I2751J-1D01*
G01Y57300D01*
X767200Y57000D01*
X765109D01*
G03X763091I-1009J-1900D01*
G01X757647D01*
G03X752698Y55200I-2147J-1800D01*
G01Y52750D01*
G03X753998Y50385I2801J0D01*
G01Y47748D01*
X754000D01*
Y46200D01*
X754265Y45935D01*
X754277Y45916D01*
G03X755724Y45265I1223J784D01*
G03X756317Y45500I-225J1434D01*
G01X766400D01*
X767130Y44770D01*
Y41033D01*
G03X767500Y39654I2751J-1D01*
G01Y19900D01*
X766600Y19000D01*
X765109D01*
G03X763132Y19021I-1009J-1900D01*
G01X763089Y19000D01*
X762327D01*
G03X758119Y19281I-2227J-1700D01*
G01X757838Y19000D01*
X757635D01*
X757575Y19066D01*
G03X752698Y17184I-2075J-1882D01*
G01Y14750D01*
G03X753998Y12385I2801J0D01*
G01Y9748D01*
X754000D01*
Y8000D01*
X754500Y7500D01*
X754680D01*
X754729Y7469D01*
G03X755775Y7274I771J1231D01*
G03X756317Y7500I-276J1425D01*
G01X766700D01*
X767130Y7070D01*
Y3233D01*
G03X767500Y1854I2751J-1D01*
G01Y-17500D01*
X766800Y-18200D01*
X741100D01*
G37*
G36*
G01X700816Y34300D02*
X700302Y34815D01*
Y37328D01*
X700200Y37429D01*
Y37437D01*
X698000Y39637D01*
Y42500D01*
X698500Y43000D01*
X700500D01*
X701000Y42500D01*
Y39600D01*
X702587Y38013D01*
Y34687D01*
X702200Y34300D01*
X700816D01*
G37*
G36*
G01X694390Y101790D02*
X690951D01*
X690100Y102641D01*
Y129600D01*
X695000Y134500D01*
X732000D01*
X733000Y133500D01*
Y127500D01*
X738000Y122500D01*
X751800D01*
X756600Y127300D01*
Y133500D01*
X757600Y134500D01*
X786200D01*
X789050Y131650D01*
Y108100D01*
X787250Y106300D01*
X753300D01*
X745500Y98500D01*
X734461D01*
X730927Y102034D01*
X725164D01*
X723625Y103573D01*
X703335D01*
X701564Y101802D01*
X694402D01*
X694390Y101790D01*
G37*
G36*
G01X727577Y241971D02*
X734543D01*
X736743Y244171D01*
X746974D01*
X747558Y243587D01*
Y239568D01*
X747061Y239071D01*
X738283D01*
X735300Y236088D01*
Y235000D01*
X734702Y234402D01*
X720398D01*
X719700Y235100D01*
Y237000D01*
X718346Y238354D01*
Y239232D01*
X717468D01*
X715700Y241000D01*
X690480D01*
X689165Y239685D01*
Y233156D01*
X689821Y232500D01*
X696600D01*
X699000Y230100D01*
Y229802D01*
X698998D01*
Y227998D01*
X699000D01*
Y227175D01*
X700800Y225375D01*
Y224600D01*
X700900Y224500D01*
Y221300D01*
X701300Y220900D01*
X705200D01*
X705300Y221000D01*
Y224600D01*
X705400Y224700D01*
X706100D01*
X706200Y224600D01*
Y221300D01*
X706600Y220900D01*
X707100D01*
X707400Y220600D01*
Y214400D01*
X706900Y213900D01*
X699600D01*
X698300Y212600D01*
Y204500D01*
X698260Y204460D01*
Y200093D01*
X697949Y199782D01*
X696207D01*
X696065Y199924D01*
Y202302D01*
X695311Y203056D01*
X690260D01*
X689600Y203716D01*
Y223800D01*
X689100Y224300D01*
X683200D01*
X681800Y222900D01*
X674700D01*
X674000Y223600D01*
Y225550D01*
X674250Y225800D01*
X680550D01*
X681100Y226350D01*
Y229850D01*
X680600Y230350D01*
X676950D01*
X676200Y229600D01*
X667950D01*
X666700Y230850D01*
Y248140D01*
X667236Y248676D01*
X668258D01*
X669582Y250000D01*
X680903D01*
X681348Y249556D01*
X682462D01*
X684821Y247196D01*
X693014D01*
X693818Y248000D01*
X716900D01*
X718500Y246400D01*
Y243500D01*
X718998Y243002D01*
Y242498D01*
X719502D01*
X722600Y239400D01*
X724421D01*
X725216Y240195D01*
X725329Y240163D01*
G03X727177Y241569I396J1397D01*
G02X727577Y241971I400J2D01*
G37*
G36*
G01X665800Y183100D02*
X665300Y183600D01*
Y195800D01*
X669898Y200398D01*
X685315D01*
X686416Y201500D01*
X693000D01*
X694000Y200500D01*
Y197500D01*
X695300Y196200D01*
Y183400D01*
X695000Y183100D01*
X665800D01*
G37*
G36*
G01X706932Y198300D02*
X706487Y198745D01*
X700607D01*
X700514Y198838D01*
X699700Y199651D01*
Y199988D01*
X699768D01*
Y201990D01*
X699700D01*
Y211800D01*
X700300Y212400D01*
X707200D01*
X707500Y212100D01*
Y209370D01*
X707358D01*
Y205966D01*
X711834D01*
X713100Y204700D01*
X714900D01*
X715498Y204102D01*
Y202098D01*
X715502D01*
X716000Y201600D01*
X716498D01*
Y201598D01*
X719502D01*
Y201600D01*
X720550D01*
X726350Y207400D01*
Y218850D01*
X726340Y218860D01*
Y219016D01*
X720900Y224456D01*
Y227050D01*
X718750Y229200D01*
X712950D01*
X711450Y230700D01*
X700000D01*
X697100Y233600D01*
X690359D01*
X690204Y233755D01*
Y238322D01*
X690244Y238362D01*
Y239155D01*
X690689Y239600D01*
X715400D01*
X718000Y237000D01*
Y234100D01*
X718700Y233400D01*
X735677D01*
X736366Y234089D01*
Y234864D01*
X738036Y236534D01*
X746201D01*
X747800Y234935D01*
Y227200D01*
X751300Y223700D01*
Y215200D01*
X748800Y212700D01*
X741350D01*
X739500Y210850D01*
Y201650D01*
X736150Y198300D01*
X718403D01*
G02X718005Y198669I1J400D01*
G03X715109I-1448J-112D01*
G02X714711Y198300I-399J31D01*
G01X711005D01*
G03X710638Y198498I-1605J-2537D01*
G03X707748Y198700I-1438J202D01*
G02X707348Y198300I-400J0D01*
G01X706932D01*
G37*
G36*
G01X686000Y222800D02*
X688200D01*
X688500Y222500D01*
Y205000D01*
X684900Y201400D01*
X668081D01*
X666612Y202869D01*
Y219124D01*
X667188Y219700D01*
X682900D01*
X686000Y222800D01*
G37*
G36*
G01X718500Y268000D02*
Y282000D01*
X732500D01*
Y268000D01*
X718500D01*
G37*
G36*
G01X684800Y269800D02*
X682900D01*
X681200Y268100D01*
X674800D01*
X674500Y268400D01*
Y268600D01*
X674775Y268875D01*
X678275D01*
X679100Y269700D01*
Y271000D01*
X680200Y272100D01*
Y278200D01*
X681300Y279300D01*
X684600D01*
X685000Y278900D01*
Y270000D01*
X684800Y269800D01*
G37*
G36*
G01X722800Y337700D02*
Y377000D01*
X737200D01*
X738900Y375300D01*
Y335000D01*
X737500Y333600D01*
X726900D01*
X722800Y337700D01*
G37*
G36*
G01X708100Y332800D02*
X708900D01*
X713400Y328300D01*
Y323100D01*
X712200Y321900D01*
X705600D01*
X702100Y325400D01*
X700400D01*
X699400Y326400D01*
Y332500D01*
X699800Y332900D01*
X708000D01*
X708100Y332800D01*
G37*
G36*
G01X713900Y285100D02*
X712800Y286200D01*
X709263D01*
X709169Y286294D01*
Y293269D01*
X709500Y293600D01*
X713977D01*
X715800Y291777D01*
Y288100D01*
X716100Y287800D01*
X717000D01*
X717200Y287600D01*
Y285500D01*
X716800Y285100D01*
X713900D01*
G37*
G36*
G01X663727Y288773D02*
X663300Y289200D01*
Y293200D01*
X664500Y294400D01*
Y296300D01*
X664700Y296500D01*
Y298500D01*
X665400Y299200D01*
Y302800D01*
X665700Y303100D01*
X666200D01*
X666600Y302700D01*
Y298900D01*
X666598Y298898D01*
X666623Y298873D01*
X666594Y298763D01*
G03X666698Y297757I1406J-363D01*
G01X666719Y297715D01*
Y296002D01*
X666698D01*
Y293998D01*
X666719D01*
Y291810D01*
X666488Y291579D01*
Y289388D01*
X665873Y288773D01*
X663727D01*
G37*
G36*
G01X698913Y382835D02*
X698564Y383184D01*
Y385048D01*
X698500Y385113D01*
Y407000D01*
X699500Y408000D01*
X725500D01*
X726500Y407000D01*
Y386500D01*
X722835Y382835D01*
X698913D01*
G37*
G36*
G01X702407Y443373D02*
X701444Y444336D01*
Y495844D01*
X702500Y496900D01*
X708800D01*
X709774Y495926D01*
Y491687D01*
X709196Y491108D01*
Y490894D01*
X705383Y487081D01*
Y443579D01*
X705177Y443373D01*
X702407D01*
G37*
G36*
G01X707407D02*
X706444Y444336D01*
Y483864D01*
X707563Y484983D01*
X709196D01*
Y484892D01*
X710876Y483211D01*
Y467798D01*
X711019Y467655D01*
Y456651D01*
X709944Y455576D01*
Y455568D01*
X709943Y455567D01*
Y444659D01*
X708657Y443373D01*
X707407D01*
G37*
G36*
G01X695575Y442941D02*
X694732Y443784D01*
Y444310D01*
X694743Y444343D01*
G03Y445507I-1652J582D01*
G01X694732Y445540D01*
Y449310D01*
X694743Y449343D01*
G03Y450507I-1652J582D01*
G01X694732Y450540D01*
Y454310D01*
X694743Y454343D01*
G03Y455507I-1652J582D01*
G01X694732Y455540D01*
Y455853D01*
X694642Y455943D01*
Y463764D01*
X695340Y464462D01*
Y479984D01*
X689224Y486100D01*
Y490076D01*
X688600Y490700D01*
Y496100D01*
X689078Y496578D01*
X689088Y496586D01*
G03X689219Y496700I-886J1150D01*
G01X694542D01*
X694572Y496536D01*
G03X697428I1428J264D01*
G01X697458Y496700D01*
X698400D01*
X700391Y494709D01*
Y443482D01*
X699850Y442941D01*
X695575D01*
G37*
G36*
G01X741580Y446835D02*
Y447868D01*
X745576D01*
X749628Y451920D01*
X760724D01*
X769990Y442654D01*
Y425590D01*
X761500Y417100D01*
Y409600D01*
X760300Y408400D01*
X750000D01*
X749990Y408410D01*
X747190D01*
X742600Y413000D01*
X732404D01*
X716760Y428644D01*
Y435823D01*
X717346Y436410D01*
X724554D01*
X724582Y436438D01*
X725569D01*
X726178Y437047D01*
Y444678D01*
X729368Y447868D01*
X738019D01*
X738370Y447517D01*
X738369Y447432D01*
G03X741039Y446295I1564J-31D01*
G01X741580Y446835D01*
G37*
G36*
G01X684100Y502900D02*
X683624Y503376D01*
Y504676D01*
X682200Y506100D01*
Y508400D01*
X682498Y508698D01*
X684552D01*
Y508800D01*
X685800D01*
X686500Y508100D01*
Y503600D01*
X685800Y502900D01*
X684100D01*
G37*
G36*
G01X666049Y524397D02*
X665654Y524792D01*
Y529789D01*
X666070Y530205D01*
Y547838D01*
X674982Y556750D01*
X686650D01*
X686998Y556402D01*
Y554748D01*
X687000D01*
Y553838D01*
X687320Y553518D01*
X692782D01*
X693000Y553300D01*
Y547750D01*
X693500Y547250D01*
X707500D01*
X708000Y546750D01*
Y538250D01*
X707500Y537750D01*
X691000D01*
X689500Y539250D01*
X685500D01*
X682750Y536500D01*
X676600D01*
X676575Y536475D01*
X673475D01*
X669770Y532770D01*
Y528632D01*
X669117Y527979D01*
Y524707D01*
X668807Y524397D01*
X666049D01*
G37*
G36*
G01X700816Y520550D02*
X700200Y521166D01*
Y523550D01*
X698000Y525750D01*
Y528750D01*
X698348Y529098D01*
X699215D01*
X699366Y529250D01*
X700500D01*
X701000Y528750D01*
Y525850D01*
X702800Y524050D01*
Y521150D01*
X702200Y520550D01*
X700816D01*
G37*
G36*
G01X680350Y510250D02*
X678864Y511736D01*
Y515230D01*
X686870D01*
X687400Y514700D01*
Y510900D01*
X686750Y510250D01*
X680350D01*
G37*
G36*
G01X671950Y530100D02*
X678110D01*
X679304Y528906D01*
Y524621D01*
X679198Y524515D01*
X673912D01*
X673886Y524541D01*
X672699D01*
X671620Y525620D01*
Y529770D01*
X671950Y530100D01*
G37*
G36*
G01X716342Y517545D02*
X712387Y521500D01*
X709500D01*
X705000Y526000D01*
X704050D01*
X704000Y526050D01*
Y529750D01*
X703500Y530250D01*
X700916D01*
X700915Y530252D01*
X700002D01*
Y536250D01*
X712100D01*
X712150Y536300D01*
X715398D01*
Y536298D01*
X717402D01*
Y536300D01*
X718800D01*
X719400Y536900D01*
Y539000D01*
X719498Y539098D01*
X724402D01*
Y539100D01*
X736000D01*
X737150Y537950D01*
Y534750D01*
X736600Y534200D01*
X730200D01*
X728508Y532508D01*
X726923D01*
X726921Y532506D01*
X726564D01*
X723500Y529442D01*
Y523768D01*
X722989Y523257D01*
Y517857D01*
X722677Y517545D01*
X716342D01*
G37*
G36*
G01X668099Y579994D02*
Y591991D01*
X668778Y592670D01*
X674580D01*
X675099Y592151D01*
Y585993D01*
X675100Y585485D01*
Y568994D01*
X674099Y567993D01*
X669000D01*
Y570799D01*
X668952Y570848D01*
Y570902D01*
X668898D01*
X668099Y571700D01*
Y576898D01*
X668100D01*
Y579994D01*
X668099D01*
G37*
G36*
G01X690700Y530300D02*
Y534500D01*
X690000Y535200D01*
X686800D01*
X686700Y535300D01*
Y536300D01*
X686800Y536400D01*
X698500D01*
X699000Y535900D01*
Y530300D01*
X698800Y530100D01*
X690900D01*
X690700Y530300D01*
G37*
G36*
G01X726128Y585528D02*
X725606Y586050D01*
X720780D01*
X720766Y586036D01*
X719064D01*
X719050Y586050D01*
X705650D01*
X705100Y586600D01*
Y592400D01*
X705750Y593050D01*
X716498D01*
Y593048D01*
X719608D01*
Y593050D01*
X728106D01*
X728606Y592550D01*
Y586034D01*
X728100Y585528D01*
X726128D01*
G37*
G36*
G01X713650Y537800D02*
X712652Y538798D01*
Y538818D01*
X712632D01*
X712200Y539250D01*
X709500D01*
X709002Y539748D01*
Y547165D01*
X709000Y547166D01*
Y547750D01*
X708500Y548250D01*
X707916D01*
X707915Y548252D01*
X694498D01*
X694002Y548748D01*
Y552302D01*
X696448Y554748D01*
X696502D01*
Y556752D01*
X696500D01*
Y557250D01*
X697500Y558250D01*
X726550D01*
X727200Y557600D01*
Y550900D01*
X725850Y549550D01*
Y542650D01*
X725300Y542100D01*
X724402D01*
Y542102D01*
X719302D01*
X718300Y541100D01*
Y538700D01*
X717402Y537802D01*
X715398D01*
Y537800D01*
X713650D01*
G37*
G36*
G01X721000Y602000D02*
X720685Y602315D01*
Y607501D01*
X720106Y608080D01*
Y610280D01*
X720400Y610574D01*
Y616040D01*
X720640Y616280D01*
X724500D01*
X725106Y615674D01*
Y603106D01*
X724064Y602064D01*
X723308D01*
X723243Y602000D01*
X721000D01*
G37*
G36*
G01X704909Y594209D02*
X704418Y594700D01*
Y597658D01*
X707614Y600854D01*
X712012D01*
X716498Y596368D01*
Y594298D01*
X716409Y594209D01*
X704909D01*
G37*
G36*
G01X717500Y594050D02*
Y597156D01*
X710606Y604050D01*
Y613324D01*
X713412Y616130D01*
X717260D01*
X717366Y616024D01*
Y609790D01*
X717570Y609586D01*
Y602586D01*
X717604Y602552D01*
Y602548D01*
X717608D01*
X718606Y601550D01*
Y594050D01*
X717500D01*
G37*
G36*
G01X728572Y594000D02*
X728521Y594052D01*
X723448D01*
X723300Y594200D01*
Y596400D01*
X723400Y596500D01*
X725880D01*
X727700Y598320D01*
X733320D01*
X735000Y600000D01*
Y614000D01*
X726500Y622500D01*
Y623500D01*
X727500Y624500D01*
X729000D01*
X737500Y616000D01*
Y599000D01*
X732500Y594000D01*
X728572D01*
G37*
G36*
G01X727036Y32263D02*
X726132Y33167D01*
Y40454D01*
Y45351D01*
X726339Y45557D01*
X736796D01*
X737827Y44526D01*
Y32914D01*
X737176Y32263D01*
X727036D01*
G37*
G36*
G01X726447Y61632D02*
X729500Y64685D01*
Y68739D01*
X730386Y69625D01*
X735101D01*
X735932Y68794D01*
Y58497D01*
X734939Y57504D01*
X726556D01*
X726447Y57613D01*
Y61632D01*
G37*
G36*
G01X758800Y194300D02*
X742800D01*
X741100Y196000D01*
Y209100D01*
X743000Y211000D01*
X758700D01*
X760400Y209300D01*
Y195900D01*
X758800Y194300D01*
G37*
G36*
G01X785000Y203000D02*
X782722Y205278D01*
Y208532D01*
X782734D01*
Y210534D01*
X782722D01*
Y211816D01*
X783172Y212266D01*
X784941D01*
X785800Y213125D01*
Y220000D01*
X785600Y220200D01*
X782500D01*
X782200Y219900D01*
Y217700D01*
X781800Y217300D01*
Y213800D01*
X781700Y213700D01*
X780804D01*
Y217445D01*
X780637Y217612D01*
X774506D01*
X774318Y217800D01*
X774300D01*
X774100Y218000D01*
Y224000D01*
X774700Y224600D01*
X783058D01*
X783500Y225042D01*
Y235943D01*
X783472Y235971D01*
Y238637D01*
X782486Y239622D01*
Y241624D01*
X782482D01*
Y242287D01*
X781395Y243374D01*
Y244663D01*
X781000Y245058D01*
Y245500D01*
X780898Y245602D01*
Y245811D01*
X780829Y245880D01*
Y249400D01*
X774600D01*
X774200Y249800D01*
Y256211D01*
X774572Y256583D01*
X782993D01*
X783500Y257090D01*
Y268447D01*
X783298Y268648D01*
X782200D01*
X782116Y268732D01*
Y270656D01*
X782000D01*
Y271904D01*
X782046D01*
Y273908D01*
X782000D01*
Y274600D01*
X781046Y275554D01*
Y276234D01*
X780910Y276370D01*
Y277805D01*
X780810Y277905D01*
Y281444D01*
X780644Y281610D01*
X776548D01*
X776519Y281581D01*
X775315D01*
X775259Y281637D01*
X774422D01*
X774206Y281853D01*
Y288446D01*
X774378Y288618D01*
X783028D01*
X783600Y289190D01*
Y300359D01*
X783229Y300730D01*
X782300D01*
Y306100D01*
X782288Y306112D01*
Y306174D01*
X782226D01*
X781288Y307112D01*
Y307836D01*
X780908Y308215D01*
Y309700D01*
X780792Y309816D01*
Y313422D01*
X780531Y313683D01*
X776600D01*
X776583Y313700D01*
X775368D01*
X775268Y313800D01*
X774600D01*
X774300Y314100D01*
Y319700D01*
X775100Y320500D01*
X782910D01*
X783600Y321190D01*
Y332591D01*
X783755Y332746D01*
Y333044D01*
X783766D01*
Y335048D01*
X783755D01*
Y335245D01*
X782756Y336244D01*
Y339246D01*
X781734Y340268D01*
Y340355D01*
X780994Y341095D01*
G03X780805Y341255I-1062J-1062D01*
G01Y345333D01*
X780460Y345678D01*
X775347D01*
X775225Y345800D01*
X774900D01*
X774600Y346100D01*
Y352000D01*
X775100Y352500D01*
X782910D01*
X783600Y353190D01*
Y363100D01*
X782532Y364168D01*
X782500D01*
X782209Y364459D01*
Y366959D01*
X782250Y367000D01*
X784200D01*
X785400Y365800D01*
X793100D01*
X793506Y366206D01*
X796902D01*
X797058Y366050D01*
X807962D01*
X808250Y366338D01*
X819157D01*
X819586Y365909D01*
Y211014D01*
X820248Y210352D01*
Y206377D01*
X820220Y206349D01*
X819280D01*
G03X819104Y206348I-80J-1449D01*
G01X816706D01*
X816654Y206401D01*
X816211D01*
X816154Y206452D01*
G03X813149Y205960I-1305J-1451D01*
G01X813136Y205937D01*
X812699Y205500D01*
X807300D01*
X805800Y204000D01*
X805100D01*
X804100Y205000D01*
X802400D01*
X800900Y203500D01*
X798900D01*
X798500Y203900D01*
X796800D01*
X796200Y203300D01*
X791800D01*
X791500Y203000D01*
X785000D01*
G37*
G36*
G01X765770Y237680D02*
X767070Y238980D01*
X781520D01*
X781848Y238652D01*
Y236358D01*
X782000Y236206D01*
Y235212D01*
X782012Y235200D01*
Y226107D01*
X781975Y226070D01*
X774241D01*
X774208Y226103D01*
Y231333D01*
X774071Y231470D01*
Y231516D01*
X773571Y232016D01*
X770000D01*
X768016Y234000D01*
X765980D01*
X765770Y234210D01*
Y237680D01*
G37*
G36*
G01X774215Y258070D02*
X774208Y258077D01*
Y263333D01*
X774071Y263470D01*
Y263516D01*
X773571Y264016D01*
X770300D01*
X768908Y265408D01*
X768892D01*
X768502Y265798D01*
Y265902D01*
X765778D01*
X765680Y266000D01*
Y266608D01*
X765734D01*
Y268612D01*
X765680D01*
Y269289D01*
X766076Y269684D01*
X766636D01*
Y270244D01*
X766790Y270399D01*
X771807D01*
X771828Y270223D01*
G03X774955Y270870I1591J192D01*
G02X775338Y271384I383J114D01*
G01X780491D01*
X780607Y271268D01*
Y268658D01*
X782012Y267253D01*
Y258077D01*
X782005Y258070D01*
X774215D01*
G37*
G36*
G01X742381Y330482D02*
X739950Y332913D01*
Y375056D01*
G02X740634Y375337I400J0D01*
G03X740274Y377026I1140J1126D01*
G02X739617Y376883I-375J140D01*
G01X731500Y385000D01*
Y407000D01*
X732500Y408000D01*
X745574D01*
X747374Y406200D01*
X778558D01*
X781906Y402853D01*
X781984Y402774D01*
Y400782D01*
X781994D01*
Y386102D01*
X781962Y386070D01*
X774384D01*
X774158Y386296D01*
Y391333D01*
X774021Y391470D01*
Y391516D01*
X773521Y392016D01*
X770194D01*
X767885Y394325D01*
Y394830D01*
X767810Y394905D01*
X765255D01*
X764302Y395858D01*
Y395922D01*
X762007Y398216D01*
Y398799D01*
X760903Y399903D01*
X759292D01*
X758192Y398803D01*
Y397193D01*
X760068Y395317D01*
Y394666D01*
X757200Y391798D01*
Y376122D01*
X755839Y374761D01*
Y373228D01*
X756698Y372369D01*
X761857D01*
X766710Y367516D01*
X779521D01*
X779716Y367321D01*
Y364371D01*
X780780Y363307D01*
X781914D01*
X782012Y363209D01*
Y354070D01*
X774208D01*
Y359333D01*
X774071Y359470D01*
Y359516D01*
X773571Y360016D01*
X769671D01*
X769117Y360570D01*
X769108D01*
X768808Y360870D01*
X768788D01*
X768319Y361339D01*
X765936D01*
X765742Y361533D01*
Y364152D01*
X765720Y364174D01*
X765291Y364602D01*
X759402D01*
X755500Y360700D01*
Y346644D01*
X757564Y344580D01*
Y336986D01*
X751060Y330482D01*
X742381D01*
G37*
G36*
G01X774256Y322070D02*
X774208Y322118D01*
Y327333D01*
X774071Y327470D01*
Y327516D01*
X773571Y328016D01*
X769671D01*
X769117Y328570D01*
X769108D01*
X768695Y328983D01*
X768140D01*
X768014Y329110D01*
X765754D01*
X765702Y329162D01*
Y332968D01*
X767189Y334455D01*
Y335105D01*
X767347Y335263D01*
X781737D01*
X781941Y335059D01*
Y331441D01*
X782012Y331370D01*
Y322132D01*
X781950Y322070D01*
X774256D01*
G37*
G36*
G01X774213Y290070D02*
X774208Y290075D01*
Y295379D01*
X773571Y296016D01*
X769671D01*
X769117Y296570D01*
X769108D01*
X768402Y297276D01*
Y297302D01*
X768376D01*
X768357Y297321D01*
X765966D01*
X765741Y297546D01*
Y300719D01*
X768020Y302998D01*
X770810D01*
X771342Y302466D01*
X777882D01*
X778414Y302998D01*
X780649D01*
X780697Y302950D01*
Y300698D01*
X781738Y299657D01*
Y299644D01*
X782012Y299370D01*
Y290085D01*
X781997Y290070D01*
X774213D01*
G37*
G36*
G01X786000Y366800D02*
X784200Y368600D01*
X782184D01*
Y370534D01*
X782100D01*
Y371669D01*
X781328Y372441D01*
X781313Y372488D01*
G03X781282Y372574I-1427J-466D01*
G01X781269Y372609D01*
Y373431D01*
X780757Y373943D01*
Y377343D01*
X780200Y377900D01*
X774700D01*
X774300Y378300D01*
Y383600D01*
X775100Y384400D01*
X782804D01*
X783500Y385096D01*
Y397508D01*
X783522D01*
Y399222D01*
X783568Y399268D01*
Y402330D01*
X784018Y402780D01*
X802420D01*
X806900Y398300D01*
X815000D01*
X818115Y395185D01*
Y394061D01*
X817998Y393945D01*
Y368500D01*
X817870Y368372D01*
X808057D01*
X807556Y368873D01*
Y373249D01*
X807907Y373600D01*
X812400D01*
X812404Y373604D01*
X813617D01*
X813812Y373798D01*
X814105D01*
X815420Y375113D01*
Y389292D01*
X813635Y391076D01*
Y394214D01*
X811785Y396064D01*
X793702D01*
X791998Y394361D01*
Y375202D01*
X792009Y375191D01*
X793539Y373662D01*
X794400D01*
X795000Y373062D01*
Y371400D01*
X794588Y370988D01*
X789188D01*
X788800Y370600D01*
Y367300D01*
X788300Y366800D01*
X786000D01*
G37*
G36*
G01X793600Y459100D02*
Y435600D01*
X792798Y434798D01*
X775698D01*
X774957Y435538D01*
Y459142D01*
X776615Y460800D01*
X791900D01*
X793600Y459100D01*
G37*
G36*
G01X726176Y517633D02*
X726000Y517809D01*
Y518198D01*
X726002D01*
Y523002D01*
X726000D01*
Y530476D01*
X726773Y531249D01*
X729749D01*
X731200Y532700D01*
X737000D01*
X738495Y531205D01*
Y526995D01*
X733000Y521500D01*
Y518721D01*
X731912Y517633D01*
X726176D01*
G37*
G36*
G01X742470Y474183D02*
Y502812D01*
X743358Y503700D01*
X748534D01*
X755266Y496968D01*
X762630D01*
X762663Y497000D01*
X793000D01*
X794500Y495500D01*
Y477200D01*
X789346Y472046D01*
X744607D01*
X742470Y474183D01*
G37*
G36*
G01X756046Y504055D02*
X755500Y504601D01*
Y508232D01*
X756504Y509236D01*
X757828D01*
X758047Y509455D01*
Y514557D01*
X755500Y517104D01*
Y524101D01*
G02X755922Y524500I400J0D01*
G03Y527400I78J1450D01*
G02X755500Y527799I-22J399D01*
G01Y535151D01*
G02X755922Y535550I400J0D01*
G03Y538450I78J1450D01*
G02X755500Y538849I-22J399D01*
G01Y539000D01*
X747986Y546514D01*
G02X748022Y547112I282J283D01*
G03X746400Y557552I-3729J4767D01*
G01Y565082D01*
G03Y576428I-2107J5673D01*
G01Y584006D01*
G03Y595352I-2107J5673D01*
G01Y602882D01*
G03Y614228I-2107J5673D01*
G01Y621500D01*
X746575Y621675D01*
X749325D01*
X749329Y621679D01*
X767077D01*
X767500Y621256D01*
Y619086D01*
G03X767080Y617610I2381J-1475D01*
G01Y613994D01*
G03X767500Y610621I2420J-1411D01*
G01Y592483D01*
G02X766992Y592098I-400J0D01*
G03X766599Y589248I-392J-1398D01*
G02X766998Y588848I-1J-400D01*
G01Y588686D01*
G02X766690Y588518I-200J0D01*
G03X764476Y587018I-790J-1218D01*
G02X763947Y586564I-393J-78D01*
G03X764874Y585482I-497J-1364D01*
G02X765403Y585936I393J78D01*
G03X766218Y585883I498J1364D01*
G02X766704Y585519I87J-390D01*
G03X767500Y583738I2796J181D01*
G01Y581286D01*
G03X767080Y579810I2381J-1475D01*
G01Y576111D01*
G03X767500Y572738I2420J-1411D01*
G01Y553254D01*
G03X766798Y551400I2100J-1855D01*
G01Y548642D01*
X766792Y548617D01*
G03X767500Y545938I2708J-717D01*
G01Y543486D01*
G03X767080Y542010I2381J-1475D01*
G01Y538394D01*
G03X767500Y535021I2420J-1411D01*
G01Y514245D01*
G03X767098Y512800I2400J-1446D01*
G01Y511544D01*
X767072Y511497D01*
G03X767500Y508138I2428J-1397D01*
G01Y504744D01*
X766811Y504055D01*
X756046D01*
G37*
G36*
G01X736300Y541800D02*
G02X736600Y541500I0J-300D01*
G02X736300Y541200I-300J0D01*
G02X736000Y541500I0J300D01*
G02X736300Y541800I300J0D01*
G37*
G36*
G01X727000Y548600D02*
X728300Y549900D01*
Y557591D01*
X728959Y558250D01*
X731540D01*
X733300Y556490D01*
Y543100D01*
X732400Y542200D01*
X727100D01*
X727000Y542300D01*
Y548600D01*
G37*
G36*
G01X1079631Y252797D02*
G02X1079231Y253209I0J400D01*
G03X1076674Y252463I-1399J40D01*
G02X1076343Y251838I-331J-225D01*
G01X1075873D01*
X1075751Y252049D01*
G03X1073427Y252393I-1299J-753D01*
G02X1073159Y252388I-137J146D01*
G03X1073152Y252394I-948J-1099D01*
G03X1072581Y252698I-951J-1098D01*
G02X1072438Y252935I52J193D01*
G03X1070103Y254258I-1366J311D01*
G03X1070434Y251999I969J-1012D01*
G03X1070663Y251907I635J1249D01*
G02X1070798Y251665I-59J-191D01*
G03X1070750Y251259I1404J-372D01*
G02X1070351Y250849I-400J-10D01*
G01X1069492D01*
G02X1069093Y251251I1J400D01*
G01Y251271D01*
G03X1069087Y251429I-1401J26D01*
G03X1069059Y251603I-1395J-135D01*
G03X1066343Y251675I-1367J-303D01*
G03X1066553Y250474I1349J-383D01*
G02X1066229Y249841I-325J-233D01*
G01X1053235D01*
G02X1053035Y250043I0J200D01*
G03X1051534Y251561I-1501J17D01*
G01X1049953D01*
G02X1049553Y251972I0J400D01*
G03X1047650Y250705I-1399J39D01*
G01X1047705Y250683D01*
X1047843Y250491D01*
X1047822Y250403D01*
G03X1047783Y250043I1462J-341D01*
G02X1047583Y249841I-200J-2D01*
G01X1046475D01*
G02X1046275Y250043I0J200D01*
G03X1044774Y251561I-1501J17D01*
G01X1043193D01*
G02X1042793Y251972I0J400D01*
G03X1040890Y250705I-1399J39D01*
G01X1040945Y250683D01*
X1041083Y250491D01*
X1041062Y250403D01*
G03X1041023Y250043I1462J-341D01*
G02X1040823Y249841I-200J-2D01*
G01X1039716D01*
G02X1039516Y250043I0J200D01*
G03X1038015Y251561I-1501J17D01*
G01X1036433D01*
G02X1036033Y251972I0J400D01*
G03X1034129Y250705I-1399J39D01*
G01X1034185Y250683D01*
X1034324Y250490D01*
X1034303Y250402D01*
G03X1034264Y250043I1462J-340D01*
G02X1034064Y249841I-200J-2D01*
G01X1032956D01*
G02X1032756Y250043I0J200D01*
G03X1031255Y251561I-1501J17D01*
G01X1029005D01*
G03X1027504Y250043I0J-1501D01*
G02X1027304Y249841I-200J-2D01*
G01X1026196D01*
G02X1025996Y250043I0J200D01*
G03X1024495Y251561I-1501J17D01*
G01X1023016D01*
G02X1022616Y251971I0J400D01*
G03X1021115Y253511I-1501J39D01*
G01X1019635D01*
G02X1019236Y253921I1J400D01*
G03X1017735Y255461I-1501J39D01*
G01X1016256D01*
G02X1015856Y255871I0J400D01*
G03X1014355Y257411I-1501J39D01*
G01X1012875D01*
G02X1012476Y257821I1J400D01*
G03X1010975Y259361I-1501J39D01*
G01X1009496D01*
G02X1009096Y259771I0J400D01*
G03X1007595Y261311I-1501J39D01*
G01X1006115D01*
G02X1005716Y261721I1J400D01*
G03X1004215Y263261I-1501J39D01*
G01X1002737D01*
G02X1002337Y263671I0J400D01*
G03X1000836Y265211I-1501J39D01*
G01X999386D01*
X998959Y265638D01*
X998956Y265716D01*
G03X997602Y267154I-1500J-56D01*
G02X997422Y267353I20J199D01*
G01Y267867D01*
G02X997602Y268066I200J0D01*
G03Y271054I-146J1494D01*
G02X997422Y271253I20J199D01*
G01Y271767D01*
G02X997602Y271966I200J0D01*
G03X997456Y274961I-146J1494D01*
G01X996136D01*
X995575Y275522D01*
X995576Y275524D01*
X995397Y275703D01*
X995383Y275755D01*
G03X994422Y276716I-1307J-346D01*
G01X994370Y276730D01*
X994256Y276844D01*
Y277961D01*
X994407Y277999D01*
G03Y280621I-331J1311D01*
G01X994256Y280659D01*
Y281709D01*
X994411Y281745D01*
G03X994076Y284711I-335J1464D01*
G01X991826D01*
G03X990343Y283447I0J-1502D01*
G01X988799D01*
G03X987316Y284711I-1483J-238D01*
G01X985066D01*
G03X983583Y283447I0J-1502D01*
G01X982039D01*
G03X980556Y284711I-1483J-238D01*
G01X978306D01*
G03X976823Y283447I0J-1502D01*
G01X975279D01*
G03X973796Y284711I-1483J-238D01*
G01X971546D01*
G03X970063Y283447I0J-1502D01*
G01X968519D01*
G03X967036Y284711I-1483J-238D01*
G01X965556D01*
G02X965157Y285121I1J400D01*
G03X963656Y286661I-1501J39D01*
G01X961406D01*
G03Y283659I0J-1501D01*
G01X962885D01*
G02X963285Y283248I0J-400D01*
G03X964786Y281707I1501J-39D01*
G01X965051D01*
G02X965334Y281025I0J-400D01*
G01X965120Y280811D01*
X964786D01*
G03X963299Y279102I0J-1501D01*
G01X963313Y279004D01*
X963170Y278861D01*
X961404D01*
G03X960269Y278341I1J-1501D01*
G01X958034D01*
G03X956899Y278861I-1136J-981D01*
G01X954645D01*
G03X953510Y278341I1J-1501D01*
G01X951274D01*
G03X950139Y278861I-1136J-981D01*
G01X947885D01*
G03X946750Y278341I1J-1501D01*
G01X944514D01*
G03X943379Y278861I-1136J-981D01*
G01X941125D01*
G03X939990Y278341I1J-1501D01*
G01X937754D01*
G03X936619Y278861I-1136J-981D01*
G01X934365D01*
G03X933230Y278341I1J-1501D01*
G01X932733D01*
X931973Y277581D01*
G02X931305Y277758I-282J283D01*
G03X929857Y278861I-1448J-399D01*
G01X927607D01*
G03X926106Y277321I0J-1501D01*
G02X925707Y276911I-400J-10D01*
G01X924227D01*
G03X922726Y275371I0J-1501D01*
G02X922326Y274962I-400J-9D01*
G01X921371Y274961D01*
G02X920971Y275372I0J400D01*
G03X920904Y275812I-1249J35D01*
G03X919927Y276638I-1181J-406D01*
G03X919815Y276610I-13J-186D01*
G03X919789Y276592I155J-251D01*
G03X919723Y276487I125J-152D01*
G03X919717Y276453I256J-63D01*
G03X919716Y276422I263J-24D01*
G01Y276292D01*
X919715Y276285D01*
G03Y276270I180J-7D01*
G03X919716Y276254I179J3D01*
G01X919784D01*
X919804Y276253D01*
X919834Y276247D01*
X919836Y276246D01*
G03X919851Y276245I12J71D01*
G02X920002Y276205I-153J-883D01*
G02X920190Y276112I-323J-889D01*
G02X920368Y275953I-591J-840D01*
G02X920480Y275778I-654J-542D01*
G02X920557Y275533I-958J-436D01*
G02X920567Y275401I-1651J-191D01*
G02X920546Y275219I-632J-19D01*
G02X920454Y274985I-944J236D01*
G03X920432Y274956I712J-563D01*
G03X920387Y274889I731J-539D01*
G03X919831Y274566I459J-1430D01*
G02X919715Y274557I-126J876D01*
G02X919360Y274341I-355J184D01*
G01X917553D01*
G03X916338Y274961I-1215J-881D01*
G01X913785D01*
G03X913232Y274855I1J-1501D01*
G01X913196Y274841D01*
X911956D01*
X908526Y271412D01*
X908493D01*
X863080Y225998D01*
X863045Y225983D01*
G03X862017Y224955I805J-1833D01*
G01X862002Y224920D01*
X841674Y204592D01*
X823508D01*
X822250Y205850D01*
Y206368D01*
X822252D01*
Y209372D01*
X822250D01*
Y209950D01*
X820608Y211592D01*
Y363351D01*
X821712Y364455D01*
X838145D01*
X840598Y362002D01*
Y361985D01*
X842085Y360498D01*
X848115D01*
X848316Y360700D01*
X888185D01*
X912449Y336436D01*
X912410Y336319D01*
G03X914246Y334483I1377J-459D01*
G01X914363Y334522D01*
X915253Y333632D01*
G02X915214Y333032I-283J-283D01*
G03X915119Y332952I822J-1073D01*
G02X914839Y332961I-135J147D01*
G03Y330959I-1052J-1001D01*
G02X915119Y330968I145J-138D01*
G03X915724Y330645I918J992D01*
G02X916028Y330203I-92J-389D01*
G03Y329817I1439J-193D01*
G02X915724Y329375I-396J-53D01*
G03X915182Y329107I313J-1315D01*
G01X915127Y329062D01*
X914841D01*
X914784Y329116D01*
G03Y327004I-997J-1056D01*
G01X914841Y327058D01*
X915127D01*
X915182Y327013D01*
G03X916037Y326708I855J1046D01*
G01X916337D01*
G03X917655Y328358I0J1351D01*
G02X917804Y328597I195J44D01*
G03X918464Y328953I-336J1413D01*
G01X918521Y329008D01*
X918806D01*
X918861Y328962D01*
G03X919321Y328716I856J1047D01*
G02X919454Y328469I-59J-191D01*
G03X919682Y327193I1393J-409D01*
G01X919722Y327140D01*
Y326994D01*
X919721Y326988D01*
G03X919722Y326957I179J-10D01*
G01X919770Y326956D01*
X919810Y326954D01*
X919837Y326949D01*
X919844Y326947D01*
G03X919856Y326946I12J71D01*
G02X919939Y326927I-158J-882D01*
G03X920326Y326705I907J1133D01*
G02X920374Y326654I-724J-729D01*
G02X920486Y326479I-654J-542D01*
G02X920563Y326234I-959J-436D01*
G02X920572Y326102I-1653J-179D01*
G02X920552Y325920I-632J-23D01*
G02X920460Y325686I-945J236D01*
G03X920391Y325586I711J-564D01*
G02X920292Y325480I-2368J2112D01*
G02X920230Y325428I-669J735D01*
G02X920060Y325328I-445J562D01*
G01X920003Y325307D01*
G02X919826Y325265I-250J660D01*
G02X919721Y325258I-111J879D01*
G02X919722Y325200I-438J-37D01*
G03X919721Y325109I1067J-57D01*
G01X919722Y325105D01*
Y325061D01*
X919721D01*
X919724Y325048D01*
G03X919730Y325022I178J27D01*
G01X919736Y325003D01*
X919739Y324995D01*
X919752Y324969D01*
X919757Y324963D01*
X919764Y324953D01*
G03X919767Y324949I15J8D01*
G03X919788Y324928I134J113D01*
G03X919800Y324918I64J65D01*
G03X919830Y324897I83J86D01*
G01X919854Y324887D01*
G03X919870Y324883I52J172D01*
G03X919888Y324877I63J158D01*
G01X919925Y324874D01*
G03X920969Y326240I-198J1233D01*
G02X921254Y326666I398J42D01*
G03X921731Y326908I-407J1394D01*
G01X921870Y327015D01*
X922326Y326559D01*
G02X922726Y326148I0J-400D01*
G03X924227Y324609I1501J-38D01*
G01X925756D01*
G02X926155Y324198I-1J-400D01*
G03Y324159I1452J-20D01*
G03X926156Y324104I1452J-1D01*
G02X925756Y323711I-400J7D01*
G01X924227D01*
G03Y320707I0J-1502D01*
G01X925707D01*
G02X926106Y320298I-1J-400D01*
G03X927607Y318759I1501J-38D01*
G01X929086D01*
G02X929486Y318348I0J-400D01*
G03Y318271I1501J-39D01*
G02X929086Y317862I-400J-9D01*
G01X927607Y317861D01*
G03Y314859I0J-1501D01*
G01X929857D01*
G03X931343Y316578I0J1502D01*
G01X931341Y316592D01*
Y316807D01*
X931790D01*
X932756Y315841D01*
X932952D01*
X933006Y315726D01*
G03X934367Y314859I1361J635D01*
G01X936617D01*
G03X937978Y315726I0J1502D01*
G01X938032Y315841D01*
X939712D01*
X939766Y315726D01*
G03X941127Y314859I1361J635D01*
G01X943377D01*
G03X944738Y315726I0J1502D01*
G01X944792Y315841D01*
X946472D01*
X946526Y315726D01*
G03X947887Y314859I1361J635D01*
G01X950137D01*
G03X951498Y315726I0J1502D01*
G01X951552Y315841D01*
X953232D01*
X953286Y315726D01*
G03X954647Y314859I1361J635D01*
G01X956897D01*
G03X958258Y315726I0J1502D01*
G01X958312Y315841D01*
X959991D01*
X960045Y315726D01*
G03X961406Y314859I1361J635D01*
G01X962885D01*
G02X963285Y314448I0J-400D01*
G03X964786Y312907I1501J-39D01*
G01X966266D01*
G02X966665Y312498I-1J-400D01*
G03Y312421I1501J-39D01*
G02X966266Y312011I-400J-10D01*
G01X964786D01*
G03X963285Y310471I0J-1501D01*
G02X962885Y310061I-400J-10D01*
G01X961406D01*
G03Y307059I0J-1501D01*
G01X963656D01*
G03X965157Y308598I0J1501D01*
G02X965557Y309008I400J10D01*
G01X967036Y309007D01*
G03X968537Y310548I0J1502D01*
G02X968937Y310959I400J11D01*
G01X969645D01*
G02X970045Y310548I0J-400D01*
G03X971546Y309007I1501J-39D01*
G01X973796D01*
G03X975297Y310548I0J1502D01*
G02X975697Y310959I400J11D01*
G01X976405D01*
G02X976805Y310548I0J-400D01*
G03X978306Y309007I1501J-39D01*
G01X980556D01*
G03X982057Y310548I0J1502D01*
G02X982457Y310959I400J11D01*
G01X983165D01*
G02X983565Y310548I0J-400D01*
G03X985066Y309007I1501J-39D01*
G01X987316D01*
G03X988817Y310548I0J1502D01*
G02X989217Y310959I400J11D01*
G01X989925D01*
G02X990325Y310548I0J-400D01*
G03X991826Y309007I1501J-39D01*
G01X994076D01*
G03Y312011I0J1502D01*
G01X992596D01*
G02X992197Y312421I1J400D01*
G03Y312498I-1501J38D01*
G02X992597Y312908I400J10D01*
G01X994076Y312907D01*
G03Y315911I0J1502D01*
G01X993910D01*
G02X993627Y316593I0J400D01*
G01X993842Y316807D01*
X994076D01*
G03X995407Y317614I0J1501D01*
G01X996438D01*
X996986Y318162D01*
Y318759D01*
X997456D01*
G03Y321761I0J1501D01*
G01X996986D01*
Y322659D01*
X997456D01*
G03Y325661I0J1501D01*
G01X996986D01*
Y326559D01*
X997456D01*
G03Y329561I0J1501D01*
G01X996986D01*
Y330459D01*
X997456D01*
G03X998957Y331998I0J1501D01*
G02X999357Y332408I400J10D01*
G01X1000836Y332407D01*
G03X1002337Y333948I0J1502D01*
G02X1002737Y334359I400J11D01*
G01X1004215D01*
G03X1005716Y335898I0J1501D01*
G02X1006116Y336308I400J10D01*
G01X1007595Y336307D01*
G03X1009096Y337848I0J1502D01*
G02X1009496Y338259I400J11D01*
G01X1010975D01*
G03X1012476Y339798I0J1501D01*
G02X1012876Y340208I400J10D01*
G01X1014355Y340207D01*
G03X1015856Y341748I0J1502D01*
G02X1016256Y342159I400J11D01*
G01X1017735D01*
G03X1019236Y343698I0J1501D01*
G02X1019636Y344108I400J10D01*
G01X1021115Y344107D01*
G03X1022616Y345648I0J1502D01*
G02X1023016Y346059I400J11D01*
G01X1023724D01*
G02X1024124Y345648I0J-400D01*
G03X1025625Y344107I1501J-39D01*
G01X1027875D01*
G03X1029376Y345648I0J1502D01*
G02X1029776Y346059I400J11D01*
G01X1031255D01*
G03X1032756Y347598I0J1501D01*
G02X1033156Y348008I400J10D01*
G01X1034635Y348007D01*
G03X1036130Y349373I0J1501D01*
G01X1036716Y349959D01*
X1038015D01*
G03X1039495Y351209I0J1501D01*
G01X1039523Y351375D01*
X1041016D01*
X1041044Y351208D01*
G03X1041072Y351076I1481J245D01*
G02X1040943Y350836I-193J-51D01*
G03X1042794Y349548I451J-1325D01*
G02X1043193Y349959I400J11D01*
G01X1044774D01*
G03X1046254Y351209I0J1501D01*
G01X1046282Y351375D01*
X1047776D01*
X1047804Y351208D01*
G03X1047832Y351076I1481J245D01*
G02X1047703Y350836I-193J-51D01*
G03X1049554Y349548I451J-1325D01*
G02X1049953Y349959I400J11D01*
G01X1051534D01*
G03X1053014Y351209I0J1501D01*
G01X1053042Y351375D01*
X1053703D01*
G02X1053969Y350677I0J-400D01*
G03X1053412Y349509I946J-1168D01*
G01Y347108D01*
G03X1053602Y346377I1502J0D01*
G03X1056226I1312J623D01*
G03X1056416Y347108I-1312J731D01*
G01Y349509D01*
G03X1055859Y350677I-1503J0D01*
G02X1056125Y351375I266J298D01*
G01X1056785D01*
X1056806Y351252D01*
G03X1058346Y349959I1488J208D01*
G01X1060694D01*
G03X1061787Y350431I0J1502D01*
G01X1062313D01*
X1064224Y352341D01*
X1068559D01*
X1069400Y351500D01*
X1069770D01*
Y351264D01*
X1069757Y351231D01*
G03X1071037Y349346I1315J-484D01*
G03X1072446Y351022I35J1401D01*
G02X1072838Y351500I392J78D01*
G01X1073820D01*
X1073861Y351480D01*
G03X1075043I591J1216D01*
G01X1075084Y351500D01*
X1075879D01*
G03X1077525I823J1196D01*
G01X1080580D01*
X1080621Y351480D01*
G03X1081803I591J1216D01*
G01X1081844Y351500D01*
X1082639D01*
G03X1084285I823J1196D01*
G01X1087339D01*
X1087380Y351480D01*
G03X1088562I591J1216D01*
G01X1088603Y351500D01*
X1089398D01*
G03X1089613Y351377I826J1194D01*
G03X1089884Y351283I609J1318D01*
G02X1090032Y351045I-47J-194D01*
G03X1090087Y350268I1319J-297D01*
G01X1090100Y350234D01*
Y349233D01*
G03X1092602I1251J-736D01*
G01Y350234D01*
X1092615Y350268D01*
G03X1092675Y351019I-1264J479D01*
G02X1093067Y351500I392J81D01*
G01X1094099D01*
X1094140Y351480D01*
G03X1095322I591J1216D01*
G01X1095363Y351500D01*
X1096158D01*
G03X1096373Y351377I826J1194D01*
G03X1096644Y351283I609J1318D01*
G02X1096792Y351045I-47J-194D01*
G03X1098967Y349700I1319J-298D01*
G01X1099022Y349746D01*
X1099307D01*
X1099364Y349691D01*
G03X1099566Y349532I996J1057D01*
G03X1100024Y349334I797J1214D01*
G02X1100173Y349096I-46J-195D01*
G03X1102347Y347749I1318J-300D01*
G01X1102402Y347794D01*
X1102686D01*
X1102744Y347740D01*
G03X1103181Y347456I997J1056D01*
G01X1103217Y347441D01*
X1103358Y347300D01*
Y339742D01*
X1089001D01*
X1086500Y337241D01*
Y336140D01*
X1082520Y332160D01*
X1079290D01*
X1078690Y332760D01*
Y336420D01*
X1079023Y336753D01*
X1081211D01*
X1082037Y337579D01*
Y340340D01*
X1081377Y341000D01*
X1075934D01*
Y341746D01*
G02X1076356Y342145I400J0D01*
G03X1075012Y343308I79J1450D01*
G01X1075033Y343203D01*
X1074506Y342676D01*
Y341000D01*
X1073016D01*
X1073015Y341002D01*
X1054318D01*
X1053750Y340434D01*
X1037932D01*
X1037842Y340343D01*
X1037841D01*
X1037840Y340341D01*
X1036756D01*
X1031506Y335091D01*
X1028256D01*
X1026506Y333341D01*
Y333300D01*
X1022547Y329341D01*
X1016756D01*
X1013256Y325841D01*
Y313257D01*
X1013254Y313256D01*
Y310926D01*
X1013256Y310925D01*
Y310841D01*
X1013756Y310341D01*
X1013840D01*
X1014341Y309839D01*
X1016171D01*
X1016665Y310333D01*
X1029258D01*
Y310843D01*
X1029606Y311191D01*
Y311432D01*
X1029629Y311475D01*
G03X1029606Y313377I-1773J930D01*
G01Y315100D01*
X1058009D01*
Y303942D01*
X1036960D01*
Y303906D01*
X1034666D01*
Y303847D01*
X1032770D01*
Y303906D01*
X1029766D01*
Y303847D01*
X1027870D01*
Y303906D01*
X1024866D01*
Y303847D01*
X1022970D01*
Y303906D01*
X1019966D01*
Y303847D01*
X1018070D01*
Y303906D01*
X1015066D01*
Y302943D01*
X1013754D01*
Y293845D01*
X1015095D01*
Y293844D01*
X1037551D01*
X1037561Y293857D01*
X1057500D01*
Y287235D01*
X1057200Y286935D01*
X1036992D01*
X1036945Y286982D01*
X1016032D01*
X1015956Y286906D01*
X1015066D01*
Y286117D01*
X1013754D01*
Y279042D01*
X1016219Y276577D01*
X1026900D01*
X1027970Y275507D01*
Y268100D01*
X1029623Y266447D01*
X1037400D01*
X1038076Y265771D01*
Y263500D01*
X1038941Y262635D01*
X1039449D01*
Y262634D01*
X1082855D01*
X1083310Y263089D01*
Y263280D01*
G03X1083360Y265925I-878J1340D01*
G01Y267756D01*
X1083202Y267914D01*
Y268835D01*
X1084055D01*
X1086786Y266104D01*
Y265704D01*
X1087678Y264811D01*
X1087664Y264712D01*
G03X1090083Y263431I1436J-212D01*
G03X1090276Y263648I-983J1069D01*
G02X1090924I324J-235D01*
G03X1092088Y263048I1176J852D01*
G03X1093167Y265485I12J1452D01*
G02X1093210Y266068I294J271D01*
G03X1093542Y266449I-912J1130D01*
G03X1093642Y266646I-1241J754D01*
G01X1093657Y266683D01*
X1093827Y266852D01*
X1094318Y266361D01*
X1094291Y266251D01*
G03X1096250Y264556I1409J-351D01*
G03X1097124Y266187I-550J1344D01*
G01X1097102Y266292D01*
X1098126Y267315D01*
Y268835D01*
X1106071D01*
X1106133Y268773D01*
G03X1106560Y267987I1427J266D01*
G01Y267171D01*
X1106705Y267026D01*
Y264369D01*
X1106474D01*
X1106444Y264379D01*
G03X1106381Y264398I-451J-1381D01*
G02X1106238Y264635I52J193D01*
G03X1104461Y263606I-1367J311D01*
G02X1104596Y263364I-58J-191D01*
G03X1104576Y262715I1405J-368D01*
G02X1104438Y262485I-196J-39D01*
G03X1103845Y262144I432J-1438D01*
G02X1103577Y262140I-136J146D01*
G03X1103000Y262449I-956J-1093D01*
G02X1102858Y262686I53J193D01*
G03X1100805Y264218I-1367J310D01*
G03X1101081Y261656I686J-1222D01*
G02X1101216Y261414I-58J-191D01*
G03X1101178Y260888I1405J-366D01*
G03X1101197Y260764I1443J158D01*
G02X1101058Y260533I-196J-39D01*
G03X1100466Y260193I432J-1438D01*
G02X1100198Y260188I-137J146D01*
G03X1099621Y260498I-958J-1091D01*
G02X1099478Y260735I52J193D01*
G03X1097402Y262255I-1366J312D01*
G03X1097701Y259706I709J-1209D01*
G02X1097836Y259464I-58J-191D01*
G03X1097816Y258814I1405J-369D01*
G02X1097678Y258584I-196J-39D01*
G03X1097086Y258244I432J-1438D01*
G02X1096818Y258239I-137J146D01*
G03X1096763Y258285I-959J-1090D01*
G03X1096240Y258549I-902J-1138D01*
G02X1096098Y258786I53J193D01*
G03X1094115Y260355I-1367J310D01*
G03X1094321Y257756I616J-1259D01*
G02X1094456Y257514I-58J-191D01*
G03X1094414Y257264I1405J-365D01*
G03X1094409Y257108I1447J-124D01*
G02X1094010Y256697I-400J-11D01*
G01X1093153D01*
G02X1092753Y257108I0J400D01*
G03X1092513Y257932I-1402J39D01*
G03X1090798Y258435I-1161J-783D01*
G03X1090332Y258110I552J-1289D01*
G03X1090846Y255839I1019J-963D01*
G01X1090901Y255817D01*
X1091039Y255626D01*
X1091019Y255537D01*
G03X1090980Y255158I1462J-342D01*
G02X1090581Y254749I-400J-9D01*
G01X1089771D01*
G02X1089372Y255133I1J400D01*
G03X1089269Y255728I-1401J64D01*
G03X1088986Y256164I-1297J-532D01*
G03X1087195Y256364I-1014J-965D01*
G03X1087466Y253888I776J-1168D01*
G01X1087521Y253866D01*
X1087659Y253676D01*
X1087639Y253587D01*
G03X1087600Y253208I1462J-342D01*
G02X1087200Y252797I-400J-11D01*
G01X1086391D01*
G02X1085991Y253209I0J400D01*
G03X1083434Y252463I-1399J40D01*
G02X1083103Y251838I-331J-225D01*
G01X1082618D01*
X1082563Y251951D01*
G03X1081212Y252797I-1351J-656D01*
G01X1079631D01*
G37*
G36*
G01X847700Y361500D02*
X842500D01*
X841600Y362400D01*
Y367000D01*
X842400Y367800D01*
X847200D01*
X848600Y366400D01*
Y362400D01*
X847700Y361500D01*
G37*
G36*
G01X821300Y365900D02*
X819000Y368200D01*
Y393530D01*
X820770Y395300D01*
X828200D01*
X834046Y389454D01*
X850236D01*
X852590Y387100D01*
Y367254D01*
X852176Y366840D01*
X849803D01*
X847402Y369242D01*
Y370052D01*
X846592D01*
X846343Y370300D01*
X842700D01*
X838300Y365900D01*
X821300D01*
G37*
G36*
G01X812600Y393800D02*
Y390695D01*
X814418Y388877D01*
Y375528D01*
X813690Y374800D01*
X794100D01*
X793200Y375700D01*
Y393863D01*
X794200Y394863D01*
X811537D01*
X812600Y393800D01*
G37*
G36*
G01X909574Y187391D02*
X909624Y188141D01*
X910024D01*
X910074Y187391D01*
Y187191D01*
X909574D01*
Y187391D01*
G37*
G36*
G01X908774Y190091D02*
X908724Y189341D01*
X908324D01*
X908274Y190091D01*
Y190341D01*
X908774D01*
Y190091D01*
G37*
G36*
G01X906174D02*
X906124Y189341D01*
X905724D01*
X905674Y190091D01*
Y190341D01*
X906174D01*
Y190091D01*
G37*
G36*
G01X909574Y188941D02*
X909624Y189691D01*
X910024D01*
X910074Y188941D01*
Y188741D01*
X909574D01*
Y188941D01*
G37*
G36*
G01X908774Y188541D02*
X908724Y187791D01*
X908324D01*
X908274Y188541D01*
Y188741D01*
X908774D01*
Y188541D01*
G37*
G36*
G01X906974Y188941D02*
X907024Y189691D01*
X907424D01*
X907474Y188941D01*
Y188741D01*
X906974D01*
Y188941D01*
G37*
G36*
G01X949974Y7640D02*
X949601Y8013D01*
Y13823D01*
X952123Y16345D01*
Y18419D01*
X952702Y18998D01*
Y26302D01*
X953000Y26600D01*
X954800D01*
X955200Y26200D01*
Y19407D01*
X955752Y18855D01*
X956146D01*
G02X956398Y18145I0J-400D01*
G03X957793Y15751I884J-1088D01*
G02X958339Y15379I146J-372D01*
G01Y8379D01*
X957600Y7640D01*
X949974D01*
G37*
G36*
G01X965758Y-1300D02*
Y-4536D01*
G03X968886I1564J0D01*
G01X968887Y-1300D01*
X972688D01*
Y-3830D01*
X972668Y-3872D01*
G03X975362I1347J-664D01*
G01X975342Y-3830D01*
Y-1300D01*
X975877D01*
Y-1514D01*
X975875Y-1529D01*
G03X978864Y-1709I1487J-214D01*
G02X979263Y-1300I400J9D01*
G01X982154D01*
G02X982553Y-1709I-1J-400D01*
G03X985542Y-1529I1502J-34D01*
G01X985540Y-1514D01*
Y-1300D01*
X986074D01*
Y-3830D01*
X986054Y-3872D01*
G03X988748I1347J-664D01*
G01X988728Y-3830D01*
Y-1300D01*
X992768D01*
Y-3830D01*
X992747Y-3872D01*
G03X995441I1347J-664D01*
G01X995420Y-3830D01*
Y-1300D01*
X995956D01*
Y-1514D01*
X995954Y-1529D01*
G03X998943Y-1709I1487J-214D01*
G02X999342Y-1300I400J9D01*
G01X1002231D01*
G02X1002631Y-1709I0J-400D01*
G03X1005635I1502J-33D01*
G02X1006035Y-1300I400J9D01*
G01X1008931D01*
G02X1009329Y-1733I-1J-400D01*
G03X1012148Y-2572I1497J-126D01*
G02X1012851I352J-190D01*
G03X1015670Y-1733I1322J713D01*
G02X1016068Y-1300I399J33D01*
G01X1017600D01*
X1018400Y-2100D01*
Y-9600D01*
X1017500Y-10500D01*
X1016049D01*
G02X1015654Y-10034I0J400D01*
G03X1012851Y-9072I-1481J248D01*
G02X1012148I-352J190D01*
G03X1009345Y-10034I-1322J-714D01*
G02X1008950Y-10500I-395J-66D01*
G01X1005460D01*
Y-7814D01*
X1005481Y-7772D01*
G03X1002787I-1347J664D01*
G01X1002808Y-7814D01*
Y-10500D01*
X1002242D01*
Y-10276D01*
X1002247Y-10253D01*
G03X999293Y-10058I-1460J352D01*
G02X998895Y-10500I-398J-42D01*
G01X995970D01*
G02X995575Y-10034I0J400D01*
G03X992662Y-10240I-1481J248D01*
G01X992671Y-10269D01*
Y-10500D01*
X992074D01*
Y-7814D01*
X992095Y-7772D01*
G03X989401I-1347J664D01*
G01X989422Y-7814D01*
Y-10500D01*
X985382D01*
Y-7814D01*
X985402Y-7772D01*
G03X982708I-1347J664D01*
G01X982728Y-7814D01*
Y-10500D01*
X982131D01*
Y-10269D01*
X982140Y-10240D01*
G03X979227Y-10034I-1432J454D01*
G02X978832Y-10500I-395J-66D01*
G01X975907D01*
G02X975509Y-10058I0J400D01*
G03X972555Y-10253I-1494J157D01*
G01X972560Y-10276D01*
Y-10500D01*
X971996D01*
Y-7814D01*
X972016Y-7772D01*
G03X969322I-1347J664D01*
G01X969342Y-7814D01*
Y-10500D01*
X965302D01*
Y-7814D01*
X965323Y-7772D01*
G03X962629I-1347J664D01*
G01X962650Y-7814D01*
Y-10500D01*
X959500D01*
Y-6293D01*
G02X960053Y-5923I400J0D01*
G03X961976Y-3872I576J1387D01*
G01X961956Y-3830D01*
Y-2144D01*
X962800Y-1300D01*
X965758D01*
G37*
G36*
G01Y36500D02*
Y35958D01*
G03X968886Y35956I1564J-1D01*
G01X968887Y35957D01*
Y36500D01*
X972219D01*
G02X972617Y36068I-1J-400D01*
G03X975384Y36257I1398J-111D01*
G01X975380Y36278D01*
Y36500D01*
X975997D01*
Y36278D01*
X975993Y36257D01*
G03X978760Y36068I1369J-300D01*
G02X979158Y36500I399J32D01*
G01X982259D01*
G02X982657Y36068I-1J-400D01*
G03X985424Y36257I1398J-111D01*
G01X985420Y36278D01*
Y36500D01*
X986036D01*
Y36278D01*
X986032Y36257D01*
G03X988799Y36068I1369J-300D01*
G02X989197Y36500I399J32D01*
G01X992298D01*
G02X992696Y36068I-1J-400D01*
G03X995463Y36257I1398J-111D01*
G01X995459Y36278D01*
Y36500D01*
X996076D01*
Y36278D01*
X996072Y36257D01*
G03X998839Y36068I1369J-300D01*
G02X999237Y36500I399J32D01*
G01X1002338D01*
G02X1002736Y36068I-1J-400D01*
G03X1005532I1398J-111D01*
G02X1005930Y36500I399J32D01*
G01X1006100D01*
X1006200Y36600D01*
Y41800D01*
X1006600Y42200D01*
X1008500D01*
X1008800Y41900D01*
Y37200D01*
X1009448Y36552D01*
X1009407Y36434D01*
G03X1012148Y35228I1419J-493D01*
G02X1012851I352J-190D01*
G03X1015670Y36067I1322J713D01*
G02X1016068Y36500I399J33D01*
G01X1018000D01*
X1018500Y36000D01*
Y28000D01*
X1018000Y27500D01*
X1016072D01*
G02X1015672Y27924I-1J400D01*
G03X1012851Y28728I-1499J90D01*
G02X1012148I-352J190D01*
G03X1009327Y27924I-1322J-714D01*
G02X1008927Y27500I-399J-24D01*
G01X1005931D01*
G02X1005532Y27927I0J400D01*
G03X1002760Y27740I-1399J95D01*
G01X1002764Y27720D01*
Y27500D01*
X1002156D01*
Y27720D01*
X1002160Y27740D01*
G03X999388Y27927I-1373J282D01*
G02X998989Y27500I-399J-27D01*
G01X995892D01*
G02X995493Y27927I0J400D01*
G03X992721Y27740I-1399J95D01*
G01X992725Y27720D01*
Y27500D01*
X992117D01*
Y27720D01*
X992121Y27740D01*
G03X989349Y27927I-1373J282D01*
G02X988950Y27500I-399J-27D01*
G01X985852D01*
G02X985453Y27925I0J400D01*
G03X985391Y28437I-1399J90D01*
G01X985382Y28466D01*
Y28562D01*
X985314Y28630D01*
X985299Y28658D01*
G03X982679Y27739I-1245J-644D01*
G01X982683Y27720D01*
Y27500D01*
X982079D01*
Y27720D01*
X982083Y27739D01*
G03X979309Y27925I-1375J275D01*
G02X978910Y27500I-399J-25D01*
G01X975813D01*
G02X975414Y27925I0J400D01*
G03X972640Y27739I-1399J89D01*
G01X972644Y27720D01*
Y27500D01*
X972040D01*
Y27720D01*
X972044Y27739D01*
G03X969270Y27925I-1375J275D01*
G02X968871Y27500I-399J-25D01*
G01X965774D01*
G02X965375Y27925I0J400D01*
G03X962577I-1399J89D01*
G02X962178Y27500I-399J-25D01*
G01X959500D01*
X959000Y28000D01*
Y31452D01*
X959018Y31492D01*
G03Y32708I-1318J608D01*
G01X959000Y32748D01*
Y34639D01*
G02X959673Y34932I400J0D01*
G03X962027Y36068I956J1025D01*
G02X962425Y36500I399J32D01*
G01X965758D01*
G37*
G36*
G01X962118Y7700D02*
G02X961788Y8325I1J400D01*
G03X961808Y8355I-1156J793D01*
G03X961650Y10075I-1179J759D01*
G02X961942Y10748I292J273D01*
G01X964302D01*
Y11198D01*
Y11248D01*
X965802D01*
Y11698D01*
Y14702D01*
Y15152D01*
X964302D01*
Y15202D01*
Y15686D01*
X964436Y15732D01*
G03X965248Y17647I-460J1325D01*
G02X965617Y18200I370J153D01*
G01X969028D01*
G02X969397Y17647I-1J-400D01*
G03X971941I1272J-590D01*
G02X972310Y18200I370J153D01*
G01X972374D01*
G02X972743Y17647I-1J-400D01*
G03X972851Y16275I1272J-590D01*
G02X972519Y15652I-332J-223D01*
G01X971998D01*
Y14502D01*
X971445D01*
X971406Y14520D01*
G03Y11880I-606J-1320D01*
G01X971445Y11898D01*
X971998D01*
Y10748D01*
X972702D01*
G02X972994Y10075I0J-400D01*
G03X972856Y8325I1021J-961D01*
G02X972526Y7700I-331J-225D01*
G01X968811D01*
G02X968481Y8325I1J400D01*
G03X966163I-1159J789D01*
G02X965833Y7700I-331J-225D01*
G01X962118D01*
G37*
G36*
G01X959340Y14602D02*
Y17140D01*
X960400Y18200D01*
X962335D01*
G02X962704Y17647I-1J-400D01*
G03X962812Y16275I1272J-590D01*
G02X962480Y15652I-332J-223D01*
G01X959798D01*
Y15202D01*
Y14602D01*
X959340D01*
G37*
G36*
G01X952820Y45169D02*
X952800Y45190D01*
X950123D01*
X949116Y46197D01*
Y50756D01*
X952130Y53770D01*
Y55998D01*
X952769Y56636D01*
X956123D01*
G02X956381Y55930I0J-400D01*
G03X957761Y53539I902J-1073D01*
G02X958297Y53163I136J-376D01*
G01Y45908D01*
X957558Y45169D01*
X952820D01*
G37*
G36*
G01X1009896Y74500D02*
X1015500D01*
X1015844Y74156D01*
Y71933D01*
X1015738Y71826D01*
X1015372D01*
X1012350Y70575D01*
X1011775Y70000D01*
X1010500D01*
X1009500Y69000D01*
Y67702D01*
X1009208Y67410D01*
X1009204D01*
X1009133Y67339D01*
X959329D01*
X959258Y67410D01*
X959111Y67558D01*
Y68457D01*
X958181Y69387D01*
X956354D01*
X956000Y69741D01*
Y82100D01*
X956300Y82400D01*
X957629D01*
X958600Y81429D01*
Y74400D01*
X961000Y72000D01*
X1007840D01*
X1007856Y71997D01*
G03X1008342I243J1482D01*
G01X1008358Y72000D01*
X1008412D01*
X1008424Y72012D01*
X1008477Y72026D01*
G03X1009518Y73969I-378J1453D01*
G02X1009896Y74500I378J131D01*
G37*
G36*
G01X962000Y45200D02*
X961727Y45473D01*
G02X961703Y46013I283J283D01*
G03X961650Y47875I-1074J901D01*
G02X961942Y48548I292J273D01*
G01X964302D01*
Y49048D01*
X965802D01*
Y52952D01*
X964302D01*
Y53486D01*
X964436Y53533D01*
G03X964865Y55941I-460J1324D01*
G02X965119Y56650I254J309D01*
G01X969526D01*
G02X969780Y55941I0J-400D01*
G03X971558I889J-1084D01*
G02X971812Y56650I254J309D01*
G01X972872D01*
G02X973126Y55941I0J-400D01*
G03X972852Y54075I889J-1084D01*
G02X972520Y53452I-332J-223D01*
G01X971998D01*
Y52302D01*
X970975D01*
X970963Y52303D01*
G03X970637I-163J-1443D01*
G01X970625Y52302D01*
X970401D01*
X970336Y52237D01*
X970295Y52221D01*
G03X971622Y49663I505J-1361D01*
G01X971674Y49698D01*
X971998D01*
Y48548D01*
X972702D01*
G02X972994Y47875I0J-400D01*
G03X973056Y45892I1021J-961D01*
G02X972782Y45200I-274J-292D01*
G01X968555D01*
G02X968281Y45892I0J400D01*
G03X966363I-959J1022D01*
G02X966089Y45200I-274J-292D01*
G01X962000D01*
G37*
G36*
G01X959298Y52302D02*
Y56448D01*
X959500Y56650D01*
X962833D01*
G02X963087Y55941I0J-400D01*
G03X962813Y54075I889J-1084D01*
G02X962481Y53452I-332J-223D01*
G01X959798D01*
Y52302D01*
X959298D01*
G37*
G36*
G01X937490Y192735D02*
X937630Y193135D01*
X938050D01*
X938190Y192735D01*
Y192535D01*
X937490D01*
Y192735D01*
G37*
G36*
G01X937340Y192335D02*
X937200Y191935D01*
X936780D01*
X936640Y192335D01*
Y192535D01*
X937340D01*
Y192335D01*
G37*
G36*
G01X935737Y192291D02*
X935921Y191909D01*
X935624Y191612D01*
X935242Y191796D01*
X935100Y191937D01*
X935595Y192432D01*
X935737Y192291D01*
G37*
G36*
G01X939190Y192735D02*
X939330Y193135D01*
X939750D01*
X939890Y192735D01*
Y192535D01*
X939190D01*
Y192735D01*
G37*
G36*
G01X939040Y192335D02*
X938900Y191935D01*
X938480D01*
X938340Y192335D01*
Y192535D01*
X939040D01*
Y192335D01*
G37*
G36*
G01X940740D02*
X940600Y191935D01*
X940180D01*
X940040Y192335D01*
Y192535D01*
X940740D01*
Y192335D01*
G37*
G36*
G01X914624Y188274D02*
X915119Y187708D01*
X914837Y187425D01*
X914271Y187920D01*
X914129Y188061D01*
X914483Y188415D01*
X914624Y188274D01*
G37*
G36*
G01X914907Y189122D02*
X914412Y189688D01*
X914695Y189971D01*
X915261Y189476D01*
X915402Y189334D01*
X915049Y188981D01*
X914907Y189122D01*
G37*
G36*
G01X912174Y187391D02*
X912224Y188141D01*
X912624D01*
X912674Y187391D01*
Y187191D01*
X912174D01*
Y187391D01*
G37*
G36*
G01X911374Y186991D02*
X911324Y186241D01*
X910924D01*
X910874Y186991D01*
Y187191D01*
X911374D01*
Y186991D01*
G37*
G36*
G01X932940Y192035D02*
X932990Y192785D01*
X933390D01*
X933440Y192035D01*
Y191835D01*
X932940D01*
Y192035D01*
G37*
G36*
G01X922540D02*
X922590Y192785D01*
X922990D01*
X923040Y192035D01*
Y191835D01*
X922540D01*
Y192035D01*
G37*
G36*
G01X919940D02*
X919990Y192785D01*
X920390D01*
X920440Y192035D01*
Y191835D01*
X919940D01*
Y192035D01*
G37*
G36*
G01X925140D02*
X925190Y192785D01*
X925590D01*
X925640Y192035D01*
Y191835D01*
X925140D01*
Y192035D01*
G37*
G36*
G01X927740D02*
X927790Y192785D01*
X928190D01*
X928240Y192035D01*
Y191835D01*
X927740D01*
Y192035D01*
G37*
G36*
G01X930340D02*
X930390Y192785D01*
X930790D01*
X930840Y192035D01*
Y191835D01*
X930340D01*
Y192035D01*
G37*
G36*
G01X926940Y191635D02*
X926890Y190885D01*
X926490D01*
X926440Y191635D01*
Y191835D01*
X926940D01*
Y191635D01*
G37*
G36*
G01X924340D02*
X924290Y190885D01*
X923890D01*
X923840Y191635D01*
Y191835D01*
X924340D01*
Y191635D01*
G37*
G36*
G01X921740D02*
X921690Y190885D01*
X921290D01*
X921240Y191635D01*
Y191835D01*
X921740D01*
Y191635D01*
G37*
G36*
G01X929540D02*
X929490Y190885D01*
X929090D01*
X929040Y191635D01*
Y191835D01*
X929540D01*
Y191635D01*
G37*
G36*
G01X932140D02*
X932090Y190885D01*
X931690D01*
X931640Y191635D01*
Y191835D01*
X932140D01*
Y191635D01*
G37*
G36*
G01X916463Y190112D02*
X916958Y189546D01*
X916675Y189264D01*
X916109Y189759D01*
X915968Y189900D01*
X916321Y190253D01*
X916463Y190112D01*
G37*
G36*
G01X916747Y190962D02*
X916252Y191528D01*
X916535Y191811D01*
X917101Y191316D01*
X917242Y191174D01*
X916889Y190821D01*
X916747Y190962D01*
G37*
G36*
G01X919140Y191635D02*
X919090Y190885D01*
X918690D01*
X918640Y191635D01*
Y191835D01*
X919140D01*
Y191635D01*
G37*
G36*
G01X947540Y192335D02*
X947400Y191935D01*
X946980D01*
X946840Y192335D01*
Y192535D01*
X947540D01*
Y192335D01*
G37*
G36*
G01X945990Y192735D02*
X946130Y193135D01*
X946550D01*
X946690Y192735D01*
Y192535D01*
X945990D01*
Y192735D01*
G37*
G36*
G01X940890D02*
X941030Y193135D01*
X941450D01*
X941590Y192735D01*
Y192535D01*
X940890D01*
Y192735D01*
G37*
G36*
G01X942590D02*
X942730Y193135D01*
X943150D01*
X943290Y192735D01*
Y192535D01*
X942590D01*
Y192735D01*
G37*
G36*
G01X944290D02*
X944430Y193135D01*
X944850D01*
X944990Y192735D01*
Y192535D01*
X944290D01*
Y192735D01*
G37*
G36*
G01X942440Y192335D02*
X942300Y191935D01*
X941880D01*
X941740Y192335D01*
Y192535D01*
X942440D01*
Y192335D01*
G37*
G36*
G01X944140D02*
X944000Y191935D01*
X943580D01*
X943440Y192335D01*
Y192535D01*
X944140D01*
Y192335D01*
G37*
G36*
G01X945840D02*
X945700Y191935D01*
X945280D01*
X945140Y192335D01*
Y192535D01*
X945840D01*
Y192335D01*
G37*
G36*
G01X953657Y194511D02*
X953841Y194129D01*
X953544Y193832D01*
X953162Y194016D01*
X953021Y194158D01*
X953516Y194653D01*
X953657Y194511D01*
G37*
G36*
G01X949240Y192335D02*
X949100Y191935D01*
X948680D01*
X948540Y192335D01*
Y192535D01*
X949240D01*
Y192335D01*
G37*
G36*
G01X952455Y193309D02*
X952639Y192927D01*
X952342Y192630D01*
X951960Y192814D01*
X951818Y192955D01*
X952313Y193450D01*
X952455Y193309D01*
G37*
G36*
G01X949390Y192735D02*
X949530Y193135D01*
X949950D01*
X950090Y192735D01*
Y192535D01*
X949390D01*
Y192735D01*
G37*
G36*
G01X950940Y192335D02*
X950800Y191935D01*
X950380D01*
X950240Y192335D01*
Y192535D01*
X950940D01*
Y192335D01*
G37*
G36*
G01X947690Y192735D02*
X947830Y193135D01*
X948250D01*
X948390Y192735D01*
Y192535D01*
X947690D01*
Y192735D01*
G37*
G36*
G01X937490Y191535D02*
X937630Y191935D01*
X938050D01*
X938190Y191535D01*
Y191335D01*
X937490D01*
Y191535D01*
G37*
G36*
G01X935207Y190629D02*
X935023Y191011D01*
X935320Y191308D01*
X935702Y191124D01*
X935843Y190982D01*
X935348Y190487D01*
X935207Y190629D01*
G37*
G36*
G01X934740Y190085D02*
X934690Y189335D01*
X934290D01*
X934240Y190085D01*
Y190285D01*
X934740D01*
Y190085D01*
G37*
G36*
G01X939190Y191535D02*
X939330Y191935D01*
X939750D01*
X939890Y191535D01*
Y191335D01*
X939190D01*
Y191535D01*
G37*
G36*
G01X939040Y191135D02*
X938900Y190735D01*
X938480D01*
X938340Y191135D01*
Y191335D01*
X939040D01*
Y191135D01*
G37*
G36*
G01X940740D02*
X940600Y190735D01*
X940180D01*
X940040Y191135D01*
Y191335D01*
X940740D01*
Y191135D01*
G37*
G36*
G01X914164Y186186D02*
X913669Y186751D01*
X913952Y187034D01*
X914517Y186539D01*
X914659Y186398D01*
X914305Y186044D01*
X914164Y186186D01*
G37*
G36*
G01X912174Y185841D02*
X912224Y186591D01*
X912624D01*
X912674Y185841D01*
Y185641D01*
X912174D01*
Y185841D01*
G37*
G36*
G01X915721Y187177D02*
X916216Y186611D01*
X915933Y186329D01*
X915367Y186824D01*
X915226Y186965D01*
X915580Y187319D01*
X915721Y187177D01*
G37*
G36*
G01X916004Y188026D02*
X915509Y188591D01*
X915792Y188874D01*
X916357Y188379D01*
X916499Y188238D01*
X916145Y187884D01*
X916004Y188026D01*
G37*
G36*
G01X932940Y190485D02*
X932990Y191235D01*
X933390D01*
X933440Y190485D01*
Y190285D01*
X932940D01*
Y190485D01*
G37*
G36*
G01X917561Y189017D02*
X918056Y188451D01*
X917773Y188169D01*
X917207Y188664D01*
X917066Y188805D01*
X917420Y189159D01*
X917561Y189017D01*
G37*
G36*
G01X917844Y189866D02*
X917349Y190431D01*
X917632Y190714D01*
X918197Y190219D01*
X918339Y190078D01*
X917985Y189724D01*
X917844Y189866D01*
G37*
G36*
G01X925140Y190485D02*
X925190Y191235D01*
X925590D01*
X925640Y190485D01*
Y190285D01*
X925140D01*
Y190485D01*
G37*
G36*
G01X922540D02*
X922590Y191235D01*
X922990D01*
X923040Y190485D01*
Y190285D01*
X922540D01*
Y190485D01*
G37*
G36*
G01X919940D02*
X919990Y191235D01*
X920390D01*
X920440Y190485D01*
Y190285D01*
X919940D01*
Y190485D01*
G37*
G36*
G01X927740D02*
X927790Y191235D01*
X928190D01*
X928240Y190485D01*
Y190285D01*
X927740D01*
Y190485D01*
G37*
G36*
G01X930340D02*
X930390Y191235D01*
X930790D01*
X930840Y190485D01*
Y190285D01*
X930340D01*
Y190485D01*
G37*
G36*
G01X926940Y190085D02*
X926890Y189335D01*
X926490D01*
X926440Y190085D01*
Y190285D01*
X926940D01*
Y190085D01*
G37*
G36*
G01X924340D02*
X924290Y189335D01*
X923890D01*
X923840Y190085D01*
Y190285D01*
X924340D01*
Y190085D01*
G37*
G36*
G01X921740D02*
X921690Y189335D01*
X921290D01*
X921240Y190085D01*
Y190285D01*
X921740D01*
Y190085D01*
G37*
G36*
G01X929540D02*
X929490Y189335D01*
X929090D01*
X929040Y190085D01*
Y190285D01*
X929540D01*
Y190085D01*
G37*
G36*
G01X932140D02*
X932090Y189335D01*
X931690D01*
X931640Y190085D01*
Y190285D01*
X932140D01*
Y190085D01*
G37*
G36*
G01X947540Y191135D02*
X947400Y190735D01*
X946980D01*
X946840Y191135D01*
Y191335D01*
X947540D01*
Y191135D01*
G37*
G36*
G01X945990Y191535D02*
X946130Y191935D01*
X946550D01*
X946690Y191535D01*
Y191335D01*
X945990D01*
Y191535D01*
G37*
G36*
G01X942590D02*
X942730Y191935D01*
X943150D01*
X943290Y191535D01*
Y191335D01*
X942590D01*
Y191535D01*
G37*
G36*
G01X940890D02*
X941030Y191935D01*
X941450D01*
X941590Y191535D01*
Y191335D01*
X940890D01*
Y191535D01*
G37*
G36*
G01X944290D02*
X944430Y191935D01*
X944850D01*
X944990Y191535D01*
Y191335D01*
X944290D01*
Y191535D01*
G37*
G36*
G01X942440Y191135D02*
X942300Y190735D01*
X941880D01*
X941740Y191135D01*
Y191335D01*
X942440D01*
Y191135D01*
G37*
G36*
G01X944140D02*
X944000Y190735D01*
X943580D01*
X943440Y191135D01*
Y191335D01*
X944140D01*
Y191135D01*
G37*
G36*
G01X945840D02*
X945700Y190735D01*
X945280D01*
X945140Y191135D01*
Y191335D01*
X945840D01*
Y191135D01*
G37*
G36*
G01X955708Y194864D02*
X955892Y194482D01*
X955595Y194185D01*
X955213Y194369D01*
X955072Y194511D01*
X955567Y195006D01*
X955708Y194864D01*
G37*
G36*
G01X954329Y194051D02*
X954145Y194433D01*
X954442Y194730D01*
X954824Y194546D01*
X954966Y194405D01*
X954471Y193910D01*
X954329Y194051D01*
G37*
G36*
G01X955531Y195253D02*
X955347Y195635D01*
X955644Y195932D01*
X956026Y195748D01*
X956168Y195607D01*
X955673Y195112D01*
X955531Y195253D01*
G37*
G36*
G01X953304Y192460D02*
X953488Y192078D01*
X953191Y191781D01*
X952809Y191965D01*
X952667Y192106D01*
X953162Y192601D01*
X953304Y192460D01*
G37*
G36*
G01X954506Y193662D02*
X954690Y193280D01*
X954393Y192983D01*
X954011Y193167D01*
X953870Y193309D01*
X954365Y193804D01*
X954506Y193662D01*
G37*
G36*
G01X953127Y192849D02*
X952943Y193231D01*
X953240Y193528D01*
X953622Y193344D01*
X953763Y193202D01*
X953269Y192708D01*
X953127Y192849D01*
G37*
G36*
G01X951925Y191647D02*
X951741Y192029D01*
X952038Y192326D01*
X952420Y192142D01*
X952561Y192000D01*
X952067Y191506D01*
X951925Y191647D01*
G37*
G36*
G01X947690Y191535D02*
X947830Y191935D01*
X948250D01*
X948390Y191535D01*
Y191335D01*
X947690D01*
Y191535D01*
G37*
G36*
G01X949390D02*
X949530Y191935D01*
X949950D01*
X950090Y191535D01*
Y191335D01*
X949390D01*
Y191535D01*
G37*
G36*
G01X949240Y191135D02*
X949100Y190735D01*
X948680D01*
X948540Y191135D01*
Y191335D01*
X949240D01*
Y191135D01*
G37*
G36*
G01X950940D02*
X950800Y190735D01*
X950380D01*
X950240Y191135D01*
Y191335D01*
X950940D01*
Y191135D01*
G37*
G36*
G01X913974Y185441D02*
X913924Y184691D01*
X913524D01*
X913474Y185441D01*
Y185641D01*
X913974D01*
Y185441D01*
G37*
G36*
G01X937544Y181080D02*
X937360Y181461D01*
X937657Y181758D01*
X938039Y181575D01*
X938180Y181433D01*
X937685Y180938D01*
X937544Y181080D01*
G37*
G36*
G01X938923Y181893D02*
X939107Y181511D01*
X938810Y181214D01*
X938428Y181398D01*
X938286Y181539D01*
X938781Y182034D01*
X938923Y181893D01*
G37*
G36*
G01X938746Y182282D02*
X938562Y182663D01*
X938859Y182960D01*
X939241Y182777D01*
X939382Y182635D01*
X938887Y182140D01*
X938746Y182282D01*
G37*
G36*
G01X934740Y179235D02*
X934690Y178485D01*
X934290D01*
X934240Y179235D01*
Y179435D01*
X934740D01*
Y179235D01*
G37*
G36*
G01X937721Y180691D02*
X937904Y180309D01*
X937607Y180012D01*
X937226Y180196D01*
X937084Y180337D01*
X937579Y180832D01*
X937721Y180691D01*
G37*
G36*
G01X936342Y179878D02*
X936158Y180259D01*
X936455Y180556D01*
X936837Y180373D01*
X936978Y180231D01*
X936483Y179736D01*
X936342Y179878D01*
G37*
G36*
G01X932940Y179635D02*
X932990Y180385D01*
X933390D01*
X933440Y179635D01*
Y179435D01*
X932940D01*
Y179635D01*
G37*
G36*
G01X927740D02*
X927790Y180385D01*
X928190D01*
X928240Y179635D01*
Y179435D01*
X927740D01*
Y179635D01*
G37*
G36*
G01X925140D02*
X925190Y180385D01*
X925590D01*
X925640Y179635D01*
Y179435D01*
X925140D01*
Y179635D01*
G37*
G36*
G01X930340D02*
X930390Y180385D01*
X930790D01*
X930840Y179635D01*
Y179435D01*
X930340D01*
Y179635D01*
G37*
G36*
G01X929540Y179235D02*
X929490Y178485D01*
X929090D01*
X929040Y179235D01*
Y179435D01*
X929540D01*
Y179235D01*
G37*
G36*
G01X926940D02*
X926890Y178485D01*
X926490D01*
X926440Y179235D01*
Y179435D01*
X926940D01*
Y179235D01*
G37*
G36*
G01X932140D02*
X932090Y178485D01*
X931690D01*
X931640Y179235D01*
Y179435D01*
X932140D01*
Y179235D01*
G37*
G36*
G01X924340D02*
X924290Y178485D01*
X923890D01*
X923840Y179235D01*
Y179435D01*
X924340D01*
Y179235D01*
G37*
G36*
G01X921841Y178511D02*
X921346Y179077D01*
X921629Y179360D01*
X922195Y178865D01*
X922336Y178723D01*
X921983Y178370D01*
X921841Y178511D01*
G37*
G36*
G01X921021Y176421D02*
X920271Y176471D01*
Y176871D01*
X921021Y176921D01*
X921271D01*
Y176421D01*
X921021D01*
G37*
G36*
G01X921471Y175621D02*
X922221Y175571D01*
Y175171D01*
X921471Y175121D01*
X921221D01*
Y175621D01*
X921471D01*
G37*
G36*
G01X947540Y182735D02*
X947400Y182335D01*
X946980D01*
X946840Y182735D01*
Y182935D01*
X947540D01*
Y182735D01*
G37*
G36*
G01X945990Y183135D02*
X946130Y183535D01*
X946550D01*
X946690Y183135D01*
Y182935D01*
X945990D01*
Y183135D01*
G37*
G36*
G01X944290D02*
X944430Y183535D01*
X944850D01*
X944990Y183135D01*
Y182935D01*
X944290D01*
Y183135D01*
G37*
G36*
G01X942590D02*
X942730Y183535D01*
X943150D01*
X943290Y183135D01*
Y182935D01*
X942590D01*
Y183135D01*
G37*
G36*
G01X940890D02*
X941030Y183535D01*
X941450D01*
X941590Y183135D01*
Y182935D01*
X940890D01*
Y183135D01*
G37*
G36*
G01X945840Y182735D02*
X945700Y182335D01*
X945280D01*
X945140Y182735D01*
Y182935D01*
X945840D01*
Y182735D01*
G37*
G36*
G01X944140D02*
X944000Y182335D01*
X943580D01*
X943440Y182735D01*
Y182935D01*
X944140D01*
Y182735D01*
G37*
G36*
G01X942440D02*
X942300Y182335D01*
X941880D01*
X941740Y182735D01*
Y182935D01*
X942440D01*
Y182735D01*
G37*
G36*
G01X956843Y184113D02*
X957027Y183731D01*
X956730Y183434D01*
X956348Y183618D01*
X956206Y183759D01*
X956701Y184254D01*
X956843Y184113D01*
G37*
G36*
G01X955464Y183300D02*
X955280Y183682D01*
X955577Y183979D01*
X955959Y183795D01*
X956100Y183653D01*
X955605Y183158D01*
X955464Y183300D01*
G37*
G36*
G01X959247Y186517D02*
X959431Y186135D01*
X959134Y185838D01*
X958752Y186022D01*
X958610Y186163D01*
X959105Y186658D01*
X959247Y186517D01*
G37*
G36*
G01X958045Y185315D02*
X958229Y184933D01*
X957932Y184636D01*
X957550Y184820D01*
X957408Y184961D01*
X957903Y185456D01*
X958045Y185315D01*
G37*
G36*
G01X960449Y187719D02*
X960633Y187337D01*
X960336Y187040D01*
X959954Y187224D01*
X959813Y187366D01*
X960308Y187861D01*
X960449Y187719D01*
G37*
G36*
G01X961651Y188921D02*
X961835Y188539D01*
X961538Y188242D01*
X961156Y188426D01*
X961015Y188568D01*
X961510Y189063D01*
X961651Y188921D01*
G37*
G36*
G01X962853Y190123D02*
X963037Y189741D01*
X962740Y189444D01*
X962358Y189628D01*
X962217Y189770D01*
X962712Y190265D01*
X962853Y190123D01*
G37*
G36*
G01X964055Y191325D02*
X964239Y190944D01*
X963942Y190647D01*
X963560Y190830D01*
X963419Y190972D01*
X963914Y191467D01*
X964055Y191325D01*
G37*
G36*
G01X956666Y184502D02*
X956482Y184884D01*
X956779Y185181D01*
X957161Y184997D01*
X957302Y184855D01*
X956807Y184360D01*
X956666Y184502D01*
G37*
G36*
G01X959070Y186906D02*
X958886Y187288D01*
X959183Y187585D01*
X959565Y187401D01*
X959706Y187259D01*
X959212Y186765D01*
X959070Y186906D01*
G37*
G36*
G01X960272Y188108D02*
X960088Y188490D01*
X960385Y188787D01*
X960767Y188603D01*
X960909Y188462D01*
X960414Y187967D01*
X960272Y188108D01*
G37*
G36*
G01X961474Y189310D02*
X961290Y189692D01*
X961587Y189989D01*
X961969Y189805D01*
X962111Y189664D01*
X961616Y189169D01*
X961474Y189310D01*
G37*
G36*
G01X962676Y190512D02*
X962492Y190894D01*
X962789Y191191D01*
X963171Y191007D01*
X963313Y190866D01*
X962818Y190371D01*
X962676Y190512D01*
G37*
G36*
G01X947690Y183135D02*
X947830Y183535D01*
X948250D01*
X948390Y183135D01*
Y182935D01*
X947690D01*
Y183135D01*
G37*
G36*
G01X949390D02*
X949530Y183535D01*
X949950D01*
X950090Y183135D01*
Y182935D01*
X949390D01*
Y183135D01*
G37*
G36*
G01X951090D02*
X951230Y183535D01*
X951650D01*
X951790Y183135D01*
Y182935D01*
X951090D01*
Y183135D01*
G37*
G36*
G01X952790D02*
X952930Y183535D01*
X953350D01*
X953490Y183135D01*
Y182935D01*
X952790D01*
Y183135D01*
G37*
G36*
G01X949240Y182735D02*
X949100Y182335D01*
X948680D01*
X948540Y182735D01*
Y182935D01*
X949240D01*
Y182735D01*
G37*
G36*
G01X950940D02*
X950800Y182335D01*
X950380D01*
X950240Y182735D01*
Y182935D01*
X950940D01*
Y182735D01*
G37*
G36*
G01X952640D02*
X952500Y182335D01*
X952080D01*
X951940Y182735D01*
Y182935D01*
X952640D01*
Y182735D01*
G37*
G36*
G01X954340D02*
X954200Y182335D01*
X953780D01*
X953640Y182735D01*
Y182935D01*
X954340D01*
Y182735D01*
G37*
G36*
G01X957868Y185704D02*
X957684Y186086D01*
X957981Y186383D01*
X958363Y186199D01*
X958504Y186057D01*
X958009Y185562D01*
X957868Y185704D01*
G37*
G36*
G01X937190Y179029D02*
X937007Y179411D01*
X937304Y179708D01*
X937685Y179524D01*
X937862Y179347D01*
X937367Y178852D01*
X937190Y179029D01*
G37*
G36*
G01X935540Y178085D02*
X935590Y178835D01*
X935990D01*
X936040Y178085D01*
Y177835D01*
X935540D01*
Y178085D01*
G37*
G36*
G01X938392Y180231D02*
X938209Y180613D01*
X938506Y180910D01*
X938887Y180726D01*
X939064Y180549D01*
X938569Y180054D01*
X938392Y180231D01*
G37*
G36*
G01X932940Y178085D02*
X932990Y178835D01*
X933390D01*
X933440Y178085D01*
Y177835D01*
X932940D01*
Y178085D01*
G37*
G36*
G01X927740D02*
X927790Y178835D01*
X928190D01*
X928240Y178085D01*
Y177835D01*
X927740D01*
Y178085D01*
G37*
G36*
G01X925140D02*
X925190Y178835D01*
X925590D01*
X925640Y178085D01*
Y177835D01*
X925140D01*
Y178085D01*
G37*
G36*
G01X930340D02*
X930390Y178835D01*
X930790D01*
X930840Y178085D01*
Y177835D01*
X930340D01*
Y178085D01*
G37*
G36*
G01X922938Y177414D02*
X922443Y177980D01*
X922726Y178263D01*
X923292Y177768D01*
X923433Y177626D01*
X923080Y177273D01*
X922938Y177414D01*
G37*
G36*
G01X922621Y176421D02*
X921871Y176471D01*
Y176871D01*
X922621Y176921D01*
X922871D01*
Y176421D01*
X922621D01*
G37*
G36*
G01Y173821D02*
X921871Y173871D01*
Y174271D01*
X922621Y174321D01*
X922871D01*
Y173821D01*
X922621D01*
G37*
G36*
G01X945990Y181935D02*
X946130Y182335D01*
X946550D01*
X946690Y181935D01*
Y181685D01*
X945990D01*
Y181935D01*
G37*
G36*
G01X944290D02*
X944430Y182335D01*
X944850D01*
X944990Y181935D01*
Y181685D01*
X944290D01*
Y181935D01*
G37*
G36*
G01X942590D02*
X942730Y182335D01*
X943150D01*
X943290Y181935D01*
Y181685D01*
X942590D01*
Y181935D01*
G37*
G36*
G01X940890D02*
X941030Y182335D01*
X941450D01*
X941590Y181935D01*
Y181685D01*
X940890D01*
Y181935D01*
G37*
G36*
G01X957515Y183653D02*
X957331Y184035D01*
X957628Y184332D01*
X958010Y184148D01*
X958186Y183971D01*
X957691Y183476D01*
X957515Y183653D01*
G37*
G36*
G01X956312Y182451D02*
X956129Y182833D01*
X956426Y183130D01*
X956807Y182946D01*
X956984Y182769D01*
X956489Y182274D01*
X956312Y182451D01*
G37*
G36*
G01X958717Y184855D02*
X958533Y185237D01*
X958830Y185534D01*
X959212Y185350D01*
X959388Y185173D01*
X958893Y184678D01*
X958717Y184855D01*
G37*
G36*
G01X959919Y186057D02*
X959735Y186439D01*
X960032Y186736D01*
X960414Y186552D01*
X960590Y186375D01*
X960096Y185881D01*
X959919Y186057D01*
G37*
G36*
G01X961121Y187259D02*
X960937Y187641D01*
X961234Y187938D01*
X961616Y187754D01*
X961793Y187578D01*
X961298Y187083D01*
X961121Y187259D01*
G37*
G36*
G01X962323Y188461D02*
X962139Y188843D01*
X962436Y189140D01*
X962818Y188956D01*
X962995Y188780D01*
X962500Y188285D01*
X962323Y188461D01*
G37*
G36*
G01X963525Y189664D02*
X963341Y190045D01*
X963638Y190342D01*
X964020Y190159D01*
X964197Y189982D01*
X963702Y189487D01*
X963525Y189664D01*
G37*
G36*
G01X947690Y181935D02*
X947830Y182335D01*
X948250D01*
X948390Y181935D01*
Y181685D01*
X947690D01*
Y181935D01*
G37*
G36*
G01X949390D02*
X949530Y182335D01*
X949950D01*
X950090Y181935D01*
Y181685D01*
X949390D01*
Y181935D01*
G37*
G36*
G01X951090D02*
X951230Y182335D01*
X951650D01*
X951790Y181935D01*
Y181685D01*
X951090D01*
Y181935D01*
G37*
G36*
G01X952790D02*
X952930Y182335D01*
X953350D01*
X953490Y181935D01*
Y181685D01*
X952790D01*
Y181935D01*
G37*
G36*
G01X954490D02*
X954630Y182335D01*
X955050D01*
X955190Y181935D01*
Y181685D01*
X954490D01*
Y181935D01*
G37*
G36*
G01X939594Y181433D02*
X939411Y181815D01*
X939708Y182112D01*
X940089Y181928D01*
X940266Y181751D01*
X939771Y181256D01*
X939594Y181433D01*
G37*
G36*
G01X937340Y194735D02*
X937200Y194335D01*
X936780D01*
X936640Y194735D01*
Y194985D01*
X937340D01*
Y194735D01*
G37*
G36*
G01X935640D02*
X935500Y194335D01*
X935080D01*
X934940Y194735D01*
Y194985D01*
X935640D01*
Y194735D01*
G37*
G36*
G01X939040D02*
X938900Y194335D01*
X938480D01*
X938340Y194735D01*
Y194985D01*
X939040D01*
Y194735D01*
G37*
G36*
G01X940740D02*
X940600Y194335D01*
X940180D01*
X940040Y194735D01*
Y194985D01*
X940740D01*
Y194735D01*
G37*
G36*
G01X914270Y192305D02*
X914765Y191739D01*
X914482Y191456D01*
X913917Y191951D01*
X913740Y192128D01*
X914093Y192481D01*
X914270Y192305D01*
G37*
G36*
G01X911374Y190091D02*
X911324Y189341D01*
X910924D01*
X910874Y190091D01*
Y190341D01*
X911374D01*
Y190091D01*
G37*
G36*
G01X929540Y194735D02*
X929490Y193985D01*
X929090D01*
X929040Y194735D01*
Y194985D01*
X929540D01*
Y194735D01*
G37*
G36*
G01X932140D02*
X932090Y193985D01*
X931690D01*
X931640Y194735D01*
Y194985D01*
X932140D01*
Y194735D01*
G37*
G36*
G01X926940D02*
X926890Y193985D01*
X926490D01*
X926440Y194735D01*
Y194985D01*
X926940D01*
Y194735D01*
G37*
G36*
G01X924340D02*
X924290Y193985D01*
X923890D01*
X923840Y194735D01*
Y194985D01*
X924340D01*
Y194735D01*
G37*
G36*
G01X921740D02*
X921690Y193985D01*
X921290D01*
X921240Y194735D01*
Y194985D01*
X921740D01*
Y194735D01*
G37*
G36*
G01X919140D02*
X919090Y193985D01*
X918690D01*
X918640Y194735D01*
Y194985D01*
X919140D01*
Y194735D01*
G37*
G36*
G01X916110Y194145D02*
X916605Y193579D01*
X916322Y193296D01*
X915757Y193791D01*
X915580Y193968D01*
X915933Y194321D01*
X916110Y194145D01*
G37*
G36*
G01X942440Y194735D02*
X942300Y194335D01*
X941880D01*
X941740Y194735D01*
Y194985D01*
X942440D01*
Y194735D01*
G37*
G36*
G01X944140D02*
X944000Y194335D01*
X943580D01*
X943440Y194735D01*
Y194985D01*
X944140D01*
Y194735D01*
G37*
G36*
G01X945840D02*
X945700Y194335D01*
X945280D01*
X945140Y194735D01*
Y194985D01*
X945840D01*
Y194735D01*
G37*
G36*
G01X948335Y195784D02*
X948519Y195402D01*
X948222Y195105D01*
X947840Y195289D01*
X947699Y195431D01*
X948194Y195926D01*
X948335Y195784D01*
G37*
G36*
G01X950955Y200663D02*
X950318Y201070D01*
X950394Y201937D01*
X951092Y202227D01*
X951266Y202212D01*
X951130Y200648D01*
X950955Y200663D01*
G37*
G36*
G01X912430Y190465D02*
X912925Y189899D01*
X912642Y189616D01*
X912077Y190111D01*
X911900Y190288D01*
X912253Y190641D01*
X912430Y190465D01*
G37*
G36*
G01X937490Y193935D02*
X937630Y194335D01*
X938050D01*
X938190Y193935D01*
Y193735D01*
X937490D01*
Y193935D01*
G37*
G36*
G01X935790D02*
X935930Y194335D01*
X936350D01*
X936490Y193935D01*
Y193735D01*
X935790D01*
Y193935D01*
G37*
G36*
G01X937340Y193535D02*
X937200Y193135D01*
X936780D01*
X936640Y193535D01*
Y193735D01*
X937340D01*
Y193535D01*
G37*
G36*
G01X934740Y193185D02*
X934690Y192435D01*
X934290D01*
X934240Y193185D01*
Y193385D01*
X934740D01*
Y193185D01*
G37*
G36*
G01X939190Y193935D02*
X939330Y194335D01*
X939750D01*
X939890Y193935D01*
Y193735D01*
X939190D01*
Y193935D01*
G37*
G36*
G01X939040Y193535D02*
X938900Y193135D01*
X938480D01*
X938340Y193535D01*
Y193735D01*
X939040D01*
Y193535D01*
G37*
G36*
G01X940740D02*
X940600Y193135D01*
X940180D01*
X940040Y193535D01*
Y193735D01*
X940740D01*
Y193535D01*
G37*
G36*
G01X915366Y191209D02*
X915861Y190643D01*
X915579Y190360D01*
X915013Y190855D01*
X914871Y190996D01*
X915225Y191350D01*
X915366Y191209D01*
G37*
G36*
G01X913811Y190219D02*
X913316Y190784D01*
X913599Y191067D01*
X914164Y190572D01*
X914306Y190431D01*
X913952Y190077D01*
X913811Y190219D01*
G37*
G36*
G01X915649Y192057D02*
X915154Y192623D01*
X915437Y192906D01*
X916003Y192411D01*
X916144Y192269D01*
X915791Y191916D01*
X915649Y192057D01*
G37*
G36*
G01X913526Y189369D02*
X914021Y188803D01*
X913739Y188520D01*
X913173Y189015D01*
X913031Y189156D01*
X913385Y189510D01*
X913526Y189369D01*
G37*
G36*
G01X911374Y188541D02*
X911324Y187791D01*
X910924D01*
X910874Y188541D01*
Y188741D01*
X911374D01*
Y188541D01*
G37*
G36*
G01X932940Y193585D02*
X932990Y194335D01*
X933390D01*
X933440Y193585D01*
Y193385D01*
X932940D01*
Y193585D01*
G37*
G36*
G01X922540D02*
X922590Y194335D01*
X922990D01*
X923040Y193585D01*
Y193385D01*
X922540D01*
Y193585D01*
G37*
G36*
G01X919940D02*
X919990Y194335D01*
X920390D01*
X920440Y193585D01*
Y193385D01*
X919940D01*
Y193585D01*
G37*
G36*
G01X925140D02*
X925190Y194335D01*
X925590D01*
X925640Y193585D01*
Y193385D01*
X925140D01*
Y193585D01*
G37*
G36*
G01X927740D02*
X927790Y194335D01*
X928190D01*
X928240Y193585D01*
Y193385D01*
X927740D01*
Y193585D01*
G37*
G36*
G01X930340D02*
X930390Y194335D01*
X930790D01*
X930840Y193585D01*
Y193385D01*
X930340D01*
Y193585D01*
G37*
G36*
G01X924340Y193185D02*
X924290Y192435D01*
X923890D01*
X923840Y193185D01*
Y193385D01*
X924340D01*
Y193185D01*
G37*
G36*
G01X921740D02*
X921690Y192435D01*
X921290D01*
X921240Y193185D01*
Y193385D01*
X921740D01*
Y193185D01*
G37*
G36*
G01X919140D02*
X919090Y192435D01*
X918690D01*
X918640Y193185D01*
Y193385D01*
X919140D01*
Y193185D01*
G37*
G36*
G01X926940D02*
X926890Y192435D01*
X926490D01*
X926440Y193185D01*
Y193385D01*
X926940D01*
Y193185D01*
G37*
G36*
G01X929540D02*
X929490Y192435D01*
X929090D01*
X929040Y193185D01*
Y193385D01*
X929540D01*
Y193185D01*
G37*
G36*
G01X932140D02*
X932090Y192435D01*
X931690D01*
X931640Y193185D01*
Y193385D01*
X932140D01*
Y193185D01*
G37*
G36*
G01X917340Y193585D02*
X917390Y194335D01*
X917790D01*
X917840Y193585D01*
Y193385D01*
X917340D01*
Y193585D01*
G37*
G36*
G01X917206Y193049D02*
X917701Y192483D01*
X917419Y192200D01*
X916853Y192695D01*
X916711Y192836D01*
X917065Y193190D01*
X917206Y193049D01*
G37*
G36*
G01X947540Y193535D02*
X947400Y193135D01*
X946980D01*
X946840Y193535D01*
Y193735D01*
X947540D01*
Y193535D01*
G37*
G36*
G01X945990Y193935D02*
X946130Y194335D01*
X946550D01*
X946690Y193935D01*
Y193735D01*
X945990D01*
Y193935D01*
G37*
G36*
G01X940890D02*
X941030Y194335D01*
X941450D01*
X941590Y193935D01*
Y193735D01*
X940890D01*
Y193935D01*
G37*
G36*
G01X942590D02*
X942730Y194335D01*
X943150D01*
X943290Y193935D01*
Y193735D01*
X942590D01*
Y193935D01*
G37*
G36*
G01X944290D02*
X944430Y194335D01*
X944850D01*
X944990Y193935D01*
Y193735D01*
X944290D01*
Y193935D01*
G37*
G36*
G01X942440Y193535D02*
X942300Y193135D01*
X941880D01*
X941740Y193535D01*
Y193735D01*
X942440D01*
Y193535D01*
G37*
G36*
G01X944140D02*
X944000Y193135D01*
X943580D01*
X943440Y193535D01*
Y193735D01*
X944140D01*
Y193535D01*
G37*
G36*
G01X945840D02*
X945700Y193135D01*
X945280D01*
X945140Y193535D01*
Y193735D01*
X945840D01*
Y193535D01*
G37*
G36*
G01X949007Y195324D02*
X948823Y195706D01*
X949120Y196003D01*
X949502Y195819D01*
X949643Y195678D01*
X949148Y195183D01*
X949007Y195324D01*
G37*
G36*
G01X947805Y194122D02*
X947621Y194504D01*
X947918Y194801D01*
X948300Y194617D01*
X948441Y194476D01*
X947946Y193981D01*
X947805Y194122D01*
G37*
G36*
G01X949184Y194936D02*
X949368Y194554D01*
X949071Y194257D01*
X948689Y194441D01*
X948548Y194582D01*
X949043Y195077D01*
X949184Y194936D01*
G37*
G36*
G01X952639Y200120D02*
X953309Y199770D01*
Y198900D01*
X952639Y198550D01*
X952464D01*
Y200120D01*
X952639D01*
G37*
G36*
G01X955478Y203454D02*
X955510Y202699D01*
X954757Y202264D01*
X954119Y202669D01*
X954031Y202821D01*
X955391Y203606D01*
X955478Y203454D01*
G37*
G36*
G01X934740Y182335D02*
X934690Y181585D01*
X934290D01*
X934240Y182335D01*
Y182535D01*
X934740D01*
Y182335D01*
G37*
G36*
G01X937225Y183591D02*
X937409Y183209D01*
X937112Y182912D01*
X936730Y183096D01*
X936588Y183237D01*
X937083Y183732D01*
X937225Y183591D01*
G37*
G36*
G01X937048Y183980D02*
X936864Y184362D01*
X937161Y184659D01*
X937543Y184475D01*
X937684Y184333D01*
X937189Y183838D01*
X937048Y183980D01*
G37*
G36*
G01X938427Y184793D02*
X938611Y184411D01*
X938314Y184114D01*
X937932Y184298D01*
X937790Y184439D01*
X938285Y184934D01*
X938427Y184793D01*
G37*
G36*
G01X939190Y185535D02*
X939330Y185935D01*
X939750D01*
X939890Y185535D01*
Y185335D01*
X939190D01*
Y185535D01*
G37*
G36*
G01X940740Y185135D02*
X940600Y184735D01*
X940180D01*
X940040Y185135D01*
Y185335D01*
X940740D01*
Y185135D01*
G37*
G36*
G01X932940Y182735D02*
X932990Y183485D01*
X933390D01*
X933440Y182735D01*
Y182535D01*
X932940D01*
Y182735D01*
G37*
G36*
G01X921205Y181696D02*
X921700Y181130D01*
X921418Y180847D01*
X920852Y181342D01*
X920710Y181483D01*
X921064Y181837D01*
X921205Y181696D01*
G37*
G36*
G01X919365Y179856D02*
X919860Y179290D01*
X919578Y179007D01*
X919012Y179502D01*
X918870Y179643D01*
X919224Y179997D01*
X919365Y179856D01*
G37*
G36*
G01X917808Y178865D02*
X917313Y179430D01*
X917596Y179713D01*
X918161Y179218D01*
X918303Y179077D01*
X917949Y178723D01*
X917808Y178865D01*
G37*
G36*
G01X925140Y182735D02*
X925190Y183485D01*
X925590D01*
X925640Y182735D01*
Y182535D01*
X925140D01*
Y182735D01*
G37*
G36*
G01X927740D02*
X927790Y183485D01*
X928190D01*
X928240Y182735D01*
Y182535D01*
X927740D01*
Y182735D01*
G37*
G36*
G01X930340D02*
X930390Y183485D01*
X930790D01*
X930840Y182735D01*
Y182535D01*
X930340D01*
Y182735D01*
G37*
G36*
G01X926940Y182335D02*
X926890Y181585D01*
X926490D01*
X926440Y182335D01*
Y182535D01*
X926940D01*
Y182335D01*
G37*
G36*
G01X924340D02*
X924290Y181585D01*
X923890D01*
X923840Y182335D01*
Y182535D01*
X924340D01*
Y182335D01*
G37*
G36*
G01X929540D02*
X929490Y181585D01*
X929090D01*
X929040Y182335D01*
Y182535D01*
X929540D01*
Y182335D01*
G37*
G36*
G01X932140D02*
X932090Y181585D01*
X931690D01*
X931640Y182335D01*
Y182535D01*
X932140D01*
Y182335D01*
G37*
G36*
G01X919648Y180705D02*
X919153Y181270D01*
X919436Y181553D01*
X920001Y181058D01*
X920143Y180917D01*
X919789Y180563D01*
X919648Y180705D01*
G37*
G36*
G01X922540Y182735D02*
X922590Y183485D01*
X922990D01*
X923040Y182735D01*
Y182535D01*
X922540D01*
Y182735D01*
G37*
G36*
G01X947540Y185135D02*
X947400Y184735D01*
X946980D01*
X946840Y185135D01*
Y185335D01*
X947540D01*
Y185135D01*
G37*
G36*
G01X945990Y185535D02*
X946130Y185935D01*
X946550D01*
X946690Y185535D01*
Y185335D01*
X945990D01*
Y185535D01*
G37*
G36*
G01X944290D02*
X944430Y185935D01*
X944850D01*
X944990Y185535D01*
Y185335D01*
X944290D01*
Y185535D01*
G37*
G36*
G01X942590D02*
X942730Y185935D01*
X943150D01*
X943290Y185535D01*
Y185335D01*
X942590D01*
Y185535D01*
G37*
G36*
G01X940890D02*
X941030Y185935D01*
X941450D01*
X941590Y185535D01*
Y185335D01*
X940890D01*
Y185535D01*
G37*
G36*
G01X944140Y185135D02*
X944000Y184735D01*
X943580D01*
X943440Y185135D01*
Y185335D01*
X944140D01*
Y185135D01*
G37*
G36*
G01X942440D02*
X942300Y184735D01*
X941880D01*
X941740Y185135D01*
Y185335D01*
X942440D01*
Y185135D01*
G37*
G36*
G01X945840D02*
X945700Y184735D01*
X945280D01*
X945140Y185135D01*
Y185335D01*
X945840D01*
Y185135D01*
G37*
G36*
G01X959953Y190619D02*
X960137Y190237D01*
X959840Y189940D01*
X959458Y190124D01*
X959317Y190266D01*
X959812Y190761D01*
X959953Y190619D01*
G37*
G36*
G01X961155Y191821D02*
X961339Y191439D01*
X961042Y191142D01*
X960660Y191326D01*
X960519Y191468D01*
X961014Y191963D01*
X961155Y191821D01*
G37*
G36*
G01X962357Y193023D02*
X962541Y192642D01*
X962244Y192345D01*
X961862Y192528D01*
X961721Y192670D01*
X962216Y193165D01*
X962357Y193023D01*
G37*
G36*
G01X956170Y187402D02*
X955986Y187784D01*
X956283Y188081D01*
X956665Y187897D01*
X956806Y187755D01*
X956311Y187260D01*
X956170Y187402D01*
G37*
G36*
G01X957372Y188604D02*
X957188Y188986D01*
X957485Y189283D01*
X957867Y189099D01*
X958008Y188957D01*
X957514Y188463D01*
X957372Y188604D01*
G37*
G36*
G01X958574Y189806D02*
X958390Y190188D01*
X958687Y190485D01*
X959069Y190301D01*
X959211Y190160D01*
X958716Y189665D01*
X958574Y189806D01*
G37*
G36*
G01X959776Y191008D02*
X959592Y191390D01*
X959889Y191687D01*
X960271Y191503D01*
X960413Y191362D01*
X959918Y190867D01*
X959776Y191008D01*
G37*
G36*
G01X960978Y192210D02*
X960794Y192592D01*
X961091Y192889D01*
X961473Y192705D01*
X961615Y192564D01*
X961120Y192069D01*
X960978Y192210D01*
G37*
G36*
G01X957549Y188215D02*
X957733Y187833D01*
X957436Y187536D01*
X957054Y187720D01*
X956912Y187861D01*
X957407Y188356D01*
X957549Y188215D01*
G37*
G36*
G01X956347Y187013D02*
X956531Y186631D01*
X956234Y186334D01*
X955852Y186518D01*
X955710Y186659D01*
X956205Y187154D01*
X956347Y187013D01*
G37*
G36*
G01X954968Y186200D02*
X954784Y186582D01*
X955081Y186879D01*
X955463Y186695D01*
X955604Y186553D01*
X955109Y186058D01*
X954968Y186200D01*
G37*
G36*
G01X955145Y185811D02*
X955329Y185429D01*
X955032Y185132D01*
X954650Y185316D01*
X954508Y185457D01*
X955003Y185952D01*
X955145Y185811D01*
G37*
G36*
G01X954340Y185135D02*
X954200Y184735D01*
X953780D01*
X953640Y185135D01*
Y185335D01*
X954340D01*
Y185135D01*
G37*
G36*
G01X947690Y185535D02*
X947830Y185935D01*
X948250D01*
X948390Y185535D01*
Y185335D01*
X947690D01*
Y185535D01*
G37*
G36*
G01X949390D02*
X949530Y185935D01*
X949950D01*
X950090Y185535D01*
Y185335D01*
X949390D01*
Y185535D01*
G37*
G36*
G01X951090D02*
X951230Y185935D01*
X951650D01*
X951790Y185535D01*
Y185335D01*
X951090D01*
Y185535D01*
G37*
G36*
G01X952790D02*
X952930Y185935D01*
X953350D01*
X953490Y185535D01*
Y185335D01*
X952790D01*
Y185535D01*
G37*
G36*
G01X949240Y185135D02*
X949100Y184735D01*
X948680D01*
X948540Y185135D01*
Y185335D01*
X949240D01*
Y185135D01*
G37*
G36*
G01X950940D02*
X950800Y184735D01*
X950380D01*
X950240Y185135D01*
Y185335D01*
X950940D01*
Y185135D01*
G37*
G36*
G01X952640D02*
X952500Y184735D01*
X952080D01*
X951940Y185135D01*
Y185335D01*
X952640D01*
Y185135D01*
G37*
G36*
G01X963559Y194225D02*
X963743Y193844D01*
X963446Y193547D01*
X963064Y193730D01*
X962923Y193872D01*
X963418Y194367D01*
X963559Y194225D01*
G37*
G36*
G01X962180Y193412D02*
X961996Y193794D01*
X962293Y194091D01*
X962675Y193907D01*
X962817Y193766D01*
X962322Y193271D01*
X962180Y193412D01*
G37*
G36*
G01X958751Y189417D02*
X958935Y189035D01*
X958638Y188738D01*
X958256Y188922D01*
X958115Y189064D01*
X958610Y189559D01*
X958751Y189417D01*
G37*
G36*
G01X921488Y182545D02*
X920993Y183110D01*
X921276Y183393D01*
X921841Y182898D01*
X921983Y182757D01*
X921629Y182403D01*
X921488Y182545D01*
G37*
G36*
G01X938250Y185182D02*
X938066Y185564D01*
X938363Y185861D01*
X938745Y185677D01*
X938886Y185535D01*
X938391Y185040D01*
X938250Y185182D01*
G37*
G36*
G01X937897Y183131D02*
X937713Y183513D01*
X938010Y183810D01*
X938392Y183626D01*
X938533Y183484D01*
X938038Y182989D01*
X937897Y183131D01*
G37*
G36*
G01X938074Y182742D02*
X938258Y182360D01*
X937961Y182063D01*
X937579Y182247D01*
X937437Y182388D01*
X937932Y182883D01*
X938074Y182742D01*
G37*
G36*
G01X936872Y181540D02*
X937056Y181158D01*
X936759Y180861D01*
X936377Y181045D01*
X936235Y181186D01*
X936730Y181681D01*
X936872Y181540D01*
G37*
G36*
G01X936695Y181929D02*
X936511Y182311D01*
X936808Y182608D01*
X937190Y182424D01*
X937331Y182282D01*
X936836Y181787D01*
X936695Y181929D01*
G37*
G36*
G01X939276Y183944D02*
X939460Y183562D01*
X939163Y183265D01*
X938781Y183449D01*
X938639Y183590D01*
X939134Y184085D01*
X939276Y183944D01*
G37*
G36*
G01X940740Y183935D02*
X940600Y183535D01*
X940180D01*
X940040Y183935D01*
Y184135D01*
X940740D01*
Y183935D01*
G37*
G36*
G01X934740Y180785D02*
X934690Y180035D01*
X934290D01*
X934240Y180785D01*
Y180985D01*
X934740D01*
Y180785D01*
G37*
G36*
G01X932940Y181185D02*
X932990Y181935D01*
X933390D01*
X933440Y181185D01*
Y180985D01*
X932940D01*
Y181185D01*
G37*
G36*
G01X925140D02*
X925190Y181935D01*
X925590D01*
X925640Y181185D01*
Y180985D01*
X925140D01*
Y181185D01*
G37*
G36*
G01X927740D02*
X927790Y181935D01*
X928190D01*
X928240Y181185D01*
Y180985D01*
X927740D01*
Y181185D01*
G37*
G36*
G01X930340D02*
X930390Y181935D01*
X930790D01*
X930840Y181185D01*
Y180985D01*
X930340D01*
Y181185D01*
G37*
G36*
G01X929540Y180785D02*
X929490Y180035D01*
X929090D01*
X929040Y180785D01*
Y180985D01*
X929540D01*
Y180785D01*
G37*
G36*
G01X926940D02*
X926890Y180035D01*
X926490D01*
X926440Y180785D01*
Y180985D01*
X926940D01*
Y180785D01*
G37*
G36*
G01X924340D02*
X924290Y180035D01*
X923890D01*
X923840Y180785D01*
Y180985D01*
X924340D01*
Y180785D01*
G37*
G36*
G01X932140D02*
X932090Y180035D01*
X931690D01*
X931640Y180785D01*
Y180985D01*
X932140D01*
Y180785D01*
G37*
G36*
G01X920744Y179608D02*
X920249Y180174D01*
X920532Y180457D01*
X921098Y179962D01*
X921239Y179820D01*
X920886Y179467D01*
X920744Y179608D01*
G37*
G36*
G01X922540Y181185D02*
X922590Y181935D01*
X922990D01*
X923040Y181185D01*
Y180985D01*
X922540D01*
Y181185D01*
G37*
G36*
G01X922301Y180599D02*
X922796Y180033D01*
X922514Y179750D01*
X921948Y180245D01*
X921806Y180386D01*
X922160Y180740D01*
X922301Y180599D01*
G37*
G36*
G01X920462Y178759D02*
X920957Y178193D01*
X920675Y177910D01*
X920109Y178405D01*
X919967Y178546D01*
X920321Y178900D01*
X920462Y178759D01*
G37*
G36*
G01X947540Y183935D02*
X947400Y183535D01*
X946980D01*
X946840Y183935D01*
Y184135D01*
X947540D01*
Y183935D01*
G37*
G36*
G01X945990Y184335D02*
X946130Y184735D01*
X946550D01*
X946690Y184335D01*
Y184135D01*
X945990D01*
Y184335D01*
G37*
G36*
G01X945840Y183935D02*
X945700Y183535D01*
X945280D01*
X945140Y183935D01*
Y184135D01*
X945840D01*
Y183935D01*
G37*
G36*
G01X944140D02*
X944000Y183535D01*
X943580D01*
X943440Y183935D01*
Y184135D01*
X944140D01*
Y183935D01*
G37*
G36*
G01X942440D02*
X942300Y183535D01*
X941880D01*
X941740Y183935D01*
Y184135D01*
X942440D01*
Y183935D01*
G37*
G36*
G01X944290Y184335D02*
X944430Y184735D01*
X944850D01*
X944990Y184335D01*
Y184135D01*
X944290D01*
Y184335D01*
G37*
G36*
G01X942590D02*
X942730Y184735D01*
X943150D01*
X943290Y184335D01*
Y184135D01*
X942590D01*
Y184335D01*
G37*
G36*
G01X940890D02*
X941030Y184735D01*
X941450D01*
X941590Y184335D01*
Y184135D01*
X940890D01*
Y184335D01*
G37*
G36*
G01X957196Y186164D02*
X957380Y185782D01*
X957083Y185485D01*
X956701Y185669D01*
X956559Y185810D01*
X957054Y186305D01*
X957196Y186164D01*
G37*
G36*
G01X955994Y184962D02*
X956178Y184580D01*
X955881Y184283D01*
X955499Y184467D01*
X955357Y184608D01*
X955852Y185103D01*
X955994Y184962D01*
G37*
G36*
G01X959600Y188568D02*
X959784Y188186D01*
X959487Y187889D01*
X959105Y188073D01*
X958964Y188215D01*
X959459Y188710D01*
X959600Y188568D01*
G37*
G36*
G01X960802Y189770D02*
X960986Y189388D01*
X960689Y189091D01*
X960307Y189275D01*
X960166Y189417D01*
X960661Y189912D01*
X960802Y189770D01*
G37*
G36*
G01X962004Y190972D02*
X962188Y190590D01*
X961891Y190293D01*
X961509Y190477D01*
X961368Y190619D01*
X961863Y191114D01*
X962004Y190972D01*
G37*
G36*
G01X963206Y192174D02*
X963390Y191793D01*
X963093Y191496D01*
X962711Y191679D01*
X962570Y191821D01*
X963065Y192316D01*
X963206Y192174D01*
G37*
G36*
G01X964408Y193376D02*
X964592Y192995D01*
X964295Y192698D01*
X963913Y192881D01*
X963772Y193023D01*
X964267Y193518D01*
X964408Y193376D01*
G37*
G36*
G01X958221Y187755D02*
X958037Y188137D01*
X958334Y188434D01*
X958716Y188250D01*
X958857Y188108D01*
X958363Y187614D01*
X958221Y187755D01*
G37*
G36*
G01X957019Y186553D02*
X956835Y186935D01*
X957132Y187232D01*
X957514Y187048D01*
X957655Y186906D01*
X957160Y186411D01*
X957019Y186553D01*
G37*
G36*
G01X955817Y185351D02*
X955633Y185733D01*
X955930Y186030D01*
X956312Y185846D01*
X956453Y185704D01*
X955958Y185209D01*
X955817Y185351D01*
G37*
G36*
G01X959423Y188957D02*
X959239Y189339D01*
X959536Y189636D01*
X959918Y189452D01*
X960060Y189311D01*
X959565Y188816D01*
X959423Y188957D01*
G37*
G36*
G01X960625Y190159D02*
X960441Y190541D01*
X960738Y190838D01*
X961120Y190654D01*
X961262Y190513D01*
X960767Y190018D01*
X960625Y190159D01*
G37*
G36*
G01X961827Y191361D02*
X961643Y191743D01*
X961940Y192040D01*
X962322Y191856D01*
X962464Y191715D01*
X961969Y191220D01*
X961827Y191361D01*
G37*
G36*
G01X963029Y192563D02*
X962846Y192945D01*
X963143Y193242D01*
X963524Y193058D01*
X963666Y192917D01*
X963171Y192422D01*
X963029Y192563D01*
G37*
G36*
G01X964231Y193765D02*
X964048Y194147D01*
X964345Y194444D01*
X964726Y194260D01*
X964868Y194119D01*
X964373Y193624D01*
X964231Y193765D01*
G37*
G36*
G01X949240Y183935D02*
X949100Y183535D01*
X948680D01*
X948540Y183935D01*
Y184135D01*
X949240D01*
Y183935D01*
G37*
G36*
G01X950940D02*
X950800Y183535D01*
X950380D01*
X950240Y183935D01*
Y184135D01*
X950940D01*
Y183935D01*
G37*
G36*
G01X952640D02*
X952500Y183535D01*
X952080D01*
X951940Y183935D01*
Y184135D01*
X952640D01*
Y183935D01*
G37*
G36*
G01X954340D02*
X954200Y183535D01*
X953780D01*
X953640Y183935D01*
Y184135D01*
X954340D01*
Y183935D01*
G37*
G36*
G01X947690Y184335D02*
X947830Y184735D01*
X948250D01*
X948390Y184335D01*
Y184135D01*
X947690D01*
Y184335D01*
G37*
G36*
G01X949390D02*
X949530Y184735D01*
X949950D01*
X950090Y184335D01*
Y184135D01*
X949390D01*
Y184335D01*
G37*
G36*
G01X951090D02*
X951230Y184735D01*
X951650D01*
X951790Y184335D01*
Y184135D01*
X951090D01*
Y184335D01*
G37*
G36*
G01X952790D02*
X952930Y184735D01*
X953350D01*
X953490Y184335D01*
Y184135D01*
X952790D01*
Y184335D01*
G37*
G36*
G01X958398Y187366D02*
X958582Y186984D01*
X958285Y186687D01*
X957903Y186871D01*
X957761Y187012D01*
X958256Y187507D01*
X958398Y187366D01*
G37*
G36*
G01X937082Y188542D02*
X937266Y188160D01*
X936969Y187863D01*
X936587Y188047D01*
X936445Y188188D01*
X936940Y188683D01*
X937082Y188542D01*
G37*
G36*
G01X935703Y187729D02*
X935519Y188111D01*
X935816Y188408D01*
X936198Y188224D01*
X936339Y188082D01*
X935844Y187587D01*
X935703Y187729D01*
G37*
G36*
G01X934740Y186985D02*
X934690Y186235D01*
X934290D01*
X934240Y186985D01*
Y187185D01*
X934740D01*
Y186985D01*
G37*
G36*
G01X939190Y189135D02*
X939330Y189535D01*
X939750D01*
X939890Y189135D01*
Y188935D01*
X939190D01*
Y189135D01*
G37*
G36*
G01X939040Y188735D02*
X938900Y188335D01*
X938480D01*
X938340Y188735D01*
Y188935D01*
X939040D01*
Y188735D01*
G37*
G36*
G01X940740D02*
X940600Y188335D01*
X940180D01*
X940040Y188735D01*
Y188935D01*
X940740D01*
Y188735D01*
G37*
G36*
G01X916074Y183144D02*
X916569Y182578D01*
X916286Y182296D01*
X915720Y182791D01*
X915579Y182932D01*
X915933Y183286D01*
X916074Y183144D01*
G37*
G36*
G01X932940Y187385D02*
X932990Y188135D01*
X933390D01*
X933440Y187385D01*
Y187185D01*
X932940D01*
Y187385D01*
G37*
G36*
G01X925140D02*
X925190Y188135D01*
X925590D01*
X925640Y187385D01*
Y187185D01*
X925140D01*
Y187385D01*
G37*
G36*
G01X922540D02*
X922590Y188135D01*
X922990D01*
X923040Y187385D01*
Y187185D01*
X922540D01*
Y187385D01*
G37*
G36*
G01X927740D02*
X927790Y188135D01*
X928190D01*
X928240Y187385D01*
Y187185D01*
X927740D01*
Y187385D01*
G37*
G36*
G01X930340D02*
X930390Y188135D01*
X930790D01*
X930840Y187385D01*
Y187185D01*
X930340D01*
Y187385D01*
G37*
G36*
G01X926940Y186985D02*
X926890Y186235D01*
X926490D01*
X926440Y186985D01*
Y187185D01*
X926940D01*
Y186985D01*
G37*
G36*
G01X924340D02*
X924290Y186235D01*
X923890D01*
X923840Y186985D01*
Y187185D01*
X924340D01*
Y186985D01*
G37*
G36*
G01X921740D02*
X921690Y186235D01*
X921290D01*
X921240Y186985D01*
Y187185D01*
X921740D01*
Y186985D01*
G37*
G36*
G01X929540D02*
X929490Y186235D01*
X929090D01*
X929040Y186985D01*
Y187185D01*
X929540D01*
Y186985D01*
G37*
G36*
G01X932140D02*
X932090Y186235D01*
X931690D01*
X931640Y186985D01*
Y187185D01*
X932140D01*
Y186985D01*
G37*
G36*
G01X917914Y184984D02*
X918409Y184418D01*
X918126Y184136D01*
X917560Y184631D01*
X917419Y184772D01*
X917773Y185126D01*
X917914Y184984D01*
G37*
G36*
G01X916358Y183994D02*
X915863Y184560D01*
X916146Y184843D01*
X916712Y184348D01*
X916853Y184206D01*
X916500Y183853D01*
X916358Y183994D01*
G37*
G36*
G01X918197Y185833D02*
X917702Y186398D01*
X917985Y186681D01*
X918550Y186186D01*
X918692Y186045D01*
X918338Y185691D01*
X918197Y185833D01*
G37*
G36*
G01X919940Y187385D02*
X919990Y188135D01*
X920390D01*
X920440Y187385D01*
Y187185D01*
X919940D01*
Y187385D01*
G37*
G36*
G01X919754Y186824D02*
X920249Y186258D01*
X919966Y185976D01*
X919400Y186471D01*
X919259Y186612D01*
X919613Y186966D01*
X919754Y186824D01*
G37*
G36*
G01X947540Y188735D02*
X947400Y188335D01*
X946980D01*
X946840Y188735D01*
Y188935D01*
X947540D01*
Y188735D01*
G37*
G36*
G01X945990Y189135D02*
X946130Y189535D01*
X946550D01*
X946690Y189135D01*
Y188935D01*
X945990D01*
Y189135D01*
G37*
G36*
G01X942590D02*
X942730Y189535D01*
X943150D01*
X943290Y189135D01*
Y188935D01*
X942590D01*
Y189135D01*
G37*
G36*
G01X940890D02*
X941030Y189535D01*
X941450D01*
X941590Y189135D01*
Y188935D01*
X940890D01*
Y189135D01*
G37*
G36*
G01X944290D02*
X944430Y189535D01*
X944850D01*
X944990Y189135D01*
Y188935D01*
X944290D01*
Y189135D01*
G37*
G36*
G01X942440Y188735D02*
X942300Y188335D01*
X941880D01*
X941740Y188735D01*
Y188935D01*
X942440D01*
Y188735D01*
G37*
G36*
G01X944140D02*
X944000Y188335D01*
X943580D01*
X943440Y188735D01*
Y188935D01*
X944140D01*
Y188735D01*
G37*
G36*
G01X945840D02*
X945700Y188335D01*
X945280D01*
X945140Y188735D01*
Y188935D01*
X945840D01*
Y188735D01*
G37*
G36*
G01X956204Y191964D02*
X956388Y191582D01*
X956091Y191285D01*
X955709Y191469D01*
X955568Y191611D01*
X956063Y192106D01*
X956204Y191964D01*
G37*
G36*
G01X957406Y193166D02*
X957590Y192784D01*
X957293Y192487D01*
X956911Y192671D01*
X956770Y192813D01*
X957265Y193308D01*
X957406Y193166D01*
G37*
G36*
G01X956027Y192353D02*
X955843Y192735D01*
X956140Y193032D01*
X956522Y192848D01*
X956664Y192707D01*
X956169Y192212D01*
X956027Y192353D01*
G37*
G36*
G01X947690Y189135D02*
X947830Y189535D01*
X948250D01*
X948390Y189135D01*
Y188935D01*
X947690D01*
Y189135D01*
G37*
G36*
G01X949390D02*
X949530Y189535D01*
X949950D01*
X950090Y189135D01*
Y188935D01*
X949390D01*
Y189135D01*
G37*
G36*
G01X951090D02*
X951230Y189535D01*
X951650D01*
X951790Y189135D01*
Y188935D01*
X951090D01*
Y189135D01*
G37*
G36*
G01X949240Y188735D02*
X949100Y188335D01*
X948680D01*
X948540Y188735D01*
Y188935D01*
X949240D01*
Y188735D01*
G37*
G36*
G01X950940D02*
X950800Y188335D01*
X950380D01*
X950240Y188735D01*
Y188935D01*
X950940D01*
Y188735D01*
G37*
G36*
G01X955002Y190762D02*
X955186Y190380D01*
X954889Y190083D01*
X954507Y190267D01*
X954365Y190408D01*
X954860Y190903D01*
X955002Y190762D01*
G37*
G36*
G01X953623Y189949D02*
X953439Y190331D01*
X953736Y190628D01*
X954118Y190444D01*
X954259Y190302D01*
X953764Y189807D01*
X953623Y189949D01*
G37*
G36*
G01X954825Y191151D02*
X954641Y191533D01*
X954938Y191830D01*
X955320Y191646D01*
X955461Y191504D01*
X954967Y191010D01*
X954825Y191151D01*
G37*
G36*
G01X953800Y189560D02*
X953984Y189178D01*
X953687Y188881D01*
X953305Y189065D01*
X953163Y189206D01*
X953658Y189701D01*
X953800Y189560D01*
G37*
G36*
G01X952640Y188735D02*
X952500Y188335D01*
X952080D01*
X951940Y188735D01*
Y188935D01*
X952640D01*
Y188735D01*
G37*
G36*
G01X935880Y187340D02*
X936064Y186958D01*
X935767Y186661D01*
X935385Y186845D01*
X935243Y186986D01*
X935738Y187481D01*
X935880Y187340D01*
G37*
G36*
G01X967109Y179517D02*
X966926Y179899D01*
X967223Y180196D01*
X967604Y180012D01*
X967746Y179871D01*
X967251Y179376D01*
X967109Y179517D01*
G37*
G36*
G01X968312Y180719D02*
X968128Y181101D01*
X968425Y181398D01*
X968807Y181214D01*
X968948Y181073D01*
X968453Y180578D01*
X968312Y180719D01*
G37*
G36*
G01X968488Y180330D02*
X968672Y179949D01*
X968375Y179652D01*
X967993Y179836D01*
X967852Y179977D01*
X968347Y180472D01*
X968488Y180330D01*
G37*
G36*
G01X967286Y179128D02*
X967470Y178747D01*
X967173Y178450D01*
X966791Y178633D01*
X966650Y178775D01*
X967145Y179270D01*
X967286Y179128D01*
G37*
G36*
G01X969690Y181533D02*
X969874Y181151D01*
X969577Y180854D01*
X969195Y181038D01*
X969054Y181179D01*
X969549Y181674D01*
X969690Y181533D01*
G37*
G36*
G01X965907Y178315D02*
X965724Y178697D01*
X966021Y178994D01*
X966402Y178810D01*
X966544Y178669D01*
X966049Y178174D01*
X965907Y178315D01*
G37*
G36*
G01X970716Y183124D02*
X970532Y183505D01*
X970829Y183802D01*
X971211Y183619D01*
X971352Y183477D01*
X970857Y182982D01*
X970716Y183124D01*
G37*
G36*
G01X970892Y182735D02*
X971076Y182353D01*
X970779Y182056D01*
X970398Y182240D01*
X970256Y182381D01*
X970751Y182876D01*
X970892Y182735D01*
G37*
G36*
G01X969514Y181921D02*
X969330Y182303D01*
X969627Y182600D01*
X970009Y182416D01*
X970150Y182275D01*
X969655Y181780D01*
X969514Y181921D01*
G37*
G36*
G01X972095Y183937D02*
X972278Y183555D01*
X971981Y183258D01*
X971600Y183442D01*
X971458Y183583D01*
X971953Y184078D01*
X972095Y183937D01*
G37*
G36*
G01X957072Y172299D02*
X956577Y172864D01*
X956860Y173147D01*
X957425Y172652D01*
X957567Y172511D01*
X957213Y172157D01*
X957072Y172299D01*
G37*
G36*
G01X960638Y173191D02*
X960498Y172791D01*
X960078D01*
X959938Y173191D01*
Y173391D01*
X960638D01*
Y173191D01*
G37*
G36*
G01X964705Y177113D02*
X964521Y177495D01*
X964818Y177792D01*
X965200Y177608D01*
X965342Y177467D01*
X964847Y176972D01*
X964705Y177113D01*
G37*
G36*
G01X963503Y175911D02*
X963319Y176293D01*
X963616Y176590D01*
X963998Y176406D01*
X964140Y176265D01*
X963645Y175770D01*
X963503Y175911D01*
G37*
G36*
G01X962301Y174709D02*
X962117Y175091D01*
X962414Y175388D01*
X962796Y175204D01*
X962938Y175063D01*
X962443Y174568D01*
X962301Y174709D01*
G37*
G36*
G01X966084Y177926D02*
X966268Y177544D01*
X965971Y177247D01*
X965589Y177431D01*
X965448Y177573D01*
X965943Y178068D01*
X966084Y177926D01*
G37*
G36*
G01X964882Y176724D02*
X965066Y176342D01*
X964769Y176045D01*
X964387Y176229D01*
X964246Y176371D01*
X964741Y176866D01*
X964882Y176724D01*
G37*
G36*
G01X959088Y173591D02*
X959228Y173991D01*
X959648D01*
X959788Y173591D01*
Y173391D01*
X959088D01*
Y173591D01*
G37*
G36*
G01X962478Y174320D02*
X962662Y173938D01*
X962365Y173641D01*
X961983Y173825D01*
X961842Y173967D01*
X962337Y174462D01*
X962478Y174320D01*
G37*
G36*
G01X963680Y175522D02*
X963864Y175140D01*
X963567Y174843D01*
X963185Y175027D01*
X963044Y175169D01*
X963539Y175664D01*
X963680Y175522D01*
G37*
G36*
G01X956789Y171450D02*
X957284Y170884D01*
X957001Y170602D01*
X956435Y171097D01*
X956294Y171238D01*
X956648Y171592D01*
X956789Y171450D01*
G37*
G36*
G01X952548Y170392D02*
X952598Y171142D01*
X952998D01*
X953048Y170392D01*
Y170192D01*
X952548D01*
Y170392D01*
G37*
G36*
G01X955233Y170460D02*
X954738Y171026D01*
X955021Y171309D01*
X955587Y170814D01*
X955728Y170672D01*
X955375Y170319D01*
X955233Y170460D01*
G37*
G36*
G01X954348Y169992D02*
X954298Y169242D01*
X953898D01*
X953848Y169992D01*
Y170192D01*
X954348D01*
Y169992D01*
G37*
G36*
G01X951748D02*
X951698Y169242D01*
X951298D01*
X951248Y169992D01*
Y170192D01*
X951748D01*
Y169992D01*
G37*
G36*
G01X949848Y170392D02*
X949898Y171142D01*
X950298D01*
X950348Y170392D01*
Y170192D01*
X949848D01*
Y170392D01*
G37*
G36*
G01X936552Y186880D02*
X936368Y187262D01*
X936665Y187559D01*
X937047Y187375D01*
X937188Y187233D01*
X936693Y186738D01*
X936552Y186880D01*
G37*
G36*
G01X936729Y186491D02*
X936913Y186109D01*
X936616Y185812D01*
X936234Y185996D01*
X936092Y186137D01*
X936587Y186632D01*
X936729Y186491D01*
G37*
G36*
G01X934740Y185435D02*
X934690Y184685D01*
X934290D01*
X934240Y185435D01*
Y185635D01*
X934740D01*
Y185435D01*
G37*
G36*
G01X939040Y187535D02*
X938900Y187135D01*
X938480D01*
X938340Y187535D01*
Y187735D01*
X939040D01*
Y187535D01*
G37*
G36*
G01X939190Y187935D02*
X939330Y188335D01*
X939750D01*
X939890Y187935D01*
Y187735D01*
X939190D01*
Y187935D01*
G37*
G36*
G01X940740Y187535D02*
X940600Y187135D01*
X940180D01*
X940040Y187535D01*
Y187735D01*
X940740D01*
Y187535D01*
G37*
G36*
G01X915615Y181058D02*
X915120Y181623D01*
X915403Y181906D01*
X915968Y181411D01*
X916110Y181270D01*
X915756Y180916D01*
X915615Y181058D01*
G37*
G36*
G01X917172Y182049D02*
X917667Y181483D01*
X917384Y181201D01*
X916818Y181696D01*
X916677Y181837D01*
X917031Y182191D01*
X917172Y182049D01*
G37*
G36*
G01X919010Y183888D02*
X919505Y183322D01*
X919223Y183039D01*
X918657Y183534D01*
X918515Y183675D01*
X918869Y184029D01*
X919010Y183888D01*
G37*
G36*
G01X917455Y182898D02*
X916960Y183463D01*
X917243Y183746D01*
X917808Y183251D01*
X917950Y183110D01*
X917596Y182756D01*
X917455Y182898D01*
G37*
G36*
G01X932940Y185835D02*
X932990Y186585D01*
X933390D01*
X933440Y185835D01*
Y185635D01*
X932940D01*
Y185835D01*
G37*
G36*
G01X925140D02*
X925190Y186585D01*
X925590D01*
X925640Y185835D01*
Y185635D01*
X925140D01*
Y185835D01*
G37*
G36*
G01X922540D02*
X922590Y186585D01*
X922990D01*
X923040Y185835D01*
Y185635D01*
X922540D01*
Y185835D01*
G37*
G36*
G01X927740D02*
X927790Y186585D01*
X928190D01*
X928240Y185835D01*
Y185635D01*
X927740D01*
Y185835D01*
G37*
G36*
G01X930340D02*
X930390Y186585D01*
X930790D01*
X930840Y185835D01*
Y185635D01*
X930340D01*
Y185835D01*
G37*
G36*
G01X926940Y185435D02*
X926890Y184685D01*
X926490D01*
X926440Y185435D01*
Y185635D01*
X926940D01*
Y185435D01*
G37*
G36*
G01X924340D02*
X924290Y184685D01*
X923890D01*
X923840Y185435D01*
Y185635D01*
X924340D01*
Y185435D01*
G37*
G36*
G01X929540D02*
X929490Y184685D01*
X929090D01*
X929040Y185435D01*
Y185635D01*
X929540D01*
Y185435D01*
G37*
G36*
G01X932140D02*
X932090Y184685D01*
X931690D01*
X931640Y185435D01*
Y185635D01*
X932140D01*
Y185435D01*
G37*
G36*
G01X919295Y184738D02*
X918800Y185303D01*
X919083Y185586D01*
X919648Y185091D01*
X919790Y184950D01*
X919436Y184596D01*
X919295Y184738D01*
G37*
G36*
G01X921740Y185435D02*
X921690Y184685D01*
X921290D01*
X921240Y185435D01*
Y185635D01*
X921740D01*
Y185435D01*
G37*
G36*
G01X947540Y187535D02*
X947400Y187135D01*
X946980D01*
X946840Y187535D01*
Y187735D01*
X947540D01*
Y187535D01*
G37*
G36*
G01X945990Y187935D02*
X946130Y188335D01*
X946550D01*
X946690Y187935D01*
Y187735D01*
X945990D01*
Y187935D01*
G37*
G36*
G01X944140Y187535D02*
X944000Y187135D01*
X943580D01*
X943440Y187535D01*
Y187735D01*
X944140D01*
Y187535D01*
G37*
G36*
G01X942440D02*
X942300Y187135D01*
X941880D01*
X941740Y187535D01*
Y187735D01*
X942440D01*
Y187535D01*
G37*
G36*
G01X944290Y187935D02*
X944430Y188335D01*
X944850D01*
X944990Y187935D01*
Y187735D01*
X944290D01*
Y187935D01*
G37*
G36*
G01X942590D02*
X942730Y188335D01*
X943150D01*
X943290Y187935D01*
Y187735D01*
X942590D01*
Y187935D01*
G37*
G36*
G01X940890D02*
X941030Y188335D01*
X941450D01*
X941590Y187935D01*
Y187735D01*
X940890D01*
Y187935D01*
G37*
G36*
G01X945840Y187535D02*
X945700Y187135D01*
X945280D01*
X945140Y187535D01*
Y187735D01*
X945840D01*
Y187535D01*
G37*
G36*
G01X958255Y192317D02*
X958439Y191935D01*
X958142Y191638D01*
X957760Y191822D01*
X957619Y191964D01*
X958114Y192459D01*
X958255Y192317D01*
G37*
G36*
G01X958078Y192706D02*
X957894Y193088D01*
X958191Y193385D01*
X958573Y193201D01*
X958715Y193060D01*
X958220Y192565D01*
X958078Y192706D01*
G37*
G36*
G01X957053Y191115D02*
X957237Y190733D01*
X956940Y190436D01*
X956558Y190620D01*
X956417Y190762D01*
X956912Y191257D01*
X957053Y191115D01*
G37*
G36*
G01X955851Y189913D02*
X956035Y189531D01*
X955738Y189234D01*
X955356Y189418D01*
X955214Y189559D01*
X955709Y190054D01*
X955851Y189913D01*
G37*
G36*
G01X956876Y191504D02*
X956692Y191886D01*
X956989Y192183D01*
X957371Y191999D01*
X957513Y191858D01*
X957018Y191363D01*
X956876Y191504D01*
G37*
G36*
G01X955674Y190302D02*
X955490Y190684D01*
X955787Y190981D01*
X956169Y190797D01*
X956310Y190655D01*
X955816Y190161D01*
X955674Y190302D01*
G37*
G36*
G01X954649Y188711D02*
X954833Y188329D01*
X954536Y188032D01*
X954154Y188216D01*
X954012Y188357D01*
X954507Y188852D01*
X954649Y188711D01*
G37*
G36*
G01X954472Y189100D02*
X954288Y189482D01*
X954585Y189779D01*
X954967Y189595D01*
X955108Y189453D01*
X954613Y188958D01*
X954472Y189100D01*
G37*
G36*
G01X947690Y187935D02*
X947830Y188335D01*
X948250D01*
X948390Y187935D01*
Y187735D01*
X947690D01*
Y187935D01*
G37*
G36*
G01X949390D02*
X949530Y188335D01*
X949950D01*
X950090Y187935D01*
Y187735D01*
X949390D01*
Y187935D01*
G37*
G36*
G01X951090D02*
X951230Y188335D01*
X951650D01*
X951790Y187935D01*
Y187735D01*
X951090D01*
Y187935D01*
G37*
G36*
G01X949240Y187535D02*
X949100Y187135D01*
X948680D01*
X948540Y187535D01*
Y187735D01*
X949240D01*
Y187535D01*
G37*
G36*
G01X950940D02*
X950800Y187135D01*
X950380D01*
X950240Y187535D01*
Y187735D01*
X950940D01*
Y187535D01*
G37*
G36*
G01X952640D02*
X952500Y187135D01*
X952080D01*
X951940Y187535D01*
Y187735D01*
X952640D01*
Y187535D01*
G37*
G36*
G01X957854Y204291D02*
X957156Y204581D01*
X957080Y205448D01*
X957717Y205855D01*
X957892Y205870D01*
X958028Y204306D01*
X957854Y204291D01*
G37*
G36*
G01X969161Y179870D02*
X968977Y180252D01*
X969274Y180549D01*
X969656Y180365D01*
X969797Y180224D01*
X969302Y179729D01*
X969161Y179870D01*
G37*
G36*
G01X969337Y179481D02*
X969521Y179100D01*
X969224Y178803D01*
X968842Y178987D01*
X968701Y179128D01*
X969196Y179623D01*
X969337Y179481D01*
G37*
G36*
G01X967958Y178668D02*
X967775Y179050D01*
X968072Y179347D01*
X968453Y179163D01*
X968595Y179022D01*
X968100Y178527D01*
X967958Y178668D01*
G37*
G36*
G01X971741Y181886D02*
X971925Y181504D01*
X971628Y181207D01*
X971247Y181391D01*
X971105Y181532D01*
X971600Y182027D01*
X971741Y181886D01*
G37*
G36*
G01X970363Y181072D02*
X970179Y181454D01*
X970476Y181751D01*
X970858Y181567D01*
X970999Y181426D01*
X970504Y180931D01*
X970363Y181072D01*
G37*
G36*
G01X970539Y180684D02*
X970723Y180302D01*
X970426Y180005D01*
X970044Y180189D01*
X969903Y180330D01*
X970398Y180825D01*
X970539Y180684D01*
G37*
G36*
G01X971565Y182275D02*
X971381Y182656D01*
X971678Y182953D01*
X972060Y182770D01*
X972201Y182628D01*
X971706Y182133D01*
X971565Y182275D01*
G37*
G36*
G01X963327Y173471D02*
X963511Y173089D01*
X963214Y172792D01*
X962832Y172976D01*
X962691Y173118D01*
X963185Y173612D01*
X963327Y173471D01*
G37*
G36*
G01X961948Y172658D02*
X961764Y173040D01*
X962061Y173337D01*
X962443Y173153D01*
X962585Y173012D01*
X962090Y172517D01*
X961948Y172658D01*
G37*
G36*
G01X960788Y172391D02*
X960928Y172791D01*
X961348D01*
X961488Y172391D01*
Y172191D01*
X960788D01*
Y172391D01*
G37*
G36*
G01X968135Y178279D02*
X968319Y177898D01*
X968022Y177601D01*
X967640Y177784D01*
X967499Y177926D01*
X967994Y178421D01*
X968135Y178279D01*
G37*
G36*
G01X966756Y177466D02*
X966573Y177848D01*
X966870Y178145D01*
X967251Y177961D01*
X967393Y177820D01*
X966898Y177325D01*
X966756Y177466D01*
G37*
G36*
G01X966933Y177077D02*
X967117Y176695D01*
X966820Y176398D01*
X966438Y176582D01*
X966297Y176724D01*
X966792Y177219D01*
X966933Y177077D01*
G37*
G36*
G01X965554Y176264D02*
X965370Y176646D01*
X965667Y176943D01*
X966049Y176759D01*
X966191Y176618D01*
X965696Y176123D01*
X965554Y176264D01*
G37*
G36*
G01X965731Y175875D02*
X965915Y175493D01*
X965618Y175196D01*
X965236Y175380D01*
X965095Y175522D01*
X965590Y176017D01*
X965731Y175875D01*
G37*
G36*
G01X964352Y175062D02*
X964168Y175444D01*
X964465Y175741D01*
X964847Y175557D01*
X964989Y175416D01*
X964494Y174921D01*
X964352Y175062D01*
G37*
G36*
G01X964529Y174673D02*
X964713Y174291D01*
X964416Y173994D01*
X964034Y174178D01*
X963893Y174320D01*
X964388Y174815D01*
X964529Y174673D01*
G37*
G36*
G01X963150Y173860D02*
X962966Y174242D01*
X963263Y174539D01*
X963645Y174355D01*
X963787Y174214D01*
X963292Y173719D01*
X963150Y173860D01*
G37*
G36*
G01X960638Y171991D02*
X960498Y171591D01*
X960078D01*
X959938Y171991D01*
Y172191D01*
X960638D01*
Y171991D01*
G37*
G36*
G01X958168Y171203D02*
X957673Y171768D01*
X957956Y172051D01*
X958521Y171556D01*
X958663Y171415D01*
X958309Y171061D01*
X958168Y171203D01*
G37*
G36*
G01X957885Y170354D02*
X958380Y169788D01*
X958097Y169506D01*
X957531Y170001D01*
X957390Y170142D01*
X957744Y170496D01*
X957885Y170354D01*
G37*
G36*
G01X956329Y169364D02*
X955834Y169930D01*
X956117Y170213D01*
X956683Y169718D01*
X956824Y169576D01*
X956471Y169223D01*
X956329Y169364D01*
G37*
G36*
G01X955148Y168842D02*
X955198Y169592D01*
X955598D01*
X955648Y168842D01*
Y168642D01*
X955148D01*
Y168842D01*
G37*
G36*
G01X954348Y168442D02*
X954298Y167692D01*
X953898D01*
X953848Y168442D01*
Y168642D01*
X954348D01*
Y168442D01*
G37*
G36*
G01X952548Y168842D02*
X952598Y169592D01*
X952998D01*
X953048Y168842D01*
Y168642D01*
X952548D01*
Y168842D01*
G37*
G36*
G01X951748Y168442D02*
X951698Y167692D01*
X951298D01*
X951248Y168442D01*
Y168642D01*
X951748D01*
Y168442D01*
G37*
G36*
G01X937490Y190335D02*
X937630Y190735D01*
X938050D01*
X938190Y190335D01*
Y190135D01*
X937490D01*
Y190335D01*
G37*
G36*
G01X936056Y189780D02*
X935872Y190162D01*
X936169Y190459D01*
X936551Y190275D01*
X936692Y190133D01*
X936197Y189638D01*
X936056Y189780D01*
G37*
G36*
G01X936233Y189391D02*
X936417Y189009D01*
X936120Y188712D01*
X935738Y188896D01*
X935596Y189037D01*
X936091Y189532D01*
X936233Y189391D01*
G37*
G36*
G01X934740Y188535D02*
X934690Y187785D01*
X934290D01*
X934240Y188535D01*
Y188735D01*
X934740D01*
Y188535D01*
G37*
G36*
G01X939190Y190335D02*
X939330Y190735D01*
X939750D01*
X939890Y190335D01*
Y190135D01*
X939190D01*
Y190335D01*
G37*
G36*
G01X939040Y189935D02*
X938900Y189535D01*
X938480D01*
X938340Y189935D01*
Y190135D01*
X939040D01*
Y189935D01*
G37*
G36*
G01X940740D02*
X940600Y189535D01*
X940180D01*
X940040Y189935D01*
Y190135D01*
X940740D01*
Y189935D01*
G37*
G36*
G01X915262Y185091D02*
X914767Y185656D01*
X915050Y185939D01*
X915615Y185444D01*
X915757Y185303D01*
X915403Y184949D01*
X915262Y185091D01*
G37*
G36*
G01X932940Y188935D02*
X932990Y189685D01*
X933390D01*
X933440Y188935D01*
Y188735D01*
X932940D01*
Y188935D01*
G37*
G36*
G01X925140D02*
X925190Y189685D01*
X925590D01*
X925640Y188935D01*
Y188735D01*
X925140D01*
Y188935D01*
G37*
G36*
G01X922540D02*
X922590Y189685D01*
X922990D01*
X923040Y188935D01*
Y188735D01*
X922540D01*
Y188935D01*
G37*
G36*
G01X927740D02*
X927790Y189685D01*
X928190D01*
X928240Y188935D01*
Y188735D01*
X927740D01*
Y188935D01*
G37*
G36*
G01X930340D02*
X930390Y189685D01*
X930790D01*
X930840Y188935D01*
Y188735D01*
X930340D01*
Y188935D01*
G37*
G36*
G01X926940Y188535D02*
X926890Y187785D01*
X926490D01*
X926440Y188535D01*
Y188735D01*
X926940D01*
Y188535D01*
G37*
G36*
G01X924340D02*
X924290Y187785D01*
X923890D01*
X923840Y188535D01*
Y188735D01*
X924340D01*
Y188535D01*
G37*
G36*
G01X921740D02*
X921690Y187785D01*
X921290D01*
X921240Y188535D01*
Y188735D01*
X921740D01*
Y188535D01*
G37*
G36*
G01X929540D02*
X929490Y187785D01*
X929090D01*
X929040Y188535D01*
Y188735D01*
X929540D01*
Y188535D01*
G37*
G36*
G01X932140D02*
X932090Y187785D01*
X931690D01*
X931640Y188535D01*
Y188735D01*
X932140D01*
Y188535D01*
G37*
G36*
G01X916817Y186081D02*
X917312Y185515D01*
X917030Y185232D01*
X916464Y185727D01*
X916322Y185868D01*
X916676Y186222D01*
X916817Y186081D01*
G37*
G36*
G01X917100Y186929D02*
X916605Y187495D01*
X916888Y187778D01*
X917454Y187283D01*
X917595Y187141D01*
X917242Y186788D01*
X917100Y186929D01*
G37*
G36*
G01X919940Y188935D02*
X919990Y189685D01*
X920390D01*
X920440Y188935D01*
Y188735D01*
X919940D01*
Y188935D01*
G37*
G36*
G01X918657Y187921D02*
X919152Y187355D01*
X918870Y187072D01*
X918304Y187567D01*
X918162Y187708D01*
X918516Y188062D01*
X918657Y187921D01*
G37*
G36*
G01X947540Y189935D02*
X947400Y189535D01*
X946980D01*
X946840Y189935D01*
Y190135D01*
X947540D01*
Y189935D01*
G37*
G36*
G01X945990Y190335D02*
X946130Y190735D01*
X946550D01*
X946690Y190335D01*
Y190135D01*
X945990D01*
Y190335D01*
G37*
G36*
G01X942590D02*
X942730Y190735D01*
X943150D01*
X943290Y190335D01*
Y190135D01*
X942590D01*
Y190335D01*
G37*
G36*
G01X940890D02*
X941030Y190735D01*
X941450D01*
X941590Y190335D01*
Y190135D01*
X940890D01*
Y190335D01*
G37*
G36*
G01X944290D02*
X944430Y190735D01*
X944850D01*
X944990Y190335D01*
Y190135D01*
X944290D01*
Y190335D01*
G37*
G36*
G01X942440Y189935D02*
X942300Y189535D01*
X941880D01*
X941740Y189935D01*
Y190135D01*
X942440D01*
Y189935D01*
G37*
G36*
G01X944140D02*
X944000Y189535D01*
X943580D01*
X943440Y189935D01*
Y190135D01*
X944140D01*
Y189935D01*
G37*
G36*
G01X945840D02*
X945700Y189535D01*
X945280D01*
X945140Y189935D01*
Y190135D01*
X945840D01*
Y189935D01*
G37*
G36*
G01X956557Y194015D02*
X956741Y193633D01*
X956444Y193336D01*
X956062Y193520D01*
X955921Y193662D01*
X956416Y194157D01*
X956557Y194015D01*
G37*
G36*
G01X947690Y190335D02*
X947830Y190735D01*
X948250D01*
X948390Y190335D01*
Y190135D01*
X947690D01*
Y190335D01*
G37*
G36*
G01X949390D02*
X949530Y190735D01*
X949950D01*
X950090Y190335D01*
Y190135D01*
X949390D01*
Y190335D01*
G37*
G36*
G01X951090D02*
X951230Y190735D01*
X951650D01*
X951790Y190335D01*
Y190135D01*
X951090D01*
Y190335D01*
G37*
G36*
G01X949240Y189935D02*
X949100Y189535D01*
X948680D01*
X948540Y189935D01*
Y190135D01*
X949240D01*
Y189935D01*
G37*
G36*
G01X950940D02*
X950800Y189535D01*
X950380D01*
X950240Y189935D01*
Y190135D01*
X950940D01*
Y189935D01*
G37*
G36*
G01X954153Y191611D02*
X954337Y191229D01*
X954040Y190932D01*
X953658Y191116D01*
X953516Y191257D01*
X954011Y191752D01*
X954153Y191611D01*
G37*
G36*
G01X955355Y192813D02*
X955539Y192431D01*
X955242Y192134D01*
X954860Y192318D01*
X954719Y192460D01*
X955214Y192955D01*
X955355Y192813D01*
G37*
G36*
G01X953976Y192000D02*
X953792Y192382D01*
X954089Y192679D01*
X954471Y192495D01*
X954612Y192353D01*
X954118Y191859D01*
X953976Y192000D01*
G37*
G36*
G01X955178Y193202D02*
X954994Y193584D01*
X955291Y193881D01*
X955673Y193697D01*
X955815Y193556D01*
X955320Y193061D01*
X955178Y193202D01*
G37*
G36*
G01X952774Y190798D02*
X952590Y191180D01*
X952887Y191477D01*
X953269Y191293D01*
X953410Y191151D01*
X952916Y190657D01*
X952774Y190798D01*
G37*
G36*
G01X952951Y190409D02*
X953135Y190027D01*
X952838Y189730D01*
X952456Y189914D01*
X952314Y190055D01*
X952809Y190550D01*
X952951Y190409D01*
G37*
G36*
G01X914977Y184241D02*
X915472Y183675D01*
X915190Y183392D01*
X914624Y183887D01*
X914482Y184028D01*
X914836Y184382D01*
X914977Y184241D01*
G37*
G36*
G01X966260Y180366D02*
X966077Y180748D01*
X966374Y181045D01*
X966755Y180861D01*
X966897Y180720D01*
X966402Y180225D01*
X966260Y180366D01*
G37*
G36*
G01X968665Y182770D02*
X968481Y183152D01*
X968778Y183449D01*
X969160Y183265D01*
X969301Y183124D01*
X968806Y182629D01*
X968665Y182770D01*
G37*
G36*
G01X967463Y181568D02*
X967279Y181950D01*
X967576Y182247D01*
X967958Y182063D01*
X968099Y181922D01*
X967604Y181427D01*
X967463Y181568D01*
G37*
G36*
G01X968841Y182382D02*
X969025Y182000D01*
X968728Y181703D01*
X968346Y181887D01*
X968205Y182028D01*
X968700Y182523D01*
X968841Y182382D01*
G37*
G36*
G01X967639Y181179D02*
X967823Y180798D01*
X967526Y180501D01*
X967144Y180685D01*
X967003Y180826D01*
X967498Y181321D01*
X967639Y181179D01*
G37*
G36*
G01X966437Y179977D02*
X966621Y179596D01*
X966324Y179299D01*
X965942Y179482D01*
X965801Y179624D01*
X966296Y180119D01*
X966437Y179977D01*
G37*
G36*
G01X965058Y179164D02*
X964875Y179546D01*
X965172Y179843D01*
X965553Y179659D01*
X965695Y179518D01*
X965200Y179023D01*
X965058Y179164D01*
G37*
G36*
G01X971069Y185175D02*
X970885Y185556D01*
X971182Y185853D01*
X971564Y185670D01*
X971705Y185528D01*
X971210Y185033D01*
X971069Y185175D01*
G37*
G36*
G01X969867Y183973D02*
X969683Y184354D01*
X969980Y184651D01*
X970362Y184468D01*
X970503Y184326D01*
X970008Y183831D01*
X969867Y183973D01*
G37*
G36*
G01X971246Y184786D02*
X971429Y184404D01*
X971132Y184107D01*
X970751Y184291D01*
X970609Y184432D01*
X971104Y184927D01*
X971246Y184786D01*
G37*
G36*
G01X970043Y183584D02*
X970227Y183202D01*
X969930Y182905D01*
X969549Y183089D01*
X969407Y183230D01*
X969902Y183725D01*
X970043Y183584D01*
G37*
G36*
G01X955692Y172547D02*
X956187Y171981D01*
X955904Y171699D01*
X955338Y172194D01*
X955197Y172335D01*
X955551Y172689D01*
X955692Y172547D01*
G37*
G36*
G01X952548Y171942D02*
X952598Y172692D01*
X952998D01*
X953048Y171942D01*
Y171742D01*
X952548D01*
Y171942D01*
G37*
G36*
G01X949948D02*
X949998Y172692D01*
X950398D01*
X950448Y171942D01*
Y171742D01*
X949948D01*
Y171942D01*
G37*
G36*
G01X963856Y177962D02*
X963672Y178344D01*
X963969Y178641D01*
X964351Y178457D01*
X964493Y178316D01*
X963998Y177821D01*
X963856Y177962D01*
G37*
G36*
G01X965235Y178775D02*
X965419Y178393D01*
X965122Y178096D01*
X964740Y178280D01*
X964599Y178422D01*
X965094Y178917D01*
X965235Y178775D01*
G37*
G36*
G01X962654Y176760D02*
X962470Y177142D01*
X962767Y177439D01*
X963149Y177255D01*
X963291Y177114D01*
X962796Y176619D01*
X962654Y176760D01*
G37*
G36*
G01X964033Y177573D02*
X964217Y177191D01*
X963920Y176894D01*
X963538Y177078D01*
X963397Y177220D01*
X963892Y177715D01*
X964033Y177573D01*
G37*
G36*
G01X962831Y176371D02*
X963015Y175989D01*
X962718Y175692D01*
X962336Y175876D01*
X962195Y176018D01*
X962690Y176513D01*
X962831Y176371D01*
G37*
G36*
G01X959088Y174791D02*
X959228Y175191D01*
X959648D01*
X959788Y174791D01*
Y174591D01*
X959088D01*
Y174791D01*
G37*
G36*
G01X955975Y173395D02*
X955480Y173961D01*
X955763Y174244D01*
X956329Y173749D01*
X956470Y173607D01*
X956117Y173254D01*
X955975Y173395D01*
G37*
G36*
G01X960638Y174391D02*
X960498Y173991D01*
X960078D01*
X959938Y174391D01*
Y174591D01*
X960638D01*
Y174391D01*
G37*
G36*
G01X958938D02*
X958798Y173991D01*
X958378D01*
X958238Y174391D01*
Y174591D01*
X958938D01*
Y174391D01*
G37*
G36*
G01X961452Y175558D02*
X961268Y175940D01*
X961565Y176237D01*
X961947Y176053D01*
X962089Y175912D01*
X961594Y175417D01*
X961452Y175558D01*
G37*
G36*
G01X951748Y171542D02*
X951698Y170792D01*
X951298D01*
X951248Y171542D01*
Y171742D01*
X951748D01*
Y171542D01*
G37*
G36*
G01X954348D02*
X954298Y170792D01*
X953898D01*
X953848Y171542D01*
Y171742D01*
X954348D01*
Y171542D01*
G37*
G36*
G01X957388Y174791D02*
X957528Y175191D01*
X957948D01*
X958088Y174791D01*
Y174591D01*
X957388D01*
Y174791D01*
G37*
G36*
G01X934740Y183885D02*
X934690Y183135D01*
X934290D01*
X934240Y183885D01*
Y184085D01*
X934740D01*
Y183885D01*
G37*
G36*
G01X936376Y184440D02*
X936560Y184058D01*
X936263Y183761D01*
X935881Y183945D01*
X935739Y184086D01*
X936234Y184581D01*
X936376Y184440D01*
G37*
G36*
G01X937401Y186031D02*
X937217Y186413D01*
X937514Y186710D01*
X937896Y186526D01*
X938037Y186384D01*
X937542Y185889D01*
X937401Y186031D01*
G37*
G36*
G01X937578Y185642D02*
X937762Y185260D01*
X937465Y184963D01*
X937083Y185147D01*
X936941Y185288D01*
X937436Y185783D01*
X937578Y185642D01*
G37*
G36*
G01X936199Y184829D02*
X936015Y185211D01*
X936312Y185508D01*
X936694Y185324D01*
X936835Y185182D01*
X936340Y184687D01*
X936199Y184829D01*
G37*
G36*
G01X939190Y186735D02*
X939330Y187135D01*
X939750D01*
X939890Y186735D01*
Y186535D01*
X939190D01*
Y186735D01*
G37*
G36*
G01X940740Y186335D02*
X940600Y185935D01*
X940180D01*
X940040Y186335D01*
Y186535D01*
X940740D01*
Y186335D01*
G37*
G36*
G01X918268Y180953D02*
X918763Y180387D01*
X918481Y180104D01*
X917915Y180599D01*
X917773Y180740D01*
X918127Y181094D01*
X918268Y180953D01*
G37*
G36*
G01X918551Y181801D02*
X918056Y182367D01*
X918339Y182650D01*
X918905Y182155D01*
X919046Y182013D01*
X918693Y181660D01*
X918551Y181801D01*
G37*
G36*
G01X920108Y182793D02*
X920603Y182227D01*
X920321Y181944D01*
X919755Y182439D01*
X919613Y182580D01*
X919967Y182934D01*
X920108Y182793D01*
G37*
G36*
G01X920391Y183641D02*
X919896Y184207D01*
X920179Y184490D01*
X920745Y183995D01*
X920886Y183853D01*
X920533Y183500D01*
X920391Y183641D01*
G37*
G36*
G01X916711Y179961D02*
X916216Y180527D01*
X916499Y180810D01*
X917065Y180315D01*
X917206Y180173D01*
X916853Y179820D01*
X916711Y179961D01*
G37*
G36*
G01X926940Y183885D02*
X926890Y183135D01*
X926490D01*
X926440Y183885D01*
Y184085D01*
X926940D01*
Y183885D01*
G37*
G36*
G01X924340D02*
X924290Y183135D01*
X923890D01*
X923840Y183885D01*
Y184085D01*
X924340D01*
Y183885D01*
G37*
G36*
G01X929540D02*
X929490Y183135D01*
X929090D01*
X929040Y183885D01*
Y184085D01*
X929540D01*
Y183885D01*
G37*
G36*
G01X932140D02*
X932090Y183135D01*
X931690D01*
X931640Y183885D01*
Y184085D01*
X932140D01*
Y183885D01*
G37*
G36*
G01X932940Y184285D02*
X932990Y185035D01*
X933390D01*
X933440Y184285D01*
Y184085D01*
X932940D01*
Y184285D01*
G37*
G36*
G01X925140D02*
X925190Y185035D01*
X925590D01*
X925640Y184285D01*
Y184085D01*
X925140D01*
Y184285D01*
G37*
G36*
G01X922540D02*
X922590Y185035D01*
X922990D01*
X923040Y184285D01*
Y184085D01*
X922540D01*
Y184285D01*
G37*
G36*
G01X927740D02*
X927790Y185035D01*
X928190D01*
X928240Y184285D01*
Y184085D01*
X927740D01*
Y184285D01*
G37*
G36*
G01X930340D02*
X930390Y185035D01*
X930790D01*
X930840Y184285D01*
Y184085D01*
X930340D01*
Y184285D01*
G37*
G36*
G01X947540Y186335D02*
X947400Y185935D01*
X946980D01*
X946840Y186335D01*
Y186535D01*
X947540D01*
Y186335D01*
G37*
G36*
G01X945990Y186735D02*
X946130Y187135D01*
X946550D01*
X946690Y186735D01*
Y186535D01*
X945990D01*
Y186735D01*
G37*
G36*
G01X944290D02*
X944430Y187135D01*
X944850D01*
X944990Y186735D01*
Y186535D01*
X944290D01*
Y186735D01*
G37*
G36*
G01X942590D02*
X942730Y187135D01*
X943150D01*
X943290Y186735D01*
Y186535D01*
X942590D01*
Y186735D01*
G37*
G36*
G01X940890D02*
X941030Y187135D01*
X941450D01*
X941590Y186735D01*
Y186535D01*
X940890D01*
Y186735D01*
G37*
G36*
G01X944140Y186335D02*
X944000Y185935D01*
X943580D01*
X943440Y186335D01*
Y186535D01*
X944140D01*
Y186335D01*
G37*
G36*
G01X942440D02*
X942300Y185935D01*
X941880D01*
X941740Y186335D01*
Y186535D01*
X942440D01*
Y186335D01*
G37*
G36*
G01X945840D02*
X945700Y185935D01*
X945280D01*
X945140Y186335D01*
Y186535D01*
X945840D01*
Y186335D01*
G37*
G36*
G01X956700Y189064D02*
X956884Y188682D01*
X956587Y188385D01*
X956205Y188569D01*
X956063Y188710D01*
X956558Y189205D01*
X956700Y189064D01*
G37*
G36*
G01X959104Y191468D02*
X959288Y191086D01*
X958991Y190789D01*
X958609Y190973D01*
X958468Y191115D01*
X958963Y191610D01*
X959104Y191468D01*
G37*
G36*
G01X958927Y191857D02*
X958743Y192239D01*
X959040Y192536D01*
X959422Y192352D01*
X959564Y192211D01*
X959069Y191716D01*
X958927Y191857D01*
G37*
G36*
G01X957902Y190266D02*
X958086Y189884D01*
X957789Y189587D01*
X957407Y189771D01*
X957266Y189913D01*
X957761Y190408D01*
X957902Y190266D01*
G37*
G36*
G01X956523Y189453D02*
X956339Y189835D01*
X956636Y190132D01*
X957018Y189948D01*
X957159Y189806D01*
X956665Y189312D01*
X956523Y189453D01*
G37*
G36*
G01X947690Y186735D02*
X947830Y187135D01*
X948250D01*
X948390Y186735D01*
Y186535D01*
X947690D01*
Y186735D01*
G37*
G36*
G01X949390D02*
X949530Y187135D01*
X949950D01*
X950090Y186735D01*
Y186535D01*
X949390D01*
Y186735D01*
G37*
G36*
G01X951090D02*
X951230Y187135D01*
X951650D01*
X951790Y186735D01*
Y186535D01*
X951090D01*
Y186735D01*
G37*
G36*
G01X949240Y186335D02*
X949100Y185935D01*
X948680D01*
X948540Y186335D01*
Y186535D01*
X949240D01*
Y186335D01*
G37*
G36*
G01X950940D02*
X950800Y185935D01*
X950380D01*
X950240Y186335D01*
Y186535D01*
X950940D01*
Y186335D01*
G37*
G36*
G01X952640D02*
X952500Y185935D01*
X952080D01*
X951940Y186335D01*
Y186535D01*
X952640D01*
Y186335D01*
G37*
G36*
G01X955498Y187862D02*
X955682Y187480D01*
X955385Y187183D01*
X955003Y187367D01*
X954861Y187508D01*
X955356Y188003D01*
X955498Y187862D01*
G37*
G36*
G01X955321Y188251D02*
X955137Y188633D01*
X955434Y188930D01*
X955816Y188746D01*
X955957Y188604D01*
X955462Y188109D01*
X955321Y188251D01*
G37*
G36*
G01X954119Y187049D02*
X953935Y187431D01*
X954232Y187728D01*
X954614Y187544D01*
X954755Y187402D01*
X954260Y186907D01*
X954119Y187049D01*
G37*
G36*
G01X952790Y186735D02*
X952930Y187135D01*
X953350D01*
X953490Y186735D01*
Y186535D01*
X952790D01*
Y186735D01*
G37*
G36*
G01X962780Y202089D02*
X963449Y201738D01*
X963448Y200868D01*
X962777Y200519D01*
X962603D01*
X962606Y202089D01*
X962780D01*
G37*
G36*
G01X957725Y190655D02*
X957541Y191037D01*
X957838Y191334D01*
X958220Y191150D01*
X958362Y191009D01*
X957867Y190514D01*
X957725Y190655D01*
G37*
G36*
G01X970010Y179021D02*
X969826Y179403D01*
X970123Y179700D01*
X970505Y179516D01*
X970646Y179375D01*
X970151Y178880D01*
X970010Y179021D01*
G37*
G36*
G01X971212Y180223D02*
X971028Y180605D01*
X971325Y180902D01*
X971707Y180718D01*
X971848Y180577D01*
X971353Y180082D01*
X971212Y180223D01*
G37*
G36*
G01X971388Y179835D02*
X971572Y179453D01*
X971275Y179156D01*
X970893Y179340D01*
X970752Y179481D01*
X971247Y179976D01*
X971388Y179835D01*
G37*
G36*
G01X963999Y173011D02*
X963815Y173393D01*
X964112Y173690D01*
X964494Y173506D01*
X964636Y173365D01*
X964141Y172870D01*
X963999Y173011D01*
G37*
G36*
G01X964176Y172622D02*
X964360Y172240D01*
X964063Y171943D01*
X963681Y172127D01*
X963540Y172269D01*
X964034Y172763D01*
X964176Y172622D01*
G37*
G36*
G01X970186Y178632D02*
X970370Y178251D01*
X970073Y177954D01*
X969691Y178138D01*
X969550Y178279D01*
X970045Y178774D01*
X970186Y178632D01*
G37*
G36*
G01X968807Y177819D02*
X968624Y178201D01*
X968921Y178498D01*
X969302Y178314D01*
X969444Y178173D01*
X968949Y177678D01*
X968807Y177819D01*
G37*
G36*
G01X967605Y176617D02*
X967422Y176999D01*
X967719Y177296D01*
X968100Y177112D01*
X968242Y176971D01*
X967747Y176476D01*
X967605Y176617D01*
G37*
G36*
G01X968984Y177430D02*
X969168Y177049D01*
X968871Y176752D01*
X968489Y176935D01*
X968348Y177077D01*
X968843Y177572D01*
X968984Y177430D01*
G37*
G36*
G01X967782Y176228D02*
X967966Y175846D01*
X967669Y175549D01*
X967287Y175733D01*
X967146Y175875D01*
X967641Y176370D01*
X967782Y176228D01*
G37*
G36*
G01X966580Y175026D02*
X966764Y174644D01*
X966467Y174347D01*
X966085Y174531D01*
X965944Y174673D01*
X966439Y175168D01*
X966580Y175026D01*
G37*
G36*
G01X965201Y174213D02*
X965017Y174595D01*
X965314Y174892D01*
X965696Y174708D01*
X965838Y174567D01*
X965343Y174072D01*
X965201Y174213D01*
G37*
G36*
G01X965378Y173824D02*
X965562Y173442D01*
X965265Y173145D01*
X964883Y173329D01*
X964742Y173471D01*
X965237Y173966D01*
X965378Y173824D01*
G37*
G36*
G01X966403Y175415D02*
X966219Y175797D01*
X966516Y176094D01*
X966898Y175910D01*
X967040Y175769D01*
X966545Y175274D01*
X966403Y175415D01*
G37*
G36*
G01X962797Y171809D02*
X962613Y172191D01*
X962910Y172488D01*
X963292Y172304D01*
X963433Y172162D01*
X962938Y171667D01*
X962797Y171809D01*
G37*
G36*
G01X954348Y166892D02*
X954298Y166142D01*
X953898D01*
X953848Y166892D01*
Y167092D01*
X954348D01*
Y166892D01*
G37*
G36*
G01X958981Y169258D02*
X959476Y168692D01*
X959194Y168409D01*
X958628Y168904D01*
X958486Y169045D01*
X958840Y169399D01*
X958981Y169258D01*
G37*
G36*
G01X962974Y171420D02*
X963158Y171038D01*
X962861Y170741D01*
X962479Y170925D01*
X962338Y171067D01*
X962832Y171561D01*
X962974Y171420D01*
G37*
G36*
G01X960788Y171191D02*
X960928Y171591D01*
X961348D01*
X961488Y171191D01*
Y170991D01*
X960788D01*
Y171191D01*
G37*
G36*
G01X959266Y170108D02*
X958771Y170673D01*
X959054Y170956D01*
X959619Y170461D01*
X959761Y170320D01*
X959407Y169966D01*
X959266Y170108D01*
G37*
G36*
G01X957141Y167418D02*
X957636Y166852D01*
X957354Y166569D01*
X956788Y167064D01*
X956646Y167205D01*
X957000Y167559D01*
X957141Y167418D01*
G37*
G36*
G01X952548Y167292D02*
X952598Y168042D01*
X952998D01*
X953048Y167292D01*
Y167092D01*
X952548D01*
Y167292D01*
G37*
G36*
G01X955148D02*
X955198Y168042D01*
X955598D01*
X955648Y167292D01*
Y167092D01*
X955148D01*
Y167292D01*
G37*
G36*
G01X957426Y168268D02*
X956931Y168833D01*
X957214Y169116D01*
X957779Y168621D01*
X957921Y168480D01*
X957567Y168126D01*
X957426Y168268D01*
G37*
G36*
G01X947348Y175042D02*
X947398Y175792D01*
X947798D01*
X947848Y175042D01*
Y174842D01*
X947348D01*
Y175042D01*
G37*
G36*
G01X946448Y174642D02*
X946398Y173892D01*
X945998D01*
X945948Y174642D01*
Y174842D01*
X946448D01*
Y174642D01*
G37*
G36*
G01X967143Y184080D02*
X967327Y183698D01*
X967030Y183401D01*
X966648Y183585D01*
X966507Y183726D01*
X967002Y184221D01*
X967143Y184080D01*
G37*
G36*
G01X965765Y183266D02*
X965581Y183648D01*
X965878Y183945D01*
X966260Y183761D01*
X966401Y183620D01*
X965906Y183125D01*
X965765Y183266D01*
G37*
G36*
G01X966967Y184468D02*
X966783Y184850D01*
X967080Y185147D01*
X967462Y184963D01*
X967603Y184822D01*
X967108Y184327D01*
X966967Y184468D01*
G37*
G36*
G01X964562Y182064D02*
X964379Y182446D01*
X964676Y182743D01*
X965057Y182559D01*
X965199Y182418D01*
X964704Y181923D01*
X964562Y182064D01*
G37*
G36*
G01X963360Y180862D02*
X963177Y181244D01*
X963474Y181541D01*
X963855Y181357D01*
X963997Y181216D01*
X963502Y180721D01*
X963360Y180862D01*
G37*
G36*
G01X962158Y179660D02*
X961974Y180042D01*
X962271Y180339D01*
X962653Y180155D01*
X962795Y180014D01*
X962300Y179519D01*
X962158Y179660D01*
G37*
G36*
G01X965941Y182877D02*
X966125Y182496D01*
X965828Y182199D01*
X965446Y182383D01*
X965305Y182524D01*
X965800Y183019D01*
X965941Y182877D01*
G37*
G36*
G01X964739Y181675D02*
X964923Y181294D01*
X964626Y180997D01*
X964244Y181180D01*
X964103Y181322D01*
X964598Y181817D01*
X964739Y181675D01*
G37*
G36*
G01X963537Y180473D02*
X963721Y180091D01*
X963424Y179794D01*
X963042Y179978D01*
X962901Y180120D01*
X963396Y180615D01*
X963537Y180473D01*
G37*
G36*
G01X968169Y185671D02*
X967985Y186052D01*
X968282Y186349D01*
X968664Y186166D01*
X968805Y186024D01*
X968310Y185529D01*
X968169Y185671D01*
G37*
G36*
G01X969371Y186873D02*
X969187Y187254D01*
X969484Y187551D01*
X969866Y187368D01*
X970007Y187226D01*
X969512Y186731D01*
X969371Y186873D01*
G37*
G36*
G01X968345Y185282D02*
X968529Y184900D01*
X968232Y184603D01*
X967851Y184787D01*
X967709Y184928D01*
X968204Y185423D01*
X968345Y185282D01*
G37*
G36*
G01X969548Y186484D02*
X969731Y186102D01*
X969434Y185805D01*
X969053Y185989D01*
X968911Y186130D01*
X969406Y186625D01*
X969548Y186484D01*
G37*
G36*
G01X960956Y178458D02*
X960772Y178840D01*
X961069Y179137D01*
X961451Y178953D01*
X961593Y178812D01*
X961098Y178317D01*
X960956Y178458D01*
G37*
G36*
G01X962335Y179271D02*
X962519Y178889D01*
X962222Y178592D01*
X961840Y178776D01*
X961699Y178918D01*
X962194Y179413D01*
X962335Y179271D01*
G37*
G36*
G01X970573Y188075D02*
X970389Y188457D01*
X970686Y188754D01*
X971068Y188570D01*
X971209Y188428D01*
X970714Y187933D01*
X970573Y188075D01*
G37*
G36*
G01X970750Y187686D02*
X970934Y187304D01*
X970637Y187007D01*
X970255Y187191D01*
X970113Y187332D01*
X970608Y187827D01*
X970750Y187686D01*
G37*
G36*
G01X971952Y188888D02*
X972136Y188506D01*
X971839Y188209D01*
X971457Y188393D01*
X971315Y188534D01*
X971810Y189029D01*
X971952Y188888D01*
G37*
G36*
G01X958938Y176791D02*
X958798Y176391D01*
X958378D01*
X958238Y176791D01*
Y176991D01*
X958938D01*
Y176791D01*
G37*
G36*
G01X957388Y177191D02*
X957528Y177591D01*
X957948D01*
X958088Y177191D01*
Y176991D01*
X957388D01*
Y177191D01*
G37*
G36*
G01X957238Y176791D02*
X957098Y176391D01*
X956678D01*
X956538Y176791D01*
Y176991D01*
X957238D01*
Y176791D01*
G37*
G36*
G01X955688Y177191D02*
X955828Y177591D01*
X956248D01*
X956388Y177191D01*
Y176991D01*
X955688D01*
Y177191D01*
G37*
G36*
G01X961133Y178069D02*
X961317Y177687D01*
X961020Y177390D01*
X960638Y177574D01*
X960497Y177716D01*
X960992Y178211D01*
X961133Y178069D01*
G37*
G36*
G01X952548Y175042D02*
X952598Y175792D01*
X952998D01*
X953048Y175042D01*
Y174842D01*
X952548D01*
Y175042D01*
G37*
G36*
G01X955338Y176581D02*
X955833Y176015D01*
X955550Y175733D01*
X954984Y176228D01*
X954843Y176369D01*
X955197Y176723D01*
X955338Y176581D01*
G37*
G36*
G01X953781Y175589D02*
X953286Y176155D01*
X953569Y176438D01*
X954135Y175943D01*
X954276Y175801D01*
X953923Y175448D01*
X953781Y175589D01*
G37*
G36*
G01X949948Y175042D02*
X949998Y175792D01*
X950398D01*
X950448Y175042D01*
Y174842D01*
X949948D01*
Y175042D01*
G37*
G36*
G01X951748Y174642D02*
X951698Y173892D01*
X951298D01*
X951248Y174642D01*
Y174842D01*
X951748D01*
Y174642D01*
G37*
G36*
G01X949148D02*
X949098Y173892D01*
X948698D01*
X948648Y174642D01*
Y174842D01*
X949148D01*
Y174642D01*
G37*
G36*
G01X947248Y173492D02*
X947298Y174242D01*
X947698D01*
X947748Y173492D01*
Y173292D01*
X947248D01*
Y173492D01*
G37*
G36*
G01X966614Y182417D02*
X966430Y182799D01*
X966727Y183096D01*
X967109Y182912D01*
X967250Y182771D01*
X966755Y182276D01*
X966614Y182417D01*
G37*
G36*
G01X966790Y182028D02*
X966974Y181647D01*
X966677Y181350D01*
X966295Y181534D01*
X966154Y181675D01*
X966649Y182170D01*
X966790Y182028D01*
G37*
G36*
G01X965411Y181215D02*
X965228Y181597D01*
X965525Y181894D01*
X965906Y181710D01*
X966048Y181569D01*
X965553Y181074D01*
X965411Y181215D01*
G37*
G36*
G01X964209Y180013D02*
X964026Y180395D01*
X964323Y180692D01*
X964704Y180508D01*
X964846Y180367D01*
X964351Y179872D01*
X964209Y180013D01*
G37*
G36*
G01X965588Y180826D02*
X965772Y180445D01*
X965475Y180148D01*
X965093Y180331D01*
X964952Y180473D01*
X965447Y180968D01*
X965588Y180826D01*
G37*
G36*
G01X967816Y183619D02*
X967632Y184001D01*
X967929Y184298D01*
X968311Y184114D01*
X968452Y183973D01*
X967957Y183478D01*
X967816Y183619D01*
G37*
G36*
G01X967992Y183231D02*
X968176Y182849D01*
X967879Y182552D01*
X967497Y182736D01*
X967356Y182877D01*
X967851Y183372D01*
X967992Y183231D01*
G37*
G36*
G01X969194Y184433D02*
X969378Y184051D01*
X969081Y183754D01*
X968700Y183938D01*
X968558Y184079D01*
X969053Y184574D01*
X969194Y184433D01*
G37*
G36*
G01X969018Y184822D02*
X968834Y185203D01*
X969131Y185500D01*
X969513Y185317D01*
X969654Y185175D01*
X969159Y184680D01*
X969018Y184822D01*
G37*
G36*
G01X963007Y178811D02*
X962823Y179193D01*
X963120Y179490D01*
X963502Y179306D01*
X963644Y179165D01*
X963149Y178670D01*
X963007Y178811D01*
G37*
G36*
G01X964386Y179624D02*
X964570Y179242D01*
X964273Y178945D01*
X963891Y179129D01*
X963750Y179271D01*
X964245Y179766D01*
X964386Y179624D01*
G37*
G36*
G01X970220Y186024D02*
X970036Y186405D01*
X970333Y186702D01*
X970715Y186519D01*
X970856Y186377D01*
X970361Y185882D01*
X970220Y186024D01*
G37*
G36*
G01X971599Y186837D02*
X971783Y186455D01*
X971486Y186158D01*
X971104Y186342D01*
X970962Y186483D01*
X971457Y186978D01*
X971599Y186837D01*
G37*
G36*
G01X971422Y187226D02*
X971238Y187608D01*
X971535Y187905D01*
X971917Y187721D01*
X972058Y187579D01*
X971563Y187084D01*
X971422Y187226D01*
G37*
G36*
G01X970397Y185635D02*
X970580Y185253D01*
X970283Y184956D01*
X969902Y185140D01*
X969760Y185281D01*
X970255Y185776D01*
X970397Y185635D01*
G37*
G36*
G01X954595Y173644D02*
X955090Y173078D01*
X954807Y172796D01*
X954241Y173291D01*
X954100Y173432D01*
X954454Y173786D01*
X954595Y173644D01*
G37*
G36*
G01X951748Y173092D02*
X951698Y172342D01*
X951298D01*
X951248Y173092D01*
Y173292D01*
X951748D01*
Y173092D01*
G37*
G36*
G01X963184Y178422D02*
X963368Y178040D01*
X963071Y177743D01*
X962689Y177927D01*
X962548Y178069D01*
X963043Y178564D01*
X963184Y178422D01*
G37*
G36*
G01X961982Y177220D02*
X962166Y176838D01*
X961869Y176541D01*
X961487Y176725D01*
X961346Y176867D01*
X961841Y177362D01*
X961982Y177220D01*
G37*
G36*
G01X958938Y175591D02*
X958798Y175191D01*
X958378D01*
X958238Y175591D01*
Y175791D01*
X958938D01*
Y175591D01*
G37*
G36*
G01X959088Y175991D02*
X959228Y176391D01*
X959648D01*
X959788Y175991D01*
Y175791D01*
X959088D01*
Y175991D01*
G37*
G36*
G01X957388D02*
X957528Y176391D01*
X957948D01*
X958088Y175991D01*
Y175791D01*
X957388D01*
Y175991D01*
G37*
G36*
G01X960603Y176407D02*
X960419Y176789D01*
X960716Y177086D01*
X961098Y176902D01*
X961240Y176761D01*
X960745Y176266D01*
X960603Y176407D01*
G37*
G36*
G01X961805Y177609D02*
X961621Y177991D01*
X961918Y178288D01*
X962300Y178104D01*
X962442Y177963D01*
X961947Y177468D01*
X961805Y177609D01*
G37*
G36*
G01X954878Y174492D02*
X954383Y175058D01*
X954666Y175341D01*
X955232Y174846D01*
X955373Y174704D01*
X955020Y174351D01*
X954878Y174492D01*
G37*
G36*
G01X952548Y173492D02*
X952598Y174242D01*
X952998D01*
X953048Y173492D01*
Y173292D01*
X952548D01*
Y173492D01*
G37*
G36*
G01X949948D02*
X949998Y174242D01*
X950398D01*
X950448Y173492D01*
Y173292D01*
X949948D01*
Y173492D01*
G37*
G36*
G01X956435Y175484D02*
X956930Y174918D01*
X956647Y174636D01*
X956081Y175131D01*
X955940Y175272D01*
X956294Y175626D01*
X956435Y175484D01*
G37*
G36*
G01X949148Y173092D02*
X949098Y172342D01*
X948698D01*
X948648Y173092D01*
Y173292D01*
X949148D01*
Y173092D01*
G37*
G36*
G01X960780Y176018D02*
X960964Y175636D01*
X960667Y175339D01*
X960285Y175523D01*
X960144Y175665D01*
X960639Y176160D01*
X960780Y176018D01*
G37*
G36*
G01X968950Y172868D02*
X968766Y173250D01*
X969063Y173547D01*
X969445Y173363D01*
X969587Y173222D01*
X969092Y172727D01*
X968950Y172868D01*
G37*
G36*
G01X969127Y172479D02*
X969311Y172097D01*
X969014Y171800D01*
X968632Y171984D01*
X968491Y172126D01*
X968986Y172621D01*
X969127Y172479D01*
G37*
G36*
G01X970152Y174070D02*
X969969Y174452D01*
X970266Y174749D01*
X970647Y174565D01*
X970789Y174424D01*
X970294Y173929D01*
X970152Y174070D01*
G37*
G36*
G01X971531Y174883D02*
X971715Y174502D01*
X971418Y174205D01*
X971036Y174388D01*
X970895Y174530D01*
X971390Y175025D01*
X971531Y174883D01*
G37*
G36*
G01X970329Y173681D02*
X970513Y173299D01*
X970216Y173002D01*
X969834Y173186D01*
X969693Y173328D01*
X970188Y173823D01*
X970329Y173681D01*
G37*
G36*
G01X971354Y175272D02*
X971171Y175654D01*
X971468Y175951D01*
X971849Y175767D01*
X971991Y175626D01*
X971496Y175131D01*
X971354Y175272D01*
G37*
G36*
G01X960432Y164130D02*
X960927Y163564D01*
X960645Y163281D01*
X960079Y163776D01*
X959937Y163917D01*
X960291Y164271D01*
X960432Y164130D01*
G37*
G36*
G01X962271Y165968D02*
X962766Y165402D01*
X962483Y165120D01*
X961917Y165615D01*
X961776Y165756D01*
X962130Y166110D01*
X962271Y165968D01*
G37*
G36*
G01X960715Y164978D02*
X960220Y165544D01*
X960503Y165827D01*
X961069Y165332D01*
X961210Y165190D01*
X960857Y164837D01*
X960715Y164978D01*
G37*
G36*
G01X958592Y162290D02*
X959087Y161724D01*
X958805Y161441D01*
X958239Y161936D01*
X958097Y162077D01*
X958451Y162431D01*
X958592Y162290D01*
G37*
G36*
G01X958875Y163138D02*
X958380Y163704D01*
X958663Y163987D01*
X959229Y163492D01*
X959370Y163350D01*
X959017Y162997D01*
X958875Y163138D01*
G37*
G36*
G01X965344Y169262D02*
X965160Y169644D01*
X965457Y169941D01*
X965839Y169757D01*
X965980Y169615D01*
X965485Y169120D01*
X965344Y169262D01*
G37*
G36*
G01X965521Y168873D02*
X965705Y168491D01*
X965408Y168194D01*
X965026Y168378D01*
X964884Y168519D01*
X965379Y169014D01*
X965521Y168873D01*
G37*
G36*
G01X964142Y168060D02*
X963958Y168442D01*
X964255Y168739D01*
X964637Y168555D01*
X964778Y168413D01*
X964283Y167918D01*
X964142Y168060D01*
G37*
G36*
G01X962555Y166818D02*
X962060Y167384D01*
X962343Y167667D01*
X962909Y167172D01*
X963050Y167030D01*
X962697Y166677D01*
X962555Y166818D01*
G37*
G36*
G01X967748Y171666D02*
X967564Y172048D01*
X967861Y172345D01*
X968243Y172161D01*
X968385Y172020D01*
X967890Y171525D01*
X967748Y171666D01*
G37*
G36*
G01X966546Y170464D02*
X966362Y170846D01*
X966659Y171143D01*
X967041Y170959D01*
X967183Y170818D01*
X966688Y170323D01*
X966546Y170464D01*
G37*
G36*
G01X967925Y171277D02*
X968109Y170895D01*
X967812Y170598D01*
X967430Y170782D01*
X967289Y170924D01*
X967784Y171419D01*
X967925Y171277D01*
G37*
G36*
G01X966723Y170075D02*
X966907Y169693D01*
X966610Y169396D01*
X966228Y169580D01*
X966087Y169722D01*
X966581Y170216D01*
X966723Y170075D01*
G37*
G36*
G01X969799Y172020D02*
X969615Y172401D01*
X969912Y172698D01*
X970294Y172514D01*
X970471Y172338D01*
X969976Y171843D01*
X969799Y172020D01*
G37*
G36*
G01X971001Y173222D02*
X970817Y173603D01*
X971114Y173900D01*
X971496Y173717D01*
X971673Y173540D01*
X971178Y173045D01*
X971001Y173222D01*
G37*
G36*
G01X961812Y163882D02*
X961317Y164447D01*
X961600Y164730D01*
X962166Y164235D01*
X962342Y164058D01*
X961989Y163705D01*
X961812Y163882D01*
G37*
G36*
G01X963652Y165722D02*
X963157Y166287D01*
X963440Y166570D01*
X964006Y166075D01*
X964182Y165898D01*
X963829Y165545D01*
X963652Y165722D01*
G37*
G36*
G01X959972Y162042D02*
X959477Y162607D01*
X959760Y162890D01*
X960326Y162395D01*
X960502Y162218D01*
X960149Y161865D01*
X959972Y162042D01*
G37*
G36*
G01X964991Y167211D02*
X964807Y167593D01*
X965104Y167890D01*
X965486Y167706D01*
X965662Y167529D01*
X965167Y167034D01*
X964991Y167211D01*
G37*
G36*
G01X968597Y170817D02*
X968413Y171199D01*
X968710Y171496D01*
X969092Y171312D01*
X969269Y171136D01*
X968774Y170641D01*
X968597Y170817D01*
G37*
G36*
G01X966193Y168413D02*
X966009Y168795D01*
X966306Y169092D01*
X966688Y168908D01*
X966864Y168731D01*
X966369Y168236D01*
X966193Y168413D01*
G37*
G36*
G01X967395Y169615D02*
X967211Y169997D01*
X967508Y170294D01*
X967890Y170110D01*
X968067Y169934D01*
X967572Y169439D01*
X967395Y169615D01*
G37*
G36*
G01X946548Y177742D02*
X946498Y176992D01*
X946098D01*
X946048Y177742D01*
Y177992D01*
X946548D01*
Y177742D01*
G37*
G36*
G01X943848D02*
X943798Y176992D01*
X943398D01*
X943348Y177742D01*
Y177992D01*
X943848D01*
Y177742D01*
G37*
G36*
G01X966648Y186979D02*
X966832Y186597D01*
X966535Y186300D01*
X966153Y186484D01*
X965976Y186661D01*
X966471Y187156D01*
X966648Y186979D01*
G37*
G36*
G01X963042Y183373D02*
X963225Y182991D01*
X962928Y182694D01*
X962547Y182878D01*
X962370Y183055D01*
X962865Y183550D01*
X963042Y183373D01*
G37*
G36*
G01X961840Y182171D02*
X962023Y181789D01*
X961726Y181492D01*
X961345Y181676D01*
X961168Y181853D01*
X961663Y182348D01*
X961840Y182171D01*
G37*
G36*
G01X960637Y180969D02*
X960821Y180587D01*
X960524Y180290D01*
X960142Y180474D01*
X959966Y180651D01*
X960461Y181146D01*
X960637Y180969D01*
G37*
G36*
G01X964244Y184575D02*
X964428Y184193D01*
X964131Y183896D01*
X963749Y184080D01*
X963572Y184257D01*
X964067Y184752D01*
X964244Y184575D01*
G37*
G36*
G01X965446Y185777D02*
X965630Y185395D01*
X965333Y185098D01*
X964951Y185282D01*
X964774Y185459D01*
X965269Y185954D01*
X965446Y185777D01*
G37*
G36*
G01X967850Y188181D02*
X968034Y187800D01*
X967737Y187503D01*
X967355Y187686D01*
X967178Y187863D01*
X967673Y188358D01*
X967850Y188181D01*
G37*
G36*
G01X969052Y189383D02*
X969236Y189002D01*
X968939Y188705D01*
X968557Y188888D01*
X968380Y189065D01*
X968875Y189560D01*
X969052Y189383D01*
G37*
G36*
G01X957238Y179191D02*
X957098Y178791D01*
X956678D01*
X956538Y179191D01*
Y179441D01*
X957238D01*
Y179191D01*
G37*
G36*
G01X959435Y179767D02*
X959619Y179385D01*
X959322Y179088D01*
X958940Y179272D01*
X958764Y179449D01*
X959259Y179944D01*
X959435Y179767D01*
G37*
G36*
G01X955538Y179191D02*
X955398Y178791D01*
X954978D01*
X954838Y179191D01*
Y179441D01*
X955538D01*
Y179191D01*
G37*
G36*
G01X967914Y210250D02*
X967244Y210600D01*
Y211470D01*
X967914Y211820D01*
X968089D01*
Y210250D01*
X967914D01*
G37*
G36*
G01X971456Y191788D02*
X971640Y191406D01*
X971343Y191109D01*
X970961Y191293D01*
X970784Y191469D01*
X971279Y191964D01*
X971456Y191788D01*
G37*
G36*
G01X971537Y195448D02*
X971937Y195308D01*
Y194887D01*
X971537Y194748D01*
X971287D01*
Y195448D01*
X971537D01*
G37*
G36*
G01Y193748D02*
X971937Y193608D01*
Y193187D01*
X971537Y193048D01*
X971287D01*
Y193748D01*
X971537D01*
G37*
G36*
G01X970254Y190586D02*
X970438Y190204D01*
X970141Y189907D01*
X969759Y190091D01*
X969582Y190267D01*
X970077Y190762D01*
X970254Y190586D01*
G37*
G36*
G01X953144Y178775D02*
X953639Y178209D01*
X953356Y177927D01*
X952790Y178422D01*
X952649Y178563D01*
X953003Y178917D01*
X953144Y178775D01*
G37*
G36*
G01X951748Y177742D02*
X951698Y176992D01*
X951298D01*
X951248Y177742D01*
Y177992D01*
X951748D01*
Y177742D01*
G37*
G36*
G01X949148D02*
X949098Y176992D01*
X948698D01*
X948648Y177742D01*
Y177992D01*
X949148D01*
Y177742D01*
G37*
G36*
G01X947348Y176592D02*
X947398Y177342D01*
X947798D01*
X947848Y176592D01*
Y176392D01*
X947348D01*
Y176592D01*
G37*
G36*
G01X943848Y176192D02*
X943798Y175442D01*
X943398D01*
X943348Y176192D01*
Y176392D01*
X943848D01*
Y176192D01*
G37*
G36*
G01X944748Y176592D02*
X944798Y177342D01*
X945198D01*
X945248Y176592D01*
Y176392D01*
X944748D01*
Y176592D01*
G37*
G36*
G01X946548Y176192D02*
X946498Y175442D01*
X946098D01*
X946048Y176192D01*
Y176392D01*
X946548D01*
Y176192D01*
G37*
G36*
G01X966118Y185317D02*
X965934Y185699D01*
X966231Y185996D01*
X966613Y185812D01*
X966754Y185671D01*
X966259Y185176D01*
X966118Y185317D01*
G37*
G36*
G01X966294Y184929D02*
X966478Y184547D01*
X966181Y184250D01*
X965799Y184434D01*
X965658Y184575D01*
X966153Y185070D01*
X966294Y184929D01*
G37*
G36*
G01X965092Y183726D02*
X965276Y183345D01*
X964979Y183048D01*
X964597Y183232D01*
X964456Y183373D01*
X964951Y183868D01*
X965092Y183726D01*
G37*
G36*
G01X963890Y182524D02*
X964074Y182143D01*
X963777Y181846D01*
X963395Y182029D01*
X963254Y182171D01*
X963749Y182666D01*
X963890Y182524D01*
G37*
G36*
G01X962688Y181322D02*
X962872Y180940D01*
X962575Y180643D01*
X962193Y180827D01*
X962052Y180969D01*
X962547Y181464D01*
X962688Y181322D01*
G37*
G36*
G01X963713Y182913D02*
X963530Y183295D01*
X963827Y183592D01*
X964208Y183408D01*
X964350Y183267D01*
X963855Y182772D01*
X963713Y182913D01*
G37*
G36*
G01X962511Y181711D02*
X962328Y182093D01*
X962625Y182390D01*
X963006Y182206D01*
X963148Y182065D01*
X962653Y181570D01*
X962511Y181711D01*
G37*
G36*
G01X961309Y180509D02*
X961125Y180891D01*
X961422Y181188D01*
X961804Y181004D01*
X961946Y180863D01*
X961451Y180368D01*
X961309Y180509D01*
G37*
G36*
G01X964916Y184115D02*
X964732Y184497D01*
X965029Y184794D01*
X965411Y184610D01*
X965552Y184469D01*
X965057Y183974D01*
X964916Y184115D01*
G37*
G36*
G01X968522Y187722D02*
X968338Y188103D01*
X968635Y188400D01*
X969017Y188217D01*
X969158Y188075D01*
X968663Y187580D01*
X968522Y187722D01*
G37*
G36*
G01X967496Y186131D02*
X967680Y185749D01*
X967383Y185452D01*
X967002Y185636D01*
X966860Y185777D01*
X967355Y186272D01*
X967496Y186131D01*
G37*
G36*
G01X968699Y187333D02*
X968882Y186951D01*
X968585Y186654D01*
X968204Y186838D01*
X968062Y186979D01*
X968557Y187474D01*
X968699Y187333D01*
G37*
G36*
G01X967320Y186520D02*
X967136Y186901D01*
X967433Y187198D01*
X967815Y187015D01*
X967956Y186873D01*
X967461Y186378D01*
X967320Y186520D01*
G37*
G36*
G01X961486Y180120D02*
X961670Y179738D01*
X961373Y179441D01*
X960991Y179625D01*
X960850Y179767D01*
X961345Y180262D01*
X961486Y180120D01*
G37*
G36*
G01X960284Y178918D02*
X960468Y178536D01*
X960171Y178239D01*
X959789Y178423D01*
X959648Y178565D01*
X960143Y179060D01*
X960284Y178918D01*
G37*
G36*
G01X960107Y179307D02*
X959923Y179689D01*
X960220Y179986D01*
X960602Y179802D01*
X960744Y179661D01*
X960249Y179166D01*
X960107Y179307D01*
G37*
G36*
G01X971103Y189737D02*
X971287Y189355D01*
X970990Y189058D01*
X970608Y189242D01*
X970466Y189383D01*
X970961Y189878D01*
X971103Y189737D01*
G37*
G36*
G01X970926Y190126D02*
X970742Y190508D01*
X971039Y190805D01*
X971421Y190621D01*
X971562Y190479D01*
X971067Y189984D01*
X970926Y190126D01*
G37*
G36*
G01X969901Y188535D02*
X970085Y188153D01*
X969788Y187856D01*
X969406Y188040D01*
X969264Y188181D01*
X969759Y188676D01*
X969901Y188535D01*
G37*
G36*
G01X969724Y188924D02*
X969540Y189306D01*
X969837Y189603D01*
X970219Y189419D01*
X970360Y189277D01*
X969865Y188782D01*
X969724Y188924D01*
G37*
G36*
G01X957238Y177991D02*
X957098Y177591D01*
X956678D01*
X956538Y177991D01*
Y178191D01*
X957238D01*
Y177991D01*
G37*
G36*
G01X957388Y178391D02*
X957528Y178791D01*
X957948D01*
X958088Y178391D01*
Y178191D01*
X957388D01*
Y178391D01*
G37*
G36*
G01X955688D02*
X955828Y178791D01*
X956248D01*
X956388Y178391D01*
Y178191D01*
X955688D01*
Y178391D01*
G37*
G36*
G01X958938Y177991D02*
X958798Y177591D01*
X958378D01*
X958238Y177991D01*
Y178191D01*
X958938D01*
Y177991D01*
G37*
G36*
G01X955538D02*
X955398Y177591D01*
X954978D01*
X954838Y177991D01*
Y178191D01*
X955538D01*
Y177991D01*
G37*
G36*
G01X954241Y177678D02*
X954736Y177112D01*
X954453Y176830D01*
X953887Y177325D01*
X953746Y177466D01*
X954100Y177820D01*
X954241Y177678D01*
G37*
G36*
G01X952684Y176686D02*
X952189Y177252D01*
X952472Y177535D01*
X953038Y177040D01*
X953179Y176898D01*
X952826Y176545D01*
X952684Y176686D01*
G37*
G36*
G01X951748Y176192D02*
X951698Y175442D01*
X951298D01*
X951248Y176192D01*
Y176392D01*
X951748D01*
Y176192D01*
G37*
G36*
G01X949948Y176592D02*
X949998Y177342D01*
X950398D01*
X950448Y176592D01*
Y176392D01*
X949948D01*
Y176592D01*
G37*
G36*
G01X949148Y176192D02*
X949098Y175442D01*
X948698D01*
X948648Y176192D01*
Y176392D01*
X949148D01*
Y176192D01*
G37*
G36*
G01X970974Y209143D02*
X970454Y208594D01*
X969617Y208831D01*
X969463Y209571D01*
X969512Y209740D01*
X971022Y209310D01*
X970974Y209143D01*
G37*
G36*
G01X964848Y172162D02*
X964664Y172544D01*
X964961Y172841D01*
X965343Y172657D01*
X965485Y172516D01*
X964990Y172021D01*
X964848Y172162D01*
G37*
G36*
G01X966227Y172975D02*
X966411Y172593D01*
X966114Y172296D01*
X965732Y172480D01*
X965591Y172622D01*
X966086Y173117D01*
X966227Y172975D01*
G37*
G36*
G01X970859Y178172D02*
X970675Y178554D01*
X970972Y178851D01*
X971354Y178667D01*
X971495Y178526D01*
X971000Y178031D01*
X970859Y178172D01*
G37*
G36*
G01X971035Y177783D02*
X971219Y177402D01*
X970922Y177105D01*
X970540Y177289D01*
X970399Y177430D01*
X970894Y177925D01*
X971035Y177783D01*
G37*
G36*
G01X969656Y176970D02*
X969473Y177352D01*
X969770Y177649D01*
X970151Y177465D01*
X970293Y177324D01*
X969798Y176829D01*
X969656Y176970D01*
G37*
G36*
G01X968454Y175768D02*
X968271Y176150D01*
X968568Y176447D01*
X968949Y176263D01*
X969091Y176122D01*
X968596Y175627D01*
X968454Y175768D01*
G37*
G36*
G01X967252Y174566D02*
X967068Y174948D01*
X967365Y175245D01*
X967747Y175061D01*
X967889Y174920D01*
X967394Y174425D01*
X967252Y174566D01*
G37*
G36*
G01X969833Y176581D02*
X970017Y176200D01*
X969720Y175903D01*
X969338Y176086D01*
X969197Y176228D01*
X969692Y176723D01*
X969833Y176581D01*
G37*
G36*
G01X966050Y173364D02*
X965866Y173746D01*
X966163Y174043D01*
X966545Y173859D01*
X966687Y173718D01*
X966192Y173223D01*
X966050Y173364D01*
G37*
G36*
G01X967429Y174177D02*
X967613Y173795D01*
X967316Y173498D01*
X966934Y173682D01*
X966793Y173824D01*
X967288Y174319D01*
X967429Y174177D01*
G37*
G36*
G01X968631Y175379D02*
X968815Y174997D01*
X968518Y174700D01*
X968136Y174884D01*
X967995Y175026D01*
X968490Y175521D01*
X968631Y175379D01*
G37*
G36*
G01X958238Y166321D02*
X958733Y165755D01*
X958451Y165472D01*
X957885Y165967D01*
X957743Y166108D01*
X958097Y166462D01*
X958238Y166321D01*
G37*
G36*
G01X956918Y165342D02*
X956868Y164592D01*
X956468D01*
X956418Y165342D01*
Y165542D01*
X956918D01*
Y165342D01*
G37*
G36*
G01X955148Y165742D02*
X955198Y166492D01*
X955598D01*
X955648Y165742D01*
Y165542D01*
X955148D01*
Y165742D01*
G37*
G36*
G01X954348Y165342D02*
X954298Y164592D01*
X953898D01*
X953848Y165342D01*
Y165542D01*
X954348D01*
Y165342D01*
G37*
G36*
G01X960078Y168161D02*
X960573Y167595D01*
X960291Y167312D01*
X959725Y167807D01*
X959583Y167948D01*
X959937Y168302D01*
X960078Y168161D01*
G37*
G36*
G01X958523Y167171D02*
X958028Y167736D01*
X958311Y168019D01*
X958876Y167524D01*
X959018Y167383D01*
X958664Y167029D01*
X958523Y167171D01*
G37*
G36*
G01X963646Y170960D02*
X963462Y171342D01*
X963759Y171639D01*
X964141Y171455D01*
X964282Y171313D01*
X963787Y170818D01*
X963646Y170960D01*
G37*
G36*
G01X965025Y171773D02*
X965209Y171391D01*
X964912Y171094D01*
X964530Y171278D01*
X964389Y171420D01*
X964883Y171914D01*
X965025Y171773D01*
G37*
G36*
G01X963823Y170571D02*
X964007Y170189D01*
X963710Y169892D01*
X963328Y170076D01*
X963187Y170218D01*
X963681Y170712D01*
X963823Y170571D01*
G37*
G36*
G01X960363Y169011D02*
X959868Y169576D01*
X960151Y169859D01*
X960716Y169364D01*
X960858Y169223D01*
X960504Y168869D01*
X960363Y169011D01*
G37*
G36*
G01X962338Y169591D02*
X962198Y169191D01*
X961778D01*
X961638Y169591D01*
Y169791D01*
X962338D01*
Y169591D01*
G37*
G36*
G01X966899Y172515D02*
X966715Y172897D01*
X967012Y173194D01*
X967394Y173010D01*
X967536Y172869D01*
X967041Y172374D01*
X966899Y172515D01*
G37*
G36*
G01X968278Y173328D02*
X968462Y172946D01*
X968165Y172649D01*
X967783Y172833D01*
X967642Y172975D01*
X968137Y173470D01*
X968278Y173328D01*
G37*
G36*
G01X970505Y176121D02*
X970322Y176503D01*
X970619Y176800D01*
X971000Y176616D01*
X971142Y176475D01*
X970647Y175980D01*
X970505Y176121D01*
G37*
G36*
G01X969303Y174919D02*
X969120Y175301D01*
X969417Y175598D01*
X969798Y175414D01*
X969940Y175273D01*
X969445Y174778D01*
X969303Y174919D01*
G37*
G36*
G01X968101Y173717D02*
X967917Y174099D01*
X968214Y174396D01*
X968596Y174212D01*
X968738Y174071D01*
X968243Y173576D01*
X968101Y173717D01*
G37*
G36*
G01X969480Y174530D02*
X969664Y174148D01*
X969367Y173851D01*
X968985Y174035D01*
X968844Y174177D01*
X969339Y174672D01*
X969480Y174530D01*
G37*
G36*
G01X971884Y176934D02*
X972068Y176553D01*
X971771Y176256D01*
X971389Y176440D01*
X971248Y176581D01*
X971743Y177076D01*
X971884Y176934D01*
G37*
G36*
G01X970682Y175732D02*
X970866Y175351D01*
X970569Y175054D01*
X970187Y175237D01*
X970046Y175379D01*
X970541Y175874D01*
X970682Y175732D01*
G37*
G36*
G01X959336Y165226D02*
X959831Y164660D01*
X959548Y164378D01*
X958982Y164873D01*
X958841Y165014D01*
X959195Y165368D01*
X959336Y165226D01*
G37*
G36*
G01X959619Y166075D02*
X959124Y166640D01*
X959407Y166923D01*
X959972Y166428D01*
X960114Y166287D01*
X959760Y165933D01*
X959619Y166075D01*
G37*
G36*
G01X956948Y163792D02*
X956898Y163042D01*
X956498D01*
X956448Y163792D01*
Y163992D01*
X956948D01*
Y163792D01*
G37*
G36*
G01X957779Y164235D02*
X957284Y164800D01*
X957567Y165083D01*
X958132Y164588D01*
X958274Y164447D01*
X957920Y164093D01*
X957779Y164235D01*
G37*
G36*
G01X964495Y170111D02*
X964311Y170493D01*
X964608Y170790D01*
X964990Y170606D01*
X965131Y170464D01*
X964636Y169969D01*
X964495Y170111D01*
G37*
G36*
G01X964672Y169722D02*
X964856Y169340D01*
X964559Y169043D01*
X964177Y169227D01*
X964035Y169368D01*
X964530Y169863D01*
X964672Y169722D01*
G37*
G36*
G01X962488Y168791D02*
X962628Y169191D01*
X963048D01*
X963188Y168791D01*
Y168591D01*
X962488D01*
Y168791D01*
G37*
G36*
G01X961459Y167915D02*
X960964Y168480D01*
X961247Y168763D01*
X961812Y168268D01*
X961954Y168127D01*
X961600Y167773D01*
X961459Y167915D01*
G37*
G36*
G01X961174Y167065D02*
X961669Y166499D01*
X961387Y166216D01*
X960821Y166711D01*
X960679Y166852D01*
X961033Y167206D01*
X961174Y167065D01*
G37*
G36*
G01X967076Y172126D02*
X967260Y171744D01*
X966963Y171447D01*
X966581Y171631D01*
X966440Y171773D01*
X966935Y172268D01*
X967076Y172126D01*
G37*
G36*
G01X965697Y171313D02*
X965513Y171695D01*
X965810Y171992D01*
X966192Y171808D01*
X966334Y171667D01*
X965839Y171172D01*
X965697Y171313D01*
G37*
G36*
G01X965874Y170924D02*
X966058Y170542D01*
X965761Y170245D01*
X965379Y170429D01*
X965238Y170571D01*
X965732Y171065D01*
X965874Y170924D01*
G37*
G36*
G01X955148Y164192D02*
X955198Y164942D01*
X955598D01*
X955648Y164192D01*
Y163992D01*
X955148D01*
Y164192D01*
G37*
G36*
G01X954344Y402418D02*
X953962Y402234D01*
X953665Y402531D01*
X953849Y402913D01*
X953991Y403054D01*
X954486Y402559D01*
X954344Y402418D01*
G37*
G36*
G01X946671Y402651D02*
X946811Y403051D01*
X947231D01*
X947371Y402651D01*
Y402401D01*
X946671D01*
Y402651D01*
G37*
G36*
G01X944971D02*
X945111Y403051D01*
X945531D01*
X945671Y402651D01*
Y402401D01*
X944971D01*
Y402651D01*
G37*
G36*
G01X943271D02*
X943411Y403051D01*
X943831D01*
X943971Y402651D01*
Y402401D01*
X943271D01*
Y402651D01*
G37*
G36*
G01X941571D02*
X941711Y403051D01*
X942131D01*
X942271Y402651D01*
Y402401D01*
X941571D01*
Y402651D01*
G37*
G36*
G01X971294Y387749D02*
X970624Y388099D01*
Y388969D01*
X971294Y389319D01*
X971469D01*
Y387749D01*
X971294D01*
G37*
G36*
G01X934818Y408599D02*
X934678Y408199D01*
X934258D01*
X934118Y408599D01*
Y408799D01*
X934818D01*
Y408599D01*
G37*
G36*
G01X934968Y408999D02*
X935108Y409399D01*
X935528D01*
X935668Y408999D01*
Y408799D01*
X934968D01*
Y408999D01*
G37*
G36*
G01X937569Y408901D02*
X937951Y409085D01*
X938248Y408788D01*
X938064Y408406D01*
X937922Y408265D01*
X937427Y408760D01*
X937569Y408901D01*
G37*
G36*
G01X938382Y407522D02*
X938000Y407338D01*
X937703Y407635D01*
X937887Y408017D01*
X938028Y408159D01*
X938523Y407664D01*
X938382Y407522D01*
G37*
G36*
G01X936668Y408999D02*
X936808Y409399D01*
X937228D01*
X937368Y408999D01*
Y408799D01*
X936668D01*
Y408999D01*
G37*
G36*
G01X936518Y408599D02*
X936378Y408199D01*
X935958D01*
X935818Y408599D01*
Y408799D01*
X936518D01*
Y408599D01*
G37*
G36*
G01X939584Y406320D02*
X939202Y406136D01*
X938905Y406433D01*
X939089Y406815D01*
X939230Y406957D01*
X939725Y406462D01*
X939584Y406320D01*
G37*
G36*
G01X938771Y407699D02*
X939153Y407883D01*
X939450Y407586D01*
X939266Y407204D01*
X939124Y407063D01*
X938629Y407558D01*
X938771Y407699D01*
G37*
G36*
G01X940786Y405118D02*
X940404Y404934D01*
X940107Y405231D01*
X940291Y405613D01*
X940433Y405754D01*
X940928Y405259D01*
X940786Y405118D01*
G37*
G36*
G01X939973Y406497D02*
X940355Y406681D01*
X940652Y406384D01*
X940468Y406002D01*
X940326Y405861D01*
X939832Y406355D01*
X939973Y406497D01*
G37*
G36*
G01X933268Y408999D02*
X933408Y409399D01*
X933828D01*
X933968Y408999D01*
Y408799D01*
X933268D01*
Y408999D01*
G37*
G36*
G01X941571Y405051D02*
X941711Y405451D01*
X942131D01*
X942271Y405051D01*
Y404851D01*
X941571D01*
Y405051D01*
G37*
G36*
G01X944971D02*
X945111Y405451D01*
X945531D01*
X945671Y405051D01*
Y404851D01*
X944971D01*
Y405051D01*
G37*
G36*
G01X943271D02*
X943411Y405451D01*
X943831D01*
X943971Y405051D01*
Y404851D01*
X943271D01*
Y405051D01*
G37*
G36*
G01X946671D02*
X946811Y405451D01*
X947231D01*
X947371Y405051D01*
Y404851D01*
X946671D01*
Y405051D01*
G37*
G36*
G01X944821Y404651D02*
X944681Y404251D01*
X944261D01*
X944121Y404651D01*
Y404851D01*
X944821D01*
Y404651D01*
G37*
G36*
G01X943121D02*
X942981Y404251D01*
X942561D01*
X942421Y404651D01*
Y404851D01*
X943121D01*
Y404651D01*
G37*
G36*
G01X946521D02*
X946381Y404251D01*
X945961D01*
X945821Y404651D01*
Y404851D01*
X946521D01*
Y404651D01*
G37*
G36*
G01X948221D02*
X948081Y404251D01*
X947661D01*
X947521Y404651D01*
Y404851D01*
X948221D01*
Y404651D01*
G37*
G36*
G01X948371Y405051D02*
X948511Y405451D01*
X948931D01*
X949071Y405051D01*
Y404851D01*
X948371D01*
Y405051D01*
G37*
G36*
G01X950071D02*
X950211Y405451D01*
X950631D01*
X950771Y405051D01*
Y404851D01*
X950071D01*
Y405051D01*
G37*
G36*
G01X949921Y404651D02*
X949781Y404251D01*
X949361D01*
X949221Y404651D01*
Y404851D01*
X949921D01*
Y404651D01*
G37*
G36*
G01X951621D02*
X951481Y404251D01*
X951061D01*
X950921Y404651D01*
Y404851D01*
X951621D01*
Y404651D01*
G37*
G36*
G01X953531Y403797D02*
X953913Y403981D01*
X954210Y403684D01*
X954026Y403302D01*
X953884Y403161D01*
X953390Y403655D01*
X953531Y403797D01*
G37*
G36*
G01X952329Y404999D02*
X952711Y405183D01*
X953008Y404886D01*
X952824Y404504D01*
X952682Y404363D01*
X952188Y404857D01*
X952329Y404999D01*
G37*
G36*
G01X936518Y409799D02*
X936378Y409399D01*
X935958D01*
X935818Y409799D01*
Y409999D01*
X936518D01*
Y409799D01*
G37*
G36*
G01X934818D02*
X934678Y409399D01*
X934258D01*
X934118Y409799D01*
Y409999D01*
X934818D01*
Y409799D01*
G37*
G36*
G01X933118D02*
X932978Y409399D01*
X932558D01*
X932418Y409799D01*
Y409999D01*
X933118D01*
Y409799D01*
G37*
G36*
G01X934968Y410199D02*
X935108Y410599D01*
X935528D01*
X935668Y410199D01*
Y409999D01*
X934968D01*
Y410199D01*
G37*
G36*
G01X936668D02*
X936808Y410599D01*
X937228D01*
X937368Y410199D01*
Y409999D01*
X936668D01*
Y410199D01*
G37*
G36*
G01X933268D02*
X933408Y410599D01*
X933828D01*
X933968Y410199D01*
Y409999D01*
X933268D01*
Y410199D01*
G37*
G36*
G01X939231Y408371D02*
X938849Y408187D01*
X938552Y408484D01*
X938736Y408866D01*
X938877Y409008D01*
X939372Y408513D01*
X939231Y408371D01*
G37*
G36*
G01X939620Y408548D02*
X940002Y408732D01*
X940299Y408435D01*
X940115Y408053D01*
X939973Y407912D01*
X939478Y408407D01*
X939620Y408548D01*
G37*
G36*
G01X938418Y409750D02*
X938800Y409934D01*
X939097Y409637D01*
X938913Y409255D01*
X938771Y409114D01*
X938276Y409609D01*
X938418Y409750D01*
G37*
G36*
G01X931568Y410199D02*
X931708Y410599D01*
X932128D01*
X932268Y410199D01*
Y409999D01*
X931568D01*
Y410199D01*
G37*
G36*
G01X940433Y407169D02*
X940051Y406985D01*
X939754Y407282D01*
X939938Y407664D01*
X940079Y407806D01*
X940574Y407311D01*
X940433Y407169D01*
G37*
G36*
G01X940822Y407346D02*
X941204Y407530D01*
X941501Y407233D01*
X941317Y406851D01*
X941175Y406710D01*
X940680Y407205D01*
X940822Y407346D01*
G37*
G36*
G01X941635Y405967D02*
X941253Y405783D01*
X940956Y406080D01*
X941140Y406462D01*
X941281Y406604D01*
X941776Y406109D01*
X941635Y405967D01*
G37*
G36*
G01X946671Y406251D02*
X946811Y406651D01*
X947231D01*
X947371Y406251D01*
Y406051D01*
X946671D01*
Y406251D01*
G37*
G36*
G01X944971D02*
X945111Y406651D01*
X945531D01*
X945671Y406251D01*
Y406051D01*
X944971D01*
Y406251D01*
G37*
G36*
G01X943271D02*
X943411Y406651D01*
X943831D01*
X943971Y406251D01*
Y406051D01*
X943271D01*
Y406251D01*
G37*
G36*
G01X948221Y405851D02*
X948081Y405451D01*
X947661D01*
X947521Y405851D01*
Y406051D01*
X948221D01*
Y405851D01*
G37*
G36*
G01X946521D02*
X946381Y405451D01*
X945961D01*
X945821Y405851D01*
Y406051D01*
X946521D01*
Y405851D01*
G37*
G36*
G01X944821D02*
X944681Y405451D01*
X944261D01*
X944121Y405851D01*
Y406051D01*
X944821D01*
Y405851D01*
G37*
G36*
G01X943121D02*
X942981Y405451D01*
X942561D01*
X942421Y405851D01*
Y406051D01*
X943121D01*
Y405851D01*
G37*
G36*
G01X948371Y406251D02*
X948511Y406651D01*
X948931D01*
X949071Y406251D01*
Y406051D01*
X948371D01*
Y406251D01*
G37*
G36*
G01X950071D02*
X950211Y406651D01*
X950631D01*
X950771Y406251D01*
Y406051D01*
X950071D01*
Y406251D01*
G37*
G36*
G01X949921Y405851D02*
X949781Y405451D01*
X949361D01*
X949221Y405851D01*
Y406051D01*
X949921D01*
Y405851D01*
G37*
G36*
G01X951621D02*
X951481Y405451D01*
X951061D01*
X950921Y405851D01*
Y406051D01*
X951621D01*
Y405851D01*
G37*
G36*
G01X951771Y406251D02*
X951911Y406651D01*
X952331D01*
X952471Y406251D01*
Y406051D01*
X951771D01*
Y406251D01*
G37*
G36*
G01X955193Y403267D02*
X954811Y403083D01*
X954514Y403380D01*
X954698Y403762D01*
X954840Y403903D01*
X955335Y403408D01*
X955193Y403267D01*
G37*
G36*
G01X953991Y404469D02*
X953609Y404285D01*
X953312Y404582D01*
X953496Y404964D01*
X953637Y405106D01*
X954132Y404611D01*
X953991Y404469D01*
G37*
G36*
G01X954380Y404646D02*
X954762Y404830D01*
X955059Y404533D01*
X954875Y404151D01*
X954733Y404010D01*
X954239Y404504D01*
X954380Y404646D01*
G37*
G36*
G01X955582Y403444D02*
X955964Y403628D01*
X956261Y403331D01*
X956077Y402949D01*
X955936Y402807D01*
X955441Y403302D01*
X955582Y403444D01*
G37*
G36*
G01X953178Y405848D02*
X953560Y406032D01*
X953857Y405735D01*
X953673Y405353D01*
X953531Y405212D01*
X953037Y405706D01*
X953178Y405848D01*
G37*
G36*
G01X940370Y419127D02*
X939988Y418943D01*
X939691Y419240D01*
X939875Y419622D01*
X940016Y419763D01*
X940511Y419268D01*
X940370Y419127D01*
G37*
G36*
G01X939168Y420329D02*
X938786Y420145D01*
X938489Y420442D01*
X938673Y420824D01*
X938814Y420965D01*
X939309Y420470D01*
X939168Y420329D01*
G37*
G36*
G01X939556Y420505D02*
X939938Y420689D01*
X940235Y420392D01*
X940051Y420010D01*
X939910Y419869D01*
X939415Y420364D01*
X939556Y420505D01*
G37*
G36*
G01X940759Y419303D02*
X941140Y419487D01*
X941437Y419190D01*
X941254Y418808D01*
X941112Y418667D01*
X940617Y419162D01*
X940759Y419303D01*
G37*
G36*
G01X938354Y421707D02*
X938736Y421891D01*
X939033Y421594D01*
X938849Y421213D01*
X938708Y421071D01*
X938213Y421566D01*
X938354Y421707D01*
G37*
G36*
G01X937965Y421531D02*
X937584Y421347D01*
X937287Y421644D01*
X937470Y422026D01*
X937612Y422167D01*
X938107Y421672D01*
X937965Y421531D01*
G37*
G36*
G01X936763Y422733D02*
X936382Y422549D01*
X936085Y422846D01*
X936268Y423228D01*
X936410Y423369D01*
X936905Y422874D01*
X936763Y422733D01*
G37*
G36*
G01X937152Y422910D02*
X937534Y423093D01*
X937831Y422796D01*
X937647Y422415D01*
X937506Y422273D01*
X937011Y422768D01*
X937152Y422910D01*
G37*
G36*
G01X935950Y424112D02*
X936332Y424295D01*
X936629Y423999D01*
X936445Y423617D01*
X936304Y423475D01*
X935809Y423970D01*
X935950Y424112D01*
G37*
G36*
G01X935561Y423935D02*
X935180Y423751D01*
X934883Y424048D01*
X935066Y424430D01*
X935208Y424571D01*
X935703Y424076D01*
X935561Y423935D01*
G37*
G36*
G01X941572Y417924D02*
X941190Y417741D01*
X940893Y418038D01*
X941077Y418419D01*
X941218Y418561D01*
X941713Y418066D01*
X941572Y417924D01*
G37*
G36*
G01X941961Y418101D02*
X942342Y418285D01*
X942639Y417988D01*
X942456Y417606D01*
X942314Y417465D01*
X941819Y417960D01*
X941961Y418101D01*
G37*
G36*
G01X946671Y414651D02*
X946811Y415051D01*
X947231D01*
X947371Y414651D01*
Y414451D01*
X946671D01*
Y414651D01*
G37*
G36*
G01X948221Y414251D02*
X948081Y413851D01*
X947661D01*
X947521Y414251D01*
Y414451D01*
X948221D01*
Y414251D01*
G37*
G36*
G01X942774Y416722D02*
X942392Y416539D01*
X942095Y416836D01*
X942279Y417217D01*
X942420Y417359D01*
X942915Y416864D01*
X942774Y416722D01*
G37*
G36*
G01X943976Y415520D02*
X943594Y415336D01*
X943297Y415633D01*
X943481Y416015D01*
X943622Y416157D01*
X944117Y415662D01*
X943976Y415520D01*
G37*
G36*
G01X943163Y416899D02*
X943545Y417083D01*
X943842Y416786D01*
X943658Y416404D01*
X943516Y416263D01*
X943021Y416758D01*
X943163Y416899D01*
G37*
G36*
G01X944365Y415697D02*
X944747Y415881D01*
X945044Y415584D01*
X944860Y415202D01*
X944718Y415061D01*
X944223Y415556D01*
X944365Y415697D01*
G37*
G36*
G01X946521Y414251D02*
X946381Y413851D01*
X945961D01*
X945821Y414251D01*
Y414451D01*
X946521D01*
Y414251D01*
G37*
G36*
G01X948371Y414651D02*
X948511Y415051D01*
X948931D01*
X949071Y414651D01*
Y414451D01*
X948371D01*
Y414651D01*
G37*
G36*
G01X950071D02*
X950211Y415051D01*
X950631D01*
X950771Y414651D01*
Y414451D01*
X950071D01*
Y414651D01*
G37*
G36*
G01X951771D02*
X951911Y415051D01*
X952331D01*
X952471Y414651D01*
Y414451D01*
X951771D01*
Y414651D01*
G37*
G36*
G01X949921Y414251D02*
X949781Y413851D01*
X949361D01*
X949221Y414251D01*
Y414451D01*
X949921D01*
Y414251D01*
G37*
G36*
G01X951621D02*
X951481Y413851D01*
X951061D01*
X950921Y414251D01*
Y414451D01*
X951621D01*
Y414251D01*
G37*
G36*
G01X953321D02*
X953181Y413851D01*
X952761D01*
X952621Y414251D01*
Y414451D01*
X953321D01*
Y414251D01*
G37*
G36*
G01X957530Y412816D02*
X957148Y412632D01*
X956851Y412929D01*
X957035Y413311D01*
X957176Y413453D01*
X957671Y412958D01*
X957530Y412816D01*
G37*
G36*
G01X956717Y414195D02*
X957099Y414379D01*
X957396Y414082D01*
X957212Y413700D01*
X957070Y413559D01*
X956575Y414054D01*
X956717Y414195D01*
G37*
G36*
G01X953471Y414651D02*
X953611Y415051D01*
X954031D01*
X954171Y414651D01*
Y414451D01*
X953471D01*
Y414651D01*
G37*
G36*
G01X955021Y414251D02*
X954881Y413851D01*
X954461D01*
X954321Y414251D01*
Y414451D01*
X955021D01*
Y414251D01*
G37*
G36*
G01X955171Y414651D02*
X955311Y415051D01*
X955731D01*
X955871Y414651D01*
Y414451D01*
X955171D01*
Y414651D01*
G37*
G36*
G01X958732Y411614D02*
X958350Y411430D01*
X958053Y411727D01*
X958237Y412109D01*
X958378Y412251D01*
X958873Y411756D01*
X958732Y411614D01*
G37*
G36*
G01X959934Y410412D02*
X959552Y410228D01*
X959255Y410525D01*
X959439Y410907D01*
X959580Y411049D01*
X960075Y410554D01*
X959934Y410412D01*
G37*
G36*
G01X961136Y409210D02*
X960754Y409026D01*
X960457Y409323D01*
X960641Y409705D01*
X960783Y409846D01*
X961278Y409351D01*
X961136Y409210D01*
G37*
G36*
G01X962338Y408008D02*
X961956Y407824D01*
X961659Y408121D01*
X961843Y408503D01*
X961985Y408644D01*
X962480Y408149D01*
X962338Y408008D01*
G37*
G36*
G01X963540Y406806D02*
X963158Y406622D01*
X962861Y406919D01*
X963045Y407301D01*
X963187Y407442D01*
X963682Y406947D01*
X963540Y406806D01*
G37*
G36*
G01X959121Y411791D02*
X959503Y411975D01*
X959800Y411678D01*
X959616Y411296D01*
X959474Y411155D01*
X958979Y411650D01*
X959121Y411791D01*
G37*
G36*
G01X960323Y410589D02*
X960705Y410773D01*
X961002Y410476D01*
X960818Y410094D01*
X960676Y409953D01*
X960182Y410447D01*
X960323Y410589D01*
G37*
G36*
G01X961525Y409387D02*
X961907Y409571D01*
X962204Y409274D01*
X962020Y408892D01*
X961879Y408750D01*
X961384Y409245D01*
X961525Y409387D01*
G37*
G36*
G01X962727Y408185D02*
X963109Y408369D01*
X963406Y408072D01*
X963222Y407690D01*
X963081Y407548D01*
X962586Y408043D01*
X962727Y408185D01*
G37*
G36*
G01X957919Y412993D02*
X958301Y413177D01*
X958598Y412880D01*
X958414Y412498D01*
X958272Y412357D01*
X957777Y412852D01*
X957919Y412993D01*
G37*
G36*
G01X934748Y425314D02*
X935130Y425497D01*
X935427Y425201D01*
X935243Y424819D01*
X935102Y424677D01*
X934607Y425172D01*
X934748Y425314D01*
G37*
G36*
G01X941218Y419975D02*
X940836Y419791D01*
X940539Y420088D01*
X940723Y420470D01*
X940900Y420647D01*
X941395Y420152D01*
X941218Y419975D01*
G37*
G36*
G01X940016Y421177D02*
X939634Y420993D01*
X939337Y421290D01*
X939521Y421672D01*
X939698Y421849D01*
X940193Y421354D01*
X940016Y421177D01*
G37*
G36*
G01X938814Y422379D02*
X938432Y422195D01*
X938135Y422492D01*
X938319Y422874D01*
X938496Y423051D01*
X938991Y422556D01*
X938814Y422379D01*
G37*
G36*
G01X937612Y423581D02*
X937230Y423398D01*
X936933Y423695D01*
X937117Y424076D01*
X937294Y424253D01*
X937789Y423758D01*
X937612Y423581D01*
G37*
G36*
G01X936410Y424784D02*
X936028Y424600D01*
X935731Y424897D01*
X935915Y425278D01*
X936092Y425455D01*
X936587Y424960D01*
X936410Y424784D01*
G37*
G36*
G01X935208Y425986D02*
X934826Y425802D01*
X934529Y426099D01*
X934713Y426481D01*
X934890Y426657D01*
X935385Y426162D01*
X935208Y425986D01*
G37*
G36*
G01X943622Y417571D02*
X943241Y417387D01*
X942944Y417684D01*
X943127Y418066D01*
X943304Y418243D01*
X943799Y417748D01*
X943622Y417571D01*
G37*
G36*
G01X948221Y415451D02*
X948081Y415051D01*
X947661D01*
X947521Y415451D01*
Y415701D01*
X948221D01*
Y415451D01*
G37*
G36*
G01X944825Y416369D02*
X944443Y416185D01*
X944146Y416482D01*
X944330Y416864D01*
X944506Y417041D01*
X945001Y416546D01*
X944825Y416369D01*
G37*
G36*
G01X942420Y418773D02*
X942039Y418589D01*
X941742Y418886D01*
X941925Y419268D01*
X942102Y419445D01*
X942597Y418950D01*
X942420Y418773D01*
G37*
G36*
G01X949921Y415451D02*
X949781Y415051D01*
X949361D01*
X949221Y415451D01*
Y415701D01*
X949921D01*
Y415451D01*
G37*
G36*
G01X951621D02*
X951481Y415051D01*
X951061D01*
X950921Y415451D01*
Y415701D01*
X951621D01*
Y415451D01*
G37*
G36*
G01X953321D02*
X953181Y415051D01*
X952761D01*
X952621Y415451D01*
Y415701D01*
X953321D01*
Y415451D01*
G37*
G36*
G01X955021D02*
X954881Y415051D01*
X954461D01*
X954321Y415451D01*
Y415701D01*
X955021D01*
Y415451D01*
G37*
G36*
G01X957177Y414867D02*
X956795Y414683D01*
X956498Y414980D01*
X956682Y415362D01*
X956858Y415539D01*
X957353Y415044D01*
X957177Y414867D01*
G37*
G36*
G01X959581Y412463D02*
X959199Y412279D01*
X958902Y412576D01*
X959086Y412958D01*
X959262Y413135D01*
X959757Y412640D01*
X959581Y412463D01*
G37*
G36*
G01X960783Y411261D02*
X960401Y411077D01*
X960104Y411374D01*
X960288Y411756D01*
X960464Y411933D01*
X960959Y411438D01*
X960783Y411261D01*
G37*
G36*
G01X961985Y410059D02*
X961603Y409875D01*
X961306Y410172D01*
X961490Y410554D01*
X961667Y410730D01*
X962162Y410235D01*
X961985Y410059D01*
G37*
G36*
G01X963187Y408857D02*
X962805Y408673D01*
X962508Y408970D01*
X962692Y409352D01*
X962869Y409528D01*
X963364Y409033D01*
X963187Y408857D01*
G37*
G36*
G01X964389Y407655D02*
X964007Y407471D01*
X963710Y407768D01*
X963894Y408150D01*
X964071Y408326D01*
X964566Y407831D01*
X964389Y407655D01*
G37*
G36*
G01X958379Y413665D02*
X957997Y413481D01*
X957700Y413778D01*
X957884Y414160D01*
X958060Y414337D01*
X958555Y413842D01*
X958379Y413665D01*
G37*
G36*
G01X946521Y415451D02*
X946381Y415051D01*
X945961D01*
X945821Y415451D01*
Y415701D01*
X946521D01*
Y415451D01*
G37*
G36*
G01X937073Y406001D02*
X937455Y406185D01*
X937752Y405888D01*
X937568Y405506D01*
X937391Y405330D01*
X936896Y405825D01*
X937073Y406001D01*
G37*
G36*
G01X934968Y406599D02*
X935108Y406999D01*
X935528D01*
X935668Y406599D01*
Y406349D01*
X934968D01*
Y406599D01*
G37*
G36*
G01X933042Y405480D02*
X932858Y405862D01*
X933155Y406159D01*
X933537Y405975D01*
X933714Y405799D01*
X933219Y405304D01*
X933042Y405480D01*
G37*
G36*
G01X938275Y404799D02*
X938657Y404983D01*
X938954Y404686D01*
X938770Y404304D01*
X938593Y404128D01*
X938099Y404622D01*
X938275Y404799D01*
G37*
G36*
G01X939477Y403597D02*
X939859Y403781D01*
X940156Y403484D01*
X939972Y403102D01*
X939795Y402926D01*
X939301Y403420D01*
X939477Y403597D01*
G37*
G36*
G01X931840Y404278D02*
X931656Y404660D01*
X931953Y404957D01*
X932335Y404773D01*
X932511Y404596D01*
X932017Y404102D01*
X931840Y404278D01*
G37*
G36*
G01X937922Y406850D02*
X938304Y407034D01*
X938601Y406737D01*
X938417Y406355D01*
X938275Y406214D01*
X937780Y406709D01*
X937922Y406850D01*
G37*
G36*
G01X934968Y407799D02*
X935108Y408199D01*
X935528D01*
X935668Y407799D01*
Y407599D01*
X934968D01*
Y407799D01*
G37*
G36*
G01X937533Y406673D02*
X937151Y406489D01*
X936854Y406786D01*
X937038Y407168D01*
X937179Y407310D01*
X937674Y406815D01*
X937533Y406673D01*
G37*
G36*
G01X936518Y407399D02*
X936378Y406999D01*
X935958D01*
X935818Y407399D01*
Y407599D01*
X936518D01*
Y407399D01*
G37*
G36*
G01X934818D02*
X934678Y406999D01*
X934258D01*
X934118Y407399D01*
Y407599D01*
X934818D01*
Y407399D01*
G37*
G36*
G01X933572Y407142D02*
X933756Y406760D01*
X933459Y406463D01*
X933077Y406647D01*
X932936Y406789D01*
X933431Y407284D01*
X933572Y407142D01*
G37*
G36*
G01X932193Y406329D02*
X932009Y406711D01*
X932306Y407008D01*
X932688Y406824D01*
X932865Y406648D01*
X932370Y406153D01*
X932193Y406329D01*
G37*
G36*
G01X938735Y405471D02*
X938353Y405287D01*
X938056Y405584D01*
X938240Y405966D01*
X938381Y406108D01*
X938876Y405613D01*
X938735Y405471D01*
G37*
G36*
G01X939937Y404269D02*
X939555Y404085D01*
X939258Y404382D01*
X939442Y404764D01*
X939584Y404905D01*
X940079Y404410D01*
X939937Y404269D01*
G37*
G36*
G01X939124Y405648D02*
X939506Y405832D01*
X939803Y405535D01*
X939619Y405153D01*
X939477Y405012D01*
X938983Y405506D01*
X939124Y405648D01*
G37*
G36*
G01X932370Y405940D02*
X932554Y405558D01*
X932257Y405261D01*
X931875Y405445D01*
X931734Y405587D01*
X932229Y406082D01*
X932370Y405940D01*
G37*
G36*
G01X940326Y404446D02*
X940708Y404630D01*
X941005Y404333D01*
X940821Y403951D01*
X940679Y403810D01*
X940185Y404304D01*
X940326Y404446D01*
G37*
G36*
G01X930991Y405127D02*
X930807Y405509D01*
X931104Y405806D01*
X931486Y405622D01*
X931663Y405446D01*
X931168Y404951D01*
X930991Y405127D01*
G37*
G36*
G01X941571Y403851D02*
X941711Y404251D01*
X942131D01*
X942271Y403851D01*
Y403651D01*
X941571D01*
Y403851D01*
G37*
G36*
G01X944821Y403451D02*
X944681Y403051D01*
X944261D01*
X944121Y403451D01*
Y403651D01*
X944821D01*
Y403451D01*
G37*
G36*
G01X943121D02*
X942981Y403051D01*
X942561D01*
X942421Y403451D01*
Y403651D01*
X943121D01*
Y403451D01*
G37*
G36*
G01X946521D02*
X946381Y403051D01*
X945961D01*
X945821Y403451D01*
Y403651D01*
X946521D01*
Y403451D01*
G37*
G36*
G01X943271Y403851D02*
X943411Y404251D01*
X943831D01*
X943971Y403851D01*
Y403651D01*
X943271D01*
Y403851D01*
G37*
G36*
G01X944971D02*
X945111Y404251D01*
X945531D01*
X945671Y403851D01*
Y403651D01*
X944971D01*
Y403851D01*
G37*
G36*
G01X946671D02*
X946811Y404251D01*
X947231D01*
X947371Y403851D01*
Y403651D01*
X946671D01*
Y403851D01*
G37*
G36*
G01X948371D02*
X948511Y404251D01*
X948931D01*
X949071Y403851D01*
Y403651D01*
X948371D01*
Y403851D01*
G37*
G36*
G01X939874Y416226D02*
X939492Y416043D01*
X939195Y416340D01*
X939379Y416721D01*
X939520Y416863D01*
X940015Y416368D01*
X939874Y416226D01*
G37*
G36*
G01X938672Y417429D02*
X938290Y417245D01*
X937993Y417542D01*
X938177Y417924D01*
X938318Y418065D01*
X938813Y417570D01*
X938672Y417429D01*
G37*
G36*
G01X939061Y417605D02*
X939442Y417789D01*
X939739Y417492D01*
X939556Y417110D01*
X939414Y416969D01*
X938919Y417464D01*
X939061Y417605D01*
G37*
G36*
G01X937858Y418807D02*
X938240Y418991D01*
X938537Y418694D01*
X938353Y418312D01*
X938212Y418171D01*
X937717Y418666D01*
X937858Y418807D01*
G37*
G36*
G01X936656Y420009D02*
X937038Y420193D01*
X937335Y419896D01*
X937151Y419514D01*
X937010Y419373D01*
X936515Y419868D01*
X936656Y420009D01*
G37*
G36*
G01X937470Y418631D02*
X937088Y418447D01*
X936791Y418744D01*
X936975Y419126D01*
X937116Y419267D01*
X937611Y418772D01*
X937470Y418631D01*
G37*
G36*
G01X941076Y415024D02*
X940694Y414841D01*
X940397Y415138D01*
X940581Y415519D01*
X940722Y415661D01*
X941217Y415166D01*
X941076Y415024D01*
G37*
G36*
G01X940263Y416403D02*
X940644Y416587D01*
X940941Y416290D01*
X940758Y415908D01*
X940616Y415767D01*
X940121Y416262D01*
X940263Y416403D01*
G37*
G36*
G01X942278Y413822D02*
X941896Y413638D01*
X941599Y413935D01*
X941783Y414317D01*
X941924Y414459D01*
X942419Y413964D01*
X942278Y413822D01*
G37*
G36*
G01X941465Y415201D02*
X941847Y415385D01*
X942144Y415088D01*
X941960Y414706D01*
X941818Y414565D01*
X941323Y415060D01*
X941465Y415201D01*
G37*
G36*
G01X943480Y412620D02*
X943098Y412436D01*
X942801Y412733D01*
X942985Y413115D01*
X943126Y413257D01*
X943621Y412762D01*
X943480Y412620D01*
G37*
G36*
G01X942667Y413999D02*
X943049Y414183D01*
X943346Y413886D01*
X943162Y413504D01*
X943020Y413363D01*
X942525Y413858D01*
X942667Y413999D01*
G37*
G36*
G01X943869Y412797D02*
X944251Y412981D01*
X944548Y412684D01*
X944364Y412302D01*
X944222Y412161D01*
X943727Y412656D01*
X943869Y412797D01*
G37*
G36*
G01X946671Y412251D02*
X946811Y412651D01*
X947231D01*
X947371Y412251D01*
Y412051D01*
X946671D01*
Y412251D01*
G37*
G36*
G01X944971D02*
X945111Y412651D01*
X945531D01*
X945671Y412251D01*
Y412051D01*
X944971D01*
Y412251D01*
G37*
G36*
G01X948221Y411851D02*
X948081Y411451D01*
X947661D01*
X947521Y411851D01*
Y412051D01*
X948221D01*
Y411851D01*
G37*
G36*
G01X946521D02*
X946381Y411451D01*
X945961D01*
X945821Y411851D01*
Y412051D01*
X946521D01*
Y411851D01*
G37*
G36*
G01X949921D02*
X949781Y411451D01*
X949361D01*
X949221Y411851D01*
Y412051D01*
X949921D01*
Y411851D01*
G37*
G36*
G01X951621D02*
X951481Y411451D01*
X951061D01*
X950921Y411851D01*
Y412051D01*
X951621D01*
Y411851D01*
G37*
G36*
G01X953321D02*
X953181Y411451D01*
X952761D01*
X952621Y411851D01*
Y412051D01*
X953321D01*
Y411851D01*
G37*
G36*
G01X948371Y412251D02*
X948511Y412651D01*
X948931D01*
X949071Y412251D01*
Y412051D01*
X948371D01*
Y412251D01*
G37*
G36*
G01X950071D02*
X950211Y412651D01*
X950631D01*
X950771Y412251D01*
Y412051D01*
X950071D01*
Y412251D01*
G37*
G36*
G01X951771D02*
X951911Y412651D01*
X952331D01*
X952471Y412251D01*
Y412051D01*
X951771D01*
Y412251D01*
G37*
G36*
G01X955832Y411118D02*
X955450Y410934D01*
X955153Y411231D01*
X955337Y411613D01*
X955478Y411755D01*
X955973Y411260D01*
X955832Y411118D01*
G37*
G36*
G01X957034Y409916D02*
X956652Y409732D01*
X956355Y410029D01*
X956539Y410411D01*
X956680Y410553D01*
X957175Y410058D01*
X957034Y409916D01*
G37*
G36*
G01X959438Y407512D02*
X959056Y407328D01*
X958759Y407625D01*
X958943Y408007D01*
X959085Y408148D01*
X959580Y407653D01*
X959438Y407512D01*
G37*
G36*
G01X960640Y406310D02*
X960258Y406126D01*
X959961Y406423D01*
X960145Y406805D01*
X960287Y406946D01*
X960782Y406451D01*
X960640Y406310D01*
G37*
G36*
G01X957423Y410093D02*
X957805Y410277D01*
X958102Y409980D01*
X957918Y409598D01*
X957776Y409457D01*
X957281Y409952D01*
X957423Y410093D01*
G37*
G36*
G01X956221Y411295D02*
X956603Y411479D01*
X956900Y411182D01*
X956716Y410800D01*
X956574Y410659D01*
X956079Y411154D01*
X956221Y411295D01*
G37*
G36*
G01X958625Y408891D02*
X959007Y409075D01*
X959304Y408778D01*
X959120Y408396D01*
X958978Y408255D01*
X958484Y408749D01*
X958625Y408891D01*
G37*
G36*
G01X959827Y407689D02*
X960209Y407873D01*
X960506Y407576D01*
X960322Y407194D01*
X960181Y407052D01*
X959686Y407547D01*
X959827Y407689D01*
G37*
G36*
G01X961029Y406487D02*
X961411Y406671D01*
X961708Y406374D01*
X961524Y405992D01*
X961383Y405850D01*
X960888Y406345D01*
X961029Y406487D01*
G37*
G36*
G01X953471Y412251D02*
X953611Y412651D01*
X954031D01*
X954171Y412251D01*
Y412051D01*
X953471D01*
Y412251D01*
G37*
G36*
G01X958236Y408714D02*
X957854Y408530D01*
X957557Y408827D01*
X957741Y409209D01*
X957882Y409351D01*
X958377Y408856D01*
X958236Y408714D01*
G37*
G36*
G01X938319Y419480D02*
X937937Y419296D01*
X937640Y419593D01*
X937824Y419975D01*
X937965Y420116D01*
X938460Y419621D01*
X938319Y419480D01*
G37*
G36*
G01X937116Y420682D02*
X936735Y420498D01*
X936438Y420795D01*
X936621Y421177D01*
X936763Y421318D01*
X937258Y420823D01*
X937116Y420682D01*
G37*
G36*
G01X937505Y420858D02*
X937887Y421042D01*
X938184Y420745D01*
X938000Y420364D01*
X937859Y420222D01*
X937364Y420717D01*
X937505Y420858D01*
G37*
G36*
G01X939521Y418278D02*
X939139Y418094D01*
X938842Y418391D01*
X939026Y418773D01*
X939167Y418914D01*
X939662Y418419D01*
X939521Y418278D01*
G37*
G36*
G01X938707Y419656D02*
X939089Y419840D01*
X939386Y419543D01*
X939202Y419161D01*
X939061Y419020D01*
X938566Y419515D01*
X938707Y419656D01*
G37*
G36*
G01X940723Y417075D02*
X940341Y416892D01*
X940044Y417189D01*
X940228Y417570D01*
X940369Y417712D01*
X940864Y417217D01*
X940723Y417075D01*
G37*
G36*
G01X939910Y418454D02*
X940291Y418638D01*
X940588Y418341D01*
X940405Y417959D01*
X940263Y417818D01*
X939768Y418313D01*
X939910Y418454D01*
G37*
G36*
G01X936303Y422061D02*
X936685Y422244D01*
X936982Y421947D01*
X936798Y421566D01*
X936657Y421424D01*
X936162Y421919D01*
X936303Y422061D01*
G37*
G36*
G01X941925Y415873D02*
X941543Y415690D01*
X941246Y415987D01*
X941430Y416368D01*
X941571Y416510D01*
X942066Y416015D01*
X941925Y415873D01*
G37*
G36*
G01X941112Y417252D02*
X941493Y417436D01*
X941790Y417139D01*
X941607Y416757D01*
X941465Y416616D01*
X940970Y417111D01*
X941112Y417252D01*
G37*
G36*
G01X946671Y413451D02*
X946811Y413851D01*
X947231D01*
X947371Y413451D01*
Y413251D01*
X946671D01*
Y413451D01*
G37*
G36*
G01X948221Y413051D02*
X948081Y412651D01*
X947661D01*
X947521Y413051D01*
Y413251D01*
X948221D01*
Y413051D01*
G37*
G36*
G01X946521D02*
X946381Y412651D01*
X945961D01*
X945821Y413051D01*
Y413251D01*
X946521D01*
Y413051D01*
G37*
G36*
G01X943127Y414671D02*
X942745Y414487D01*
X942448Y414784D01*
X942632Y415166D01*
X942773Y415308D01*
X943268Y414813D01*
X943127Y414671D01*
G37*
G36*
G01X944329Y413469D02*
X943947Y413285D01*
X943650Y413582D01*
X943834Y413964D01*
X943975Y414106D01*
X944470Y413611D01*
X944329Y413469D01*
G37*
G36*
G01X942314Y416050D02*
X942696Y416234D01*
X942993Y415937D01*
X942809Y415555D01*
X942667Y415414D01*
X942172Y415909D01*
X942314Y416050D01*
G37*
G36*
G01X943516Y414848D02*
X943898Y415032D01*
X944195Y414735D01*
X944011Y414353D01*
X943869Y414212D01*
X943374Y414707D01*
X943516Y414848D01*
G37*
G36*
G01X944971Y413451D02*
X945111Y413851D01*
X945531D01*
X945671Y413451D01*
Y413251D01*
X944971D01*
Y413451D01*
G37*
G36*
G01X951771D02*
X951911Y413851D01*
X952331D01*
X952471Y413451D01*
Y413251D01*
X951771D01*
Y413451D01*
G37*
G36*
G01X950071D02*
X950211Y413851D01*
X950631D01*
X950771Y413451D01*
Y413251D01*
X950071D01*
Y413451D01*
G37*
G36*
G01X948371D02*
X948511Y413851D01*
X948931D01*
X949071Y413451D01*
Y413251D01*
X948371D01*
Y413451D01*
G37*
G36*
G01X953321Y413051D02*
X953181Y412651D01*
X952761D01*
X952621Y413051D01*
Y413251D01*
X953321D01*
Y413051D01*
G37*
G36*
G01X951621D02*
X951481Y412651D01*
X951061D01*
X950921Y413051D01*
Y413251D01*
X951621D01*
Y413051D01*
G37*
G36*
G01X949921D02*
X949781Y412651D01*
X949361D01*
X949221Y413051D01*
Y413251D01*
X949921D01*
Y413051D01*
G37*
G36*
G01X953471Y413451D02*
X953611Y413851D01*
X954031D01*
X954171Y413451D01*
Y413251D01*
X953471D01*
Y413451D01*
G37*
G36*
G01X955021Y413051D02*
X954881Y412651D01*
X954461D01*
X954321Y413051D01*
Y413251D01*
X955021D01*
Y413051D01*
G37*
G36*
G01X955868Y413346D02*
X956250Y413530D01*
X956547Y413233D01*
X956363Y412851D01*
X956221Y412710D01*
X955726Y413205D01*
X955868Y413346D01*
G37*
G36*
G01X960287Y408361D02*
X959905Y408177D01*
X959608Y408474D01*
X959792Y408856D01*
X959934Y408997D01*
X960429Y408502D01*
X960287Y408361D01*
G37*
G36*
G01X961489Y407159D02*
X961107Y406975D01*
X960810Y407272D01*
X960994Y407654D01*
X961136Y407795D01*
X961631Y407300D01*
X961489Y407159D01*
G37*
G36*
G01X962691Y405957D02*
X962309Y405773D01*
X962012Y406070D01*
X962196Y406452D01*
X962338Y406593D01*
X962833Y406098D01*
X962691Y405957D01*
G37*
G36*
G01X959085Y409563D02*
X958703Y409379D01*
X958406Y409676D01*
X958590Y410058D01*
X958731Y410200D01*
X959226Y409705D01*
X959085Y409563D01*
G37*
G36*
G01X957883Y410765D02*
X957501Y410581D01*
X957204Y410878D01*
X957388Y411260D01*
X957529Y411402D01*
X958024Y410907D01*
X957883Y410765D01*
G37*
G36*
G01X956681Y411967D02*
X956299Y411783D01*
X956002Y412080D01*
X956186Y412462D01*
X956327Y412604D01*
X956822Y412109D01*
X956681Y411967D01*
G37*
G36*
G01X960676Y408538D02*
X961058Y408722D01*
X961355Y408425D01*
X961171Y408043D01*
X961030Y407901D01*
X960535Y408396D01*
X960676Y408538D01*
G37*
G36*
G01X961878Y407336D02*
X962260Y407520D01*
X962557Y407223D01*
X962373Y406841D01*
X962232Y406699D01*
X961737Y407194D01*
X961878Y407336D01*
G37*
G36*
G01X959474Y409740D02*
X959856Y409924D01*
X960153Y409627D01*
X959969Y409245D01*
X959827Y409104D01*
X959333Y409598D01*
X959474Y409740D01*
G37*
G36*
G01X957070Y412144D02*
X957452Y412328D01*
X957749Y412031D01*
X957565Y411649D01*
X957423Y411508D01*
X956928Y412003D01*
X957070Y412144D01*
G37*
G36*
G01X958272Y410942D02*
X958654Y411126D01*
X958951Y410829D01*
X958767Y410447D01*
X958625Y410306D01*
X958130Y410801D01*
X958272Y410942D01*
G37*
G36*
G01X938529Y412477D02*
X938147Y412294D01*
X937850Y412591D01*
X938034Y412972D01*
X938175Y413114D01*
X938670Y412619D01*
X938529Y412477D01*
G37*
G36*
G01X939731Y411275D02*
X939349Y411091D01*
X939052Y411388D01*
X939236Y411770D01*
X939377Y411912D01*
X939872Y411417D01*
X939731Y411275D01*
G37*
G36*
G01X938918Y412654D02*
X939300Y412838D01*
X939597Y412541D01*
X939413Y412159D01*
X939271Y412018D01*
X938776Y412513D01*
X938918Y412654D01*
G37*
G36*
G01X940933Y410073D02*
X940551Y409889D01*
X940254Y410186D01*
X940438Y410568D01*
X940579Y410710D01*
X941074Y410215D01*
X940933Y410073D01*
G37*
G36*
G01X940120Y411452D02*
X940502Y411636D01*
X940799Y411339D01*
X940615Y410957D01*
X940473Y410816D01*
X939978Y411311D01*
X940120Y411452D01*
G37*
G36*
G01X942135Y408871D02*
X941753Y408687D01*
X941456Y408984D01*
X941640Y409366D01*
X941781Y409508D01*
X942276Y409013D01*
X942135Y408871D01*
G37*
G36*
G01X941322Y410250D02*
X941704Y410434D01*
X942001Y410137D01*
X941817Y409755D01*
X941675Y409614D01*
X941180Y410109D01*
X941322Y410250D01*
G37*
G36*
G01X946671Y408651D02*
X946811Y409051D01*
X947231D01*
X947371Y408651D01*
Y408451D01*
X946671D01*
Y408651D01*
G37*
G36*
G01X944971D02*
X945111Y409051D01*
X945531D01*
X945671Y408651D01*
Y408451D01*
X944971D01*
Y408651D01*
G37*
G36*
G01X948221Y408251D02*
X948081Y407851D01*
X947661D01*
X947521Y408251D01*
Y408451D01*
X948221D01*
Y408251D01*
G37*
G36*
G01X946521D02*
X946381Y407851D01*
X945961D01*
X945821Y408251D01*
Y408451D01*
X946521D01*
Y408251D01*
G37*
G36*
G01X944821D02*
X944681Y407851D01*
X944261D01*
X944121Y408251D01*
Y408451D01*
X944821D01*
Y408251D01*
G37*
G36*
G01X943271Y408651D02*
X943411Y409051D01*
X943831D01*
X943971Y408651D01*
Y408451D01*
X943271D01*
Y408651D01*
G37*
G36*
G01X948371D02*
X948511Y409051D01*
X948931D01*
X949071Y408651D01*
Y408451D01*
X948371D01*
Y408651D01*
G37*
G36*
G01X950071D02*
X950211Y409051D01*
X950631D01*
X950771Y408651D01*
Y408451D01*
X950071D01*
Y408651D01*
G37*
G36*
G01X951771D02*
X951911Y409051D01*
X952331D01*
X952471Y408651D01*
Y408451D01*
X951771D01*
Y408651D01*
G37*
G36*
G01X949921Y408251D02*
X949781Y407851D01*
X949361D01*
X949221Y408251D01*
Y408451D01*
X949921D01*
Y408251D01*
G37*
G36*
G01X951621D02*
X951481Y407851D01*
X951061D01*
X950921Y408251D01*
Y408451D01*
X951621D01*
Y408251D01*
G37*
G36*
G01X953321D02*
X953181Y407851D01*
X952761D01*
X952621Y408251D01*
Y408451D01*
X953321D01*
Y408251D01*
G37*
G36*
G01X956891Y404965D02*
X956509Y404781D01*
X956212Y405078D01*
X956396Y405460D01*
X956538Y405601D01*
X957033Y405106D01*
X956891Y404965D01*
G37*
G36*
G01X955689Y406167D02*
X955307Y405983D01*
X955010Y406280D01*
X955194Y406662D01*
X955335Y406804D01*
X955830Y406309D01*
X955689Y406167D01*
G37*
G36*
G01X954487Y407369D02*
X954105Y407185D01*
X953808Y407482D01*
X953992Y407864D01*
X954133Y408006D01*
X954628Y407511D01*
X954487Y407369D01*
G37*
G36*
G01X954876Y407546D02*
X955258Y407730D01*
X955555Y407433D01*
X955371Y407051D01*
X955229Y406910D01*
X954734Y407405D01*
X954876Y407546D01*
G37*
G36*
G01X956078Y406344D02*
X956460Y406528D01*
X956757Y406231D01*
X956573Y405849D01*
X956431Y405708D01*
X955937Y406202D01*
X956078Y406344D01*
G37*
G36*
G01X957280Y405142D02*
X957662Y405326D01*
X957959Y405029D01*
X957775Y404647D01*
X957634Y404505D01*
X957139Y405000D01*
X957280Y405142D01*
G37*
G36*
G01X966622Y421064D02*
X967187Y421559D01*
X967470Y421276D01*
X966975Y420711D01*
X966834Y420569D01*
X966480Y420923D01*
X966622Y421064D01*
G37*
G36*
G01X968460Y419226D02*
X969026Y419721D01*
X969309Y419438D01*
X968814Y418872D01*
X968672Y418731D01*
X968319Y419084D01*
X968460Y419226D01*
G37*
G36*
G01X967612Y419509D02*
X967046Y419014D01*
X966763Y419296D01*
X967258Y419862D01*
X967400Y420003D01*
X967753Y419650D01*
X967612Y419509D01*
G37*
G36*
G01X969450Y417670D02*
X968884Y417175D01*
X968602Y417458D01*
X969097Y418024D01*
X969238Y418165D01*
X969592Y417811D01*
X969450Y417670D01*
G37*
G36*
G01X970299Y417387D02*
X970864Y417882D01*
X971147Y417599D01*
X970652Y417034D01*
X970511Y416892D01*
X970157Y417246D01*
X970299Y417387D01*
G37*
G36*
G01X971289Y415832D02*
X970723Y415337D01*
X970440Y415619D01*
X970935Y416185D01*
X971076Y416327D01*
X971430Y415973D01*
X971289Y415832D01*
G37*
G36*
G01X958268Y426663D02*
X958318Y427413D01*
X958718D01*
X958768Y426663D01*
Y426463D01*
X958268D01*
Y426663D01*
G37*
G36*
G01X960068Y426264D02*
X960018Y425514D01*
X959618D01*
X959568Y426264D01*
Y426464D01*
X960068D01*
Y426264D01*
G37*
G36*
G01X965773Y421347D02*
X965207Y420852D01*
X964925Y421135D01*
X965420Y421701D01*
X965561Y421842D01*
X965915Y421488D01*
X965773Y421347D01*
G37*
G36*
G01X962945Y424741D02*
X963510Y425236D01*
X963793Y424953D01*
X963298Y424388D01*
X963157Y424246D01*
X962803Y424600D01*
X962945Y424741D01*
G37*
G36*
G01X962096Y425024D02*
X961531Y424529D01*
X961248Y424812D01*
X961743Y425378D01*
X961884Y425519D01*
X962238Y425165D01*
X962096Y425024D01*
G37*
G36*
G01X963935Y423185D02*
X963369Y422690D01*
X963086Y422973D01*
X963581Y423539D01*
X963723Y423680D01*
X964076Y423327D01*
X963935Y423185D01*
G37*
G36*
G01X964783Y422903D02*
X965349Y423398D01*
X965632Y423115D01*
X965137Y422549D01*
X964995Y422408D01*
X964642Y422761D01*
X964783Y422903D01*
G37*
G36*
G01X961105Y426581D02*
X961670Y427076D01*
X961953Y426793D01*
X961458Y426228D01*
X961317Y426086D01*
X960963Y426440D01*
X961105Y426581D01*
G37*
G36*
G01X938176Y414528D02*
X937794Y414345D01*
X937497Y414642D01*
X937681Y415023D01*
X937822Y415165D01*
X938317Y414670D01*
X938176Y414528D01*
G37*
G36*
G01X937363Y415907D02*
X937744Y416091D01*
X938041Y415794D01*
X937858Y415412D01*
X937716Y415271D01*
X937221Y415766D01*
X937363Y415907D01*
G37*
G36*
G01X939378Y413326D02*
X938996Y413143D01*
X938699Y413440D01*
X938883Y413821D01*
X939024Y413963D01*
X939519Y413468D01*
X939378Y413326D01*
G37*
G36*
G01X939767Y413503D02*
X940149Y413687D01*
X940446Y413390D01*
X940262Y413008D01*
X940120Y412867D01*
X939625Y413362D01*
X939767Y413503D01*
G37*
G36*
G01X938565Y414705D02*
X938946Y414889D01*
X939243Y414592D01*
X939060Y414210D01*
X938918Y414069D01*
X938423Y414564D01*
X938565Y414705D01*
G37*
G36*
G01X940580Y412124D02*
X940198Y411940D01*
X939901Y412237D01*
X940085Y412619D01*
X940226Y412761D01*
X940721Y412266D01*
X940580Y412124D01*
G37*
G36*
G01X941782Y410922D02*
X941400Y410738D01*
X941103Y411035D01*
X941287Y411417D01*
X941428Y411559D01*
X941923Y411064D01*
X941782Y410922D01*
G37*
G36*
G01X940969Y412301D02*
X941351Y412485D01*
X941648Y412188D01*
X941464Y411806D01*
X941322Y411665D01*
X940827Y412160D01*
X940969Y412301D01*
G37*
G36*
G01X946671Y409851D02*
X946811Y410251D01*
X947231D01*
X947371Y409851D01*
Y409651D01*
X946671D01*
Y409851D01*
G37*
G36*
G01X944971D02*
X945111Y410251D01*
X945531D01*
X945671Y409851D01*
Y409651D01*
X944971D01*
Y409851D01*
G37*
G36*
G01X948221Y409451D02*
X948081Y409051D01*
X947661D01*
X947521Y409451D01*
Y409651D01*
X948221D01*
Y409451D01*
G37*
G36*
G01X946521D02*
X946381Y409051D01*
X945961D01*
X945821Y409451D01*
Y409651D01*
X946521D01*
Y409451D01*
G37*
G36*
G01X944821D02*
X944681Y409051D01*
X944261D01*
X944121Y409451D01*
Y409651D01*
X944821D01*
Y409451D01*
G37*
G36*
G01X942171Y411099D02*
X942553Y411283D01*
X942850Y410986D01*
X942666Y410604D01*
X942524Y410463D01*
X942029Y410958D01*
X942171Y411099D01*
G37*
G36*
G01X942984Y409720D02*
X942602Y409536D01*
X942305Y409833D01*
X942489Y410215D01*
X942630Y410357D01*
X943125Y409862D01*
X942984Y409720D01*
G37*
G36*
G01X950071Y409851D02*
X950211Y410251D01*
X950631D01*
X950771Y409851D01*
Y409651D01*
X950071D01*
Y409851D01*
G37*
G36*
G01X951771D02*
X951911Y410251D01*
X952331D01*
X952471Y409851D01*
Y409651D01*
X951771D01*
Y409851D01*
G37*
G36*
G01X948371D02*
X948511Y410251D01*
X948931D01*
X949071Y409851D01*
Y409651D01*
X948371D01*
Y409851D01*
G37*
G36*
G01X951621Y409451D02*
X951481Y409051D01*
X951061D01*
X950921Y409451D01*
Y409651D01*
X951621D01*
Y409451D01*
G37*
G36*
G01X953321D02*
X953181Y409051D01*
X952761D01*
X952621Y409451D01*
Y409651D01*
X953321D01*
Y409451D01*
G37*
G36*
G01X949921D02*
X949781Y409051D01*
X949361D01*
X949221Y409451D01*
Y409651D01*
X949921D01*
Y409451D01*
G37*
G36*
G01X957740Y405814D02*
X957358Y405630D01*
X957061Y405927D01*
X957245Y406309D01*
X957387Y406450D01*
X957882Y405955D01*
X957740Y405814D01*
G37*
G36*
G01X958942Y404612D02*
X958560Y404428D01*
X958263Y404725D01*
X958447Y405107D01*
X958589Y405248D01*
X959084Y404753D01*
X958942Y404612D01*
G37*
G36*
G01X956538Y407016D02*
X956156Y406832D01*
X955859Y407129D01*
X956043Y407511D01*
X956184Y407653D01*
X956679Y407158D01*
X956538Y407016D01*
G37*
G36*
G01X955336Y408218D02*
X954954Y408034D01*
X954657Y408331D01*
X954841Y408713D01*
X954982Y408855D01*
X955477Y408360D01*
X955336Y408218D01*
G37*
G36*
G01X959331Y404789D02*
X959713Y404973D01*
X960010Y404676D01*
X959826Y404294D01*
X959685Y404152D01*
X959190Y404647D01*
X959331Y404789D01*
G37*
G36*
G01X956927Y407193D02*
X957309Y407377D01*
X957606Y407080D01*
X957422Y406698D01*
X957280Y406557D01*
X956786Y407051D01*
X956927Y407193D01*
G37*
G36*
G01X955725Y408395D02*
X956107Y408579D01*
X956404Y408282D01*
X956220Y407900D01*
X956078Y407759D01*
X955583Y408254D01*
X955725Y408395D01*
G37*
G36*
G01X954523Y409597D02*
X954905Y409781D01*
X955202Y409484D01*
X955018Y409102D01*
X954876Y408961D01*
X954381Y409456D01*
X954523Y409597D01*
G37*
G36*
G01X953471Y409851D02*
X953611Y410251D01*
X954031D01*
X954171Y409851D01*
Y409651D01*
X953471D01*
Y409851D01*
G37*
G36*
G01X958129Y405991D02*
X958511Y406175D01*
X958808Y405878D01*
X958624Y405496D01*
X958483Y405354D01*
X957988Y405849D01*
X958129Y405991D01*
G37*
G36*
G01X969556Y420322D02*
X970122Y420817D01*
X970405Y420534D01*
X969910Y419968D01*
X969768Y419827D01*
X969415Y420180D01*
X969556Y420322D01*
G37*
G36*
G01X968708Y420605D02*
X968142Y420110D01*
X967859Y420392D01*
X968354Y420958D01*
X968496Y421099D01*
X968849Y420746D01*
X968708Y420605D01*
G37*
G36*
G01X970546Y418766D02*
X969980Y418271D01*
X969698Y418554D01*
X970193Y419120D01*
X970334Y419261D01*
X970688Y418907D01*
X970546Y418766D01*
G37*
G36*
G01X971395Y418483D02*
X971960Y418978D01*
X972243Y418695D01*
X971748Y418130D01*
X971607Y417988D01*
X971253Y418342D01*
X971395Y418483D01*
G37*
G36*
G01X962202Y427676D02*
X962768Y428171D01*
X963051Y427888D01*
X962556Y427322D01*
X962414Y427181D01*
X962061Y427534D01*
X962202Y427676D01*
G37*
G36*
G01X963192Y426120D02*
X962627Y425625D01*
X962344Y425908D01*
X962839Y426474D01*
X962980Y426615D01*
X963334Y426261D01*
X963192Y426120D01*
G37*
G36*
G01X965879Y423999D02*
X966445Y424494D01*
X966728Y424211D01*
X966233Y423645D01*
X966091Y423504D01*
X965738Y423857D01*
X965879Y423999D01*
G37*
G36*
G01X964041Y425837D02*
X964606Y426332D01*
X964889Y426049D01*
X964394Y425484D01*
X964253Y425342D01*
X963899Y425696D01*
X964041Y425837D01*
G37*
G36*
G01X965031Y424281D02*
X964465Y423786D01*
X964182Y424069D01*
X964677Y424635D01*
X964819Y424776D01*
X965172Y424423D01*
X965031Y424281D01*
G37*
G36*
G01X967718Y422160D02*
X968283Y422655D01*
X968566Y422372D01*
X968071Y421807D01*
X967930Y421665D01*
X967576Y422019D01*
X967718Y422160D01*
G37*
G36*
G01X966869Y422443D02*
X966303Y421948D01*
X966021Y422231D01*
X966516Y422797D01*
X966657Y422938D01*
X967011Y422584D01*
X966869Y422443D01*
G37*
G36*
G01X938069Y411805D02*
X938451Y411989D01*
X938748Y411692D01*
X938564Y411310D01*
X938422Y411169D01*
X937927Y411664D01*
X938069Y411805D01*
G37*
G36*
G01X937680Y411628D02*
X937298Y411444D01*
X937001Y411741D01*
X937185Y412123D01*
X937326Y412265D01*
X937821Y411770D01*
X937680Y411628D01*
G37*
G36*
G01X940084Y409224D02*
X939702Y409040D01*
X939405Y409337D01*
X939589Y409719D01*
X939730Y409861D01*
X940225Y409366D01*
X940084Y409224D01*
G37*
G36*
G01X939271Y410603D02*
X939653Y410787D01*
X939950Y410490D01*
X939766Y410108D01*
X939624Y409967D01*
X939129Y410462D01*
X939271Y410603D01*
G37*
G36*
G01X938882Y410426D02*
X938500Y410242D01*
X938203Y410539D01*
X938387Y410921D01*
X938528Y411063D01*
X939023Y410568D01*
X938882Y410426D01*
G37*
G36*
G01X940473Y409401D02*
X940855Y409585D01*
X941152Y409288D01*
X940968Y408906D01*
X940826Y408765D01*
X940331Y409260D01*
X940473Y409401D01*
G37*
G36*
G01X941286Y408022D02*
X940904Y407838D01*
X940607Y408135D01*
X940791Y408517D01*
X940932Y408659D01*
X941427Y408164D01*
X941286Y408022D01*
G37*
G36*
G01X941675Y408199D02*
X942057Y408383D01*
X942354Y408086D01*
X942170Y407704D01*
X942028Y407563D01*
X941533Y408058D01*
X941675Y408199D01*
G37*
G36*
G01X946671Y407451D02*
X946811Y407851D01*
X947231D01*
X947371Y407451D01*
Y407251D01*
X946671D01*
Y407451D01*
G37*
G36*
G01X944971D02*
X945111Y407851D01*
X945531D01*
X945671Y407451D01*
Y407251D01*
X944971D01*
Y407451D01*
G37*
G36*
G01X943271D02*
X943411Y407851D01*
X943831D01*
X943971Y407451D01*
Y407251D01*
X943271D01*
Y407451D01*
G37*
G36*
G01X946521Y407051D02*
X946381Y406651D01*
X945961D01*
X945821Y407051D01*
Y407251D01*
X946521D01*
Y407051D01*
G37*
G36*
G01X944821D02*
X944681Y406651D01*
X944261D01*
X944121Y407051D01*
Y407251D01*
X944821D01*
Y407051D01*
G37*
G36*
G01X948221D02*
X948081Y406651D01*
X947661D01*
X947521Y407051D01*
Y407251D01*
X948221D01*
Y407051D01*
G37*
G36*
G01X943121D02*
X942981Y406651D01*
X942561D01*
X942421Y407051D01*
Y407251D01*
X943121D01*
Y407051D01*
G37*
G36*
G01X948371Y407451D02*
X948511Y407851D01*
X948931D01*
X949071Y407451D01*
Y407251D01*
X948371D01*
Y407451D01*
G37*
G36*
G01X950071D02*
X950211Y407851D01*
X950631D01*
X950771Y407451D01*
Y407251D01*
X950071D01*
Y407451D01*
G37*
G36*
G01X951771D02*
X951911Y407851D01*
X952331D01*
X952471Y407451D01*
Y407251D01*
X951771D01*
Y407451D01*
G37*
G36*
G01X949921Y407051D02*
X949781Y406651D01*
X949361D01*
X949221Y407051D01*
Y407251D01*
X949921D01*
Y407051D01*
G37*
G36*
G01X951621D02*
X951481Y406651D01*
X951061D01*
X950921Y407051D01*
Y407251D01*
X951621D01*
Y407051D01*
G37*
G36*
G01X954840Y405318D02*
X954458Y405134D01*
X954161Y405431D01*
X954345Y405813D01*
X954486Y405955D01*
X954981Y405460D01*
X954840Y405318D01*
G37*
G36*
G01X956042Y404116D02*
X955660Y403932D01*
X955363Y404229D01*
X955547Y404611D01*
X955689Y404752D01*
X956184Y404257D01*
X956042Y404116D01*
G37*
G36*
G01X954027Y406697D02*
X954409Y406881D01*
X954706Y406584D01*
X954522Y406202D01*
X954380Y406061D01*
X953885Y406556D01*
X954027Y406697D01*
G37*
G36*
G01X955229Y405495D02*
X955611Y405679D01*
X955908Y405382D01*
X955724Y405000D01*
X955582Y404859D01*
X955088Y405353D01*
X955229Y405495D01*
G37*
G36*
G01X956431Y404293D02*
X956813Y404477D01*
X957110Y404180D01*
X956926Y403798D01*
X956785Y403656D01*
X956290Y404151D01*
X956431Y404293D01*
G37*
G36*
G01X953638Y406520D02*
X953256Y406336D01*
X952959Y406633D01*
X953143Y407015D01*
X953284Y407157D01*
X953779Y406662D01*
X953638Y406520D01*
G37*
G36*
G01X964677Y420251D02*
X964111Y419756D01*
X963829Y420039D01*
X964324Y420605D01*
X964465Y420746D01*
X964819Y420392D01*
X964677Y420251D01*
G37*
G36*
G01X965526Y419968D02*
X966091Y420463D01*
X966374Y420180D01*
X965879Y419615D01*
X965738Y419473D01*
X965384Y419827D01*
X965526Y419968D01*
G37*
G36*
G01X967364Y418130D02*
X967930Y418625D01*
X968213Y418342D01*
X967718Y417776D01*
X967576Y417635D01*
X967223Y417988D01*
X967364Y418130D01*
G37*
G36*
G01X966516Y418413D02*
X965950Y417918D01*
X965667Y418200D01*
X966162Y418766D01*
X966304Y418907D01*
X966657Y418554D01*
X966516Y418413D01*
G37*
G36*
G01X969203Y416291D02*
X969768Y416786D01*
X970051Y416503D01*
X969556Y415938D01*
X969415Y415796D01*
X969061Y416150D01*
X969203Y416291D01*
G37*
G36*
G01X968354Y416574D02*
X967788Y416079D01*
X967506Y416362D01*
X968001Y416928D01*
X968142Y417069D01*
X968496Y416715D01*
X968354Y416574D01*
G37*
G36*
G01X971041Y414453D02*
X971607Y414948D01*
X971890Y414665D01*
X971395Y414099D01*
X971253Y413958D01*
X970900Y414311D01*
X971041Y414453D01*
G37*
G36*
G01X970193Y414736D02*
X969627Y414241D01*
X969344Y414523D01*
X969839Y415089D01*
X969980Y415231D01*
X970334Y414877D01*
X970193Y414736D01*
G37*
G36*
G01X972031Y412897D02*
X971465Y412402D01*
X971183Y412685D01*
X971678Y413251D01*
X971819Y413392D01*
X972172Y413039D01*
X972031Y412897D01*
G37*
G36*
G01X958268Y425113D02*
X958318Y425863D01*
X958718D01*
X958768Y425113D01*
Y424913D01*
X958268D01*
Y425113D01*
G37*
G36*
G01X961000Y423928D02*
X960435Y423433D01*
X960152Y423716D01*
X960647Y424282D01*
X960788Y424423D01*
X961142Y424069D01*
X961000Y423928D01*
G37*
G36*
G01X961849Y423645D02*
X962414Y424140D01*
X962697Y423857D01*
X962202Y423292D01*
X962061Y423150D01*
X961707Y423504D01*
X961849Y423645D01*
G37*
G36*
G01X963687Y421807D02*
X964253Y422302D01*
X964536Y422019D01*
X964041Y421453D01*
X963899Y421312D01*
X963546Y421665D01*
X963687Y421807D01*
G37*
G36*
G01X962839Y422089D02*
X962273Y421594D01*
X961990Y421877D01*
X962485Y422443D01*
X962627Y422584D01*
X962980Y422231D01*
X962839Y422089D01*
G37*
G36*
G01X937823Y416579D02*
X937441Y416396D01*
X937144Y416693D01*
X937328Y417074D01*
X937469Y417216D01*
X937964Y416721D01*
X937823Y416579D01*
G37*
G36*
G01X939025Y415377D02*
X938643Y415194D01*
X938346Y415491D01*
X938530Y415872D01*
X938671Y416014D01*
X939166Y415519D01*
X939025Y415377D01*
G37*
G36*
G01X940227Y414175D02*
X939845Y413992D01*
X939548Y414289D01*
X939732Y414670D01*
X939873Y414812D01*
X940368Y414317D01*
X940227Y414175D01*
G37*
G36*
G01X939414Y415554D02*
X939795Y415738D01*
X940092Y415441D01*
X939909Y415059D01*
X939767Y414918D01*
X939272Y415413D01*
X939414Y415554D01*
G37*
G36*
G01X938212Y416756D02*
X938593Y416940D01*
X938890Y416643D01*
X938707Y416261D01*
X938565Y416120D01*
X938070Y416615D01*
X938212Y416756D01*
G37*
G36*
G01X940616Y414352D02*
X940998Y414536D01*
X941295Y414239D01*
X941111Y413857D01*
X940969Y413716D01*
X940474Y414211D01*
X940616Y414352D01*
G37*
G36*
G01X941429Y412973D02*
X941047Y412789D01*
X940750Y413086D01*
X940934Y413468D01*
X941075Y413610D01*
X941570Y413115D01*
X941429Y412973D01*
G37*
G36*
G01X941818Y413150D02*
X942200Y413334D01*
X942497Y413037D01*
X942313Y412655D01*
X942171Y412514D01*
X941676Y413009D01*
X941818Y413150D01*
G37*
G36*
G01X946671Y411051D02*
X946811Y411451D01*
X947231D01*
X947371Y411051D01*
Y410851D01*
X946671D01*
Y411051D01*
G37*
G36*
G01X944971D02*
X945111Y411451D01*
X945531D01*
X945671Y411051D01*
Y410851D01*
X944971D01*
Y411051D01*
G37*
G36*
G01X948221Y410651D02*
X948081Y410251D01*
X947661D01*
X947521Y410651D01*
Y410851D01*
X948221D01*
Y410651D01*
G37*
G36*
G01X946521D02*
X946381Y410251D01*
X945961D01*
X945821Y410651D01*
Y410851D01*
X946521D01*
Y410651D01*
G37*
G36*
G01X942631Y411771D02*
X942249Y411587D01*
X941952Y411884D01*
X942136Y412266D01*
X942277Y412408D01*
X942772Y411913D01*
X942631Y411771D01*
G37*
G36*
G01X943020Y411948D02*
X943402Y412132D01*
X943699Y411835D01*
X943515Y411453D01*
X943373Y411312D01*
X942878Y411807D01*
X943020Y411948D01*
G37*
G36*
G01X944821Y410651D02*
X944681Y410251D01*
X944261D01*
X944121Y410651D01*
Y410851D01*
X944821D01*
Y410651D01*
G37*
G36*
G01X948371Y411051D02*
X948511Y411451D01*
X948931D01*
X949071Y411051D01*
Y410851D01*
X948371D01*
Y411051D01*
G37*
G36*
G01X950071D02*
X950211Y411451D01*
X950631D01*
X950771Y411051D01*
Y410851D01*
X950071D01*
Y411051D01*
G37*
G36*
G01X951771D02*
X951911Y411451D01*
X952331D01*
X952471Y411051D01*
Y410851D01*
X951771D01*
Y411051D01*
G37*
G36*
G01X949921Y410651D02*
X949781Y410251D01*
X949361D01*
X949221Y410651D01*
Y410851D01*
X949921D01*
Y410651D01*
G37*
G36*
G01X951621D02*
X951481Y410251D01*
X951061D01*
X950921Y410651D01*
Y410851D01*
X951621D01*
Y410651D01*
G37*
G36*
G01X953321D02*
X953181Y410251D01*
X952761D01*
X952621Y410651D01*
Y410851D01*
X953321D01*
Y410651D01*
G37*
G36*
G01X960180Y405638D02*
X960562Y405822D01*
X960859Y405525D01*
X960675Y405143D01*
X960534Y405001D01*
X960039Y405496D01*
X960180Y405638D01*
G37*
G36*
G01X953471Y411051D02*
X953611Y411451D01*
X954031D01*
X954171Y411051D01*
Y410851D01*
X953471D01*
Y411051D01*
G37*
G36*
G01X957387Y407865D02*
X957005Y407681D01*
X956708Y407978D01*
X956892Y408360D01*
X957033Y408502D01*
X957528Y408007D01*
X957387Y407865D01*
G37*
G36*
G01X956185Y409067D02*
X955803Y408883D01*
X955506Y409180D01*
X955690Y409562D01*
X955831Y409704D01*
X956326Y409209D01*
X956185Y409067D01*
G37*
G36*
G01X958589Y406663D02*
X958207Y406479D01*
X957910Y406776D01*
X958094Y407158D01*
X958236Y407299D01*
X958731Y406804D01*
X958589Y406663D01*
G37*
G36*
G01X959791Y405461D02*
X959409Y405277D01*
X959112Y405574D01*
X959296Y405956D01*
X959438Y406097D01*
X959933Y405602D01*
X959791Y405461D01*
G37*
G36*
G01X956574Y409244D02*
X956956Y409428D01*
X957253Y409131D01*
X957069Y408749D01*
X956927Y408608D01*
X956432Y409103D01*
X956574Y409244D01*
G37*
G36*
G01X955372Y410446D02*
X955754Y410630D01*
X956051Y410333D01*
X955867Y409951D01*
X955725Y409810D01*
X955230Y410305D01*
X955372Y410446D01*
G37*
G36*
G01X957776Y408042D02*
X958158Y408226D01*
X958455Y407929D01*
X958271Y407547D01*
X958129Y407406D01*
X957635Y407900D01*
X957776Y408042D01*
G37*
G36*
G01X958978Y406840D02*
X959360Y407024D01*
X959657Y406727D01*
X959473Y406345D01*
X959332Y406203D01*
X958837Y406698D01*
X958978Y406840D01*
G37*
G36*
G01X971642Y419862D02*
X971076Y419367D01*
X970794Y419650D01*
X971289Y420216D01*
X971430Y420357D01*
X971784Y420003D01*
X971642Y419862D01*
G37*
G36*
G01X963298Y428772D02*
X963864Y429267D01*
X964147Y428984D01*
X963652Y428418D01*
X963510Y428277D01*
X963157Y428630D01*
X963298Y428772D01*
G37*
G36*
G01X964288Y427216D02*
X963723Y426721D01*
X963440Y427004D01*
X963935Y427570D01*
X964076Y427711D01*
X964430Y427357D01*
X964288Y427216D01*
G37*
G36*
G01X965137Y426933D02*
X965702Y427428D01*
X965985Y427145D01*
X965490Y426580D01*
X965349Y426438D01*
X964995Y426792D01*
X965137Y426933D01*
G37*
G36*
G01X962448Y429056D02*
X961883Y428561D01*
X961600Y428844D01*
X962095Y429410D01*
X962236Y429551D01*
X962590Y429197D01*
X962448Y429056D01*
G37*
G36*
G01X966127Y425377D02*
X965561Y424882D01*
X965278Y425165D01*
X965773Y425731D01*
X965915Y425872D01*
X966268Y425519D01*
X966127Y425377D01*
G37*
G36*
G01X970652Y421418D02*
X971218Y421913D01*
X971501Y421630D01*
X971006Y421064D01*
X970864Y420923D01*
X970511Y421276D01*
X970652Y421418D01*
G37*
G36*
G01X969804Y421701D02*
X969238Y421206D01*
X968955Y421488D01*
X969450Y422054D01*
X969592Y422195D01*
X969945Y421842D01*
X969804Y421701D01*
G37*
G36*
G01X966975Y425095D02*
X967541Y425590D01*
X967824Y425307D01*
X967329Y424741D01*
X967187Y424600D01*
X966834Y424953D01*
X966975Y425095D01*
G37*
G36*
G01X968814Y423256D02*
X969379Y423751D01*
X969662Y423468D01*
X969167Y422903D01*
X969026Y422761D01*
X968672Y423115D01*
X968814Y423256D01*
G37*
G36*
G01X967965Y423539D02*
X967399Y423044D01*
X967117Y423327D01*
X967612Y423893D01*
X967753Y424034D01*
X968107Y423680D01*
X967965Y423539D01*
G37*
G36*
G01X963334Y417776D02*
X963899Y418271D01*
X964182Y417988D01*
X963687Y417423D01*
X963546Y417281D01*
X963192Y417635D01*
X963334Y417776D01*
G37*
G36*
G01X965172Y415938D02*
X965738Y416433D01*
X966021Y416150D01*
X965526Y415584D01*
X965384Y415443D01*
X965031Y415796D01*
X965172Y415938D01*
G37*
G36*
G01X964324Y416221D02*
X963758Y415726D01*
X963475Y416008D01*
X963970Y416574D01*
X964112Y416715D01*
X964465Y416362D01*
X964324Y416221D01*
G37*
G36*
G01X966162Y414382D02*
X965596Y413887D01*
X965314Y414170D01*
X965809Y414736D01*
X965950Y414877D01*
X966304Y414523D01*
X966162Y414382D01*
G37*
G36*
G01X960647Y419897D02*
X960081Y419402D01*
X959798Y419685D01*
X960293Y420251D01*
X960435Y420392D01*
X960788Y420039D01*
X960647Y419897D01*
G37*
G36*
G01X961495Y419615D02*
X962061Y420110D01*
X962344Y419827D01*
X961849Y419261D01*
X961707Y419120D01*
X961354Y419473D01*
X961495Y419615D01*
G37*
G36*
G01X962485Y418059D02*
X961919Y417564D01*
X961637Y417847D01*
X962132Y418413D01*
X962273Y418554D01*
X962627Y418200D01*
X962485Y418059D01*
G37*
G36*
G01X967011Y414099D02*
X967576Y414594D01*
X967859Y414311D01*
X967364Y413746D01*
X967223Y413604D01*
X966869Y413958D01*
X967011Y414099D01*
G37*
G36*
G01X968849Y412261D02*
X969415Y412756D01*
X969698Y412473D01*
X969203Y411907D01*
X969061Y411766D01*
X968708Y412119D01*
X968849Y412261D01*
G37*
G36*
G01X968001Y412544D02*
X967435Y412049D01*
X967152Y412331D01*
X967647Y412897D01*
X967788Y413039D01*
X968142Y412685D01*
X968001Y412544D01*
G37*
G36*
G01X970688Y410422D02*
X971253Y410917D01*
X971536Y410634D01*
X971041Y410069D01*
X970900Y409927D01*
X970546Y410281D01*
X970688Y410422D01*
G37*
G36*
G01X971678Y408867D02*
X971112Y408372D01*
X970829Y408654D01*
X971324Y409220D01*
X971465Y409362D01*
X971819Y409008D01*
X971678Y408867D01*
G37*
G36*
G01X969839Y410705D02*
X969273Y410210D01*
X968991Y410493D01*
X969486Y411059D01*
X969627Y411200D01*
X969980Y410847D01*
X969839Y410705D01*
G37*
G36*
G01X957468Y421615D02*
X957418Y420865D01*
X957018D01*
X956968Y421615D01*
Y421815D01*
X957468D01*
Y421615D01*
G37*
G36*
G01X954868D02*
X954818Y420865D01*
X954418D01*
X954368Y421615D01*
Y421815D01*
X954868D01*
Y421615D01*
G37*
G36*
G01X959657Y421453D02*
X960222Y421948D01*
X960505Y421665D01*
X960010Y421100D01*
X959869Y420958D01*
X959515Y421312D01*
X959657Y421453D01*
G37*
G36*
G01X955668Y422015D02*
X955718Y422765D01*
X956118D01*
X956168Y422015D01*
Y421815D01*
X955668D01*
Y422015D01*
G37*
G36*
G01X958268D02*
X958318Y422765D01*
X958718D01*
X958768Y422015D01*
Y421815D01*
X958268D01*
Y422015D01*
G37*
G36*
G01X953068D02*
X953118Y422765D01*
X953518D01*
X953568Y422015D01*
Y421815D01*
X953068D01*
Y422015D01*
G37*
G36*
G01X965420Y417317D02*
X964854Y416822D01*
X964571Y417104D01*
X965066Y417670D01*
X965208Y417811D01*
X965561Y417458D01*
X965420Y417317D01*
G37*
G36*
G01X966268Y417034D02*
X966834Y417529D01*
X967117Y417246D01*
X966622Y416680D01*
X966480Y416539D01*
X966127Y416892D01*
X966268Y417034D01*
G37*
G36*
G01X967258Y415478D02*
X966692Y414983D01*
X966410Y415266D01*
X966905Y415832D01*
X967046Y415973D01*
X967400Y415619D01*
X967258Y415478D01*
G37*
G36*
G01X962591Y420711D02*
X963157Y421206D01*
X963440Y420923D01*
X962945Y420357D01*
X962803Y420216D01*
X962450Y420569D01*
X962591Y420711D01*
G37*
G36*
G01X961743Y420993D02*
X961177Y420498D01*
X960894Y420781D01*
X961389Y421347D01*
X961531Y421488D01*
X961884Y421135D01*
X961743Y420993D01*
G37*
G36*
G01X963581Y419155D02*
X963015Y418660D01*
X962733Y418943D01*
X963228Y419509D01*
X963369Y419650D01*
X963723Y419296D01*
X963581Y419155D01*
G37*
G36*
G01X964430Y418872D02*
X964995Y419367D01*
X965278Y419084D01*
X964783Y418519D01*
X964642Y418377D01*
X964288Y418731D01*
X964430Y418872D01*
G37*
G36*
G01X968107Y415195D02*
X968672Y415690D01*
X968955Y415407D01*
X968460Y414842D01*
X968319Y414700D01*
X967965Y415054D01*
X968107Y415195D01*
G37*
G36*
G01X969945Y413357D02*
X970511Y413852D01*
X970794Y413569D01*
X970299Y413003D01*
X970157Y412862D01*
X969804Y413215D01*
X969945Y413357D01*
G37*
G36*
G01X969097Y413640D02*
X968531Y413145D01*
X968248Y413427D01*
X968743Y413993D01*
X968884Y414135D01*
X969238Y413781D01*
X969097Y413640D01*
G37*
G36*
G01X970935Y411801D02*
X970369Y411306D01*
X970087Y411589D01*
X970582Y412155D01*
X970723Y412296D01*
X971076Y411943D01*
X970935Y411801D01*
G37*
G36*
G01X958268Y423564D02*
X958318Y424314D01*
X958718D01*
X958768Y423564D01*
Y423364D01*
X958268D01*
Y423564D01*
G37*
G36*
G01X955668D02*
X955718Y424314D01*
X956118D01*
X956168Y423564D01*
Y423364D01*
X955668D01*
Y423564D01*
G37*
G36*
G01X957468Y423164D02*
X957418Y422414D01*
X957018D01*
X956968Y423164D01*
Y423364D01*
X957468D01*
Y423164D01*
G37*
G36*
G01X960753Y422549D02*
X961318Y423044D01*
X961601Y422761D01*
X961106Y422196D01*
X960965Y422054D01*
X960611Y422408D01*
X960753Y422549D01*
G37*
G36*
G01X965738Y432342D02*
X965172Y431847D01*
X964889Y432130D01*
X965384Y432696D01*
X965526Y432837D01*
X965879Y432484D01*
X965738Y432342D01*
G37*
G36*
G01X969415Y428665D02*
X968849Y428170D01*
X968566Y428453D01*
X969061Y429019D01*
X969203Y429160D01*
X969556Y428807D01*
X969415Y428665D01*
G37*
G36*
G01X968425Y430221D02*
X968990Y430716D01*
X969273Y430433D01*
X968778Y429868D01*
X968637Y429726D01*
X968283Y430080D01*
X968425Y430221D01*
G37*
G36*
G01X966586Y432060D02*
X967152Y432555D01*
X967435Y432272D01*
X966940Y431706D01*
X966798Y431565D01*
X966445Y431918D01*
X966586Y432060D01*
G37*
G36*
G01X967576Y430504D02*
X967011Y430009D01*
X966728Y430292D01*
X967223Y430858D01*
X967364Y430999D01*
X967718Y430645D01*
X967576Y430504D01*
G37*
G36*
G01X970263Y428383D02*
X970829Y428878D01*
X971112Y428595D01*
X970617Y428029D01*
X970475Y427888D01*
X970122Y428241D01*
X970263Y428383D01*
G37*
G36*
G01X971253Y426827D02*
X970687Y426332D01*
X970405Y426615D01*
X970900Y427181D01*
X971041Y427322D01*
X971395Y426968D01*
X971253Y426827D01*
G37*
G36*
G01X970510Y429761D02*
X969945Y429266D01*
X969662Y429549D01*
X970157Y430115D01*
X970334Y430291D01*
X970687Y429938D01*
X970510Y429761D01*
G37*
G36*
G01X972349Y427923D02*
X971783Y427428D01*
X971500Y427711D01*
X971995Y428276D01*
X972172Y428453D01*
X972526Y428099D01*
X972349Y427923D01*
G37*
G36*
G01X968672Y431599D02*
X968107Y431104D01*
X967824Y431387D01*
X968319Y431953D01*
X968496Y432129D01*
X968849Y431776D01*
X968672Y431599D01*
G37*
G36*
G01X966834Y433437D02*
X966269Y432942D01*
X965986Y433225D01*
X966481Y433791D01*
X966658Y433967D01*
X967011Y433614D01*
X966834Y433437D01*
G37*
G36*
G01X964818Y411907D02*
X965384Y412402D01*
X965667Y412119D01*
X965172Y411553D01*
X964995Y411376D01*
X964641Y411730D01*
X964818Y411907D01*
G37*
G36*
G01X959303Y417422D02*
X959868Y417917D01*
X960151Y417634D01*
X959656Y417068D01*
X959479Y416892D01*
X959126Y417245D01*
X959303Y417422D01*
G37*
G36*
G01X961141Y415584D02*
X961707Y416078D01*
X961990Y415796D01*
X961495Y415230D01*
X961318Y415053D01*
X960964Y415407D01*
X961141Y415584D01*
G37*
G36*
G01X962980Y413745D02*
X963545Y414240D01*
X963828Y413957D01*
X963333Y413391D01*
X963156Y413215D01*
X962803Y413568D01*
X962980Y413745D01*
G37*
G36*
G01X953068Y418916D02*
X953118Y419666D01*
X953518D01*
X953568Y418916D01*
Y418666D01*
X953068D01*
Y418916D01*
G37*
G36*
G01X955668D02*
X955718Y419666D01*
X956118D01*
X956168Y418916D01*
Y418666D01*
X955668D01*
Y418916D01*
G37*
G36*
G01X950468D02*
X950518Y419666D01*
X950918D01*
X950968Y418916D01*
Y418666D01*
X950468D01*
Y418916D01*
G37*
G36*
G01X970333Y406391D02*
X970899Y406886D01*
X971182Y406603D01*
X970687Y406038D01*
X970510Y405861D01*
X970157Y406214D01*
X970333Y406391D01*
G37*
G36*
G01X968495Y408230D02*
X969061Y408725D01*
X969343Y408442D01*
X968849Y407876D01*
X968672Y407699D01*
X968318Y408053D01*
X968495Y408230D01*
G37*
G36*
G01X966656Y410068D02*
X967222Y410563D01*
X967505Y410280D01*
X967010Y409715D01*
X966833Y409538D01*
X966480Y409891D01*
X966656Y410068D01*
G37*
G36*
G01X962237Y416680D02*
X962803Y417175D01*
X963086Y416892D01*
X962591Y416326D01*
X962449Y416185D01*
X962096Y416538D01*
X962237Y416680D01*
G37*
G36*
G01X964076Y414841D02*
X964641Y415336D01*
X964924Y415053D01*
X964429Y414488D01*
X964288Y414346D01*
X963934Y414700D01*
X964076Y414841D01*
G37*
G36*
G01X965066Y413286D02*
X964500Y412791D01*
X964217Y413073D01*
X964712Y413639D01*
X964853Y413781D01*
X965207Y413427D01*
X965066Y413286D01*
G37*
G36*
G01X961389Y416962D02*
X960823Y416468D01*
X960540Y416750D01*
X961035Y417316D01*
X961177Y417457D01*
X961530Y417104D01*
X961389Y416962D01*
G37*
G36*
G01X963227Y415124D02*
X962661Y414629D01*
X962379Y414912D01*
X962874Y415478D01*
X963015Y415619D01*
X963369Y415265D01*
X963227Y415124D01*
G37*
G36*
G01X965914Y413003D02*
X966480Y413498D01*
X966763Y413215D01*
X966268Y412649D01*
X966126Y412508D01*
X965773Y412861D01*
X965914Y413003D01*
G37*
G36*
G01X966904Y411447D02*
X966338Y410952D01*
X966056Y411235D01*
X966551Y411801D01*
X966692Y411942D01*
X967046Y411588D01*
X966904Y411447D01*
G37*
G36*
G01X955668Y420466D02*
X955718Y421216D01*
X956118D01*
X956168Y420466D01*
Y420266D01*
X955668D01*
Y420466D01*
G37*
G36*
G01X953068D02*
X953118Y421216D01*
X953518D01*
X953568Y420466D01*
Y420266D01*
X953068D01*
Y420466D01*
G37*
G36*
G01X954868Y420066D02*
X954818Y419316D01*
X954418D01*
X954368Y420066D01*
Y420266D01*
X954868D01*
Y420066D01*
G37*
G36*
G01X960399Y418518D02*
X960964Y419013D01*
X961247Y418730D01*
X960752Y418165D01*
X960611Y418023D01*
X960257Y418377D01*
X960399Y418518D01*
G37*
G36*
G01X959550Y418801D02*
X958984Y418306D01*
X958702Y418589D01*
X959197Y419155D01*
X959338Y419296D01*
X959692Y418942D01*
X959550Y418801D01*
G37*
G36*
G01X958559Y420358D02*
X959124Y420853D01*
X959407Y420570D01*
X958912Y420005D01*
X958771Y419863D01*
X958417Y420217D01*
X958559Y420358D01*
G37*
G36*
G01X957468Y420066D02*
X957418Y419316D01*
X957018D01*
X956968Y420066D01*
Y420266D01*
X957468D01*
Y420066D01*
G37*
G36*
G01X952268D02*
X952218Y419316D01*
X951818D01*
X951768Y420066D01*
Y420266D01*
X952268D01*
Y420066D01*
G37*
G36*
G01X969591Y409326D02*
X970157Y409821D01*
X970440Y409538D01*
X969945Y408972D01*
X969803Y408831D01*
X969450Y409184D01*
X969591Y409326D01*
G37*
G36*
G01X967753Y411164D02*
X968318Y411659D01*
X968601Y411376D01*
X968106Y410811D01*
X967965Y410669D01*
X967611Y411023D01*
X967753Y411164D01*
G37*
G36*
G01X970581Y407770D02*
X970015Y407275D01*
X969733Y407558D01*
X970227Y408124D01*
X970369Y408265D01*
X970722Y407912D01*
X970581Y407770D01*
G37*
G36*
G01X968743Y409609D02*
X968177Y409114D01*
X967894Y409396D01*
X968389Y409962D01*
X968530Y410104D01*
X968884Y409750D01*
X968743Y409609D01*
G37*
G36*
G01X971430Y407487D02*
X971995Y407982D01*
X972278Y407699D01*
X971783Y407134D01*
X971642Y406992D01*
X971288Y407346D01*
X971430Y407487D01*
G37*
G36*
G01X964394Y429868D02*
X964960Y430363D01*
X965243Y430080D01*
X964748Y429514D01*
X964606Y429373D01*
X964253Y429726D01*
X964394Y429868D01*
G37*
G36*
G01X963546Y430150D02*
X962980Y429655D01*
X962697Y429938D01*
X963192Y430504D01*
X963334Y430645D01*
X963687Y430292D01*
X963546Y430150D01*
G37*
G36*
G01X967223Y426473D02*
X966657Y425978D01*
X966374Y426261D01*
X966869Y426827D01*
X967011Y426968D01*
X967364Y426615D01*
X967223Y426473D01*
G37*
G36*
G01X966233Y428029D02*
X966798Y428524D01*
X967081Y428241D01*
X966586Y427676D01*
X966445Y427534D01*
X966091Y427888D01*
X966233Y428029D01*
G37*
G36*
G01X965384Y428312D02*
X964819Y427817D01*
X964536Y428100D01*
X965031Y428666D01*
X965172Y428807D01*
X965526Y428453D01*
X965384Y428312D01*
G37*
G36*
G01X968071Y426191D02*
X968637Y426686D01*
X968920Y426403D01*
X968425Y425837D01*
X968283Y425696D01*
X967930Y426049D01*
X968071Y426191D01*
G37*
G36*
G01X969910Y424352D02*
X970475Y424847D01*
X970758Y424564D01*
X970263Y423999D01*
X970122Y423857D01*
X969768Y424211D01*
X969910Y424352D01*
G37*
G36*
G01X970900Y422797D02*
X970334Y422302D01*
X970051Y422584D01*
X970546Y423150D01*
X970688Y423291D01*
X971041Y422938D01*
X970900Y422797D01*
G37*
G36*
G01X969061Y424635D02*
X968495Y424140D01*
X968213Y424423D01*
X968708Y424989D01*
X968849Y425130D01*
X969203Y424776D01*
X969061Y424635D01*
G37*
G36*
G01X963652Y432802D02*
X964217Y433297D01*
X964500Y433014D01*
X964005Y432449D01*
X963864Y432307D01*
X963510Y432661D01*
X963652Y432802D01*
G37*
G36*
G01X964642Y431246D02*
X964076Y430751D01*
X963793Y431034D01*
X964288Y431600D01*
X964430Y431741D01*
X964783Y431388D01*
X964642Y431246D01*
G37*
G36*
G01X968319Y427569D02*
X967753Y427074D01*
X967470Y427357D01*
X967965Y427923D01*
X968107Y428064D01*
X968460Y427711D01*
X968319Y427569D01*
G37*
G36*
G01X967329Y429125D02*
X967894Y429620D01*
X968177Y429337D01*
X967682Y428772D01*
X967541Y428630D01*
X967187Y428984D01*
X967329Y429125D01*
G37*
G36*
G01X966480Y429408D02*
X965915Y428913D01*
X965632Y429196D01*
X966127Y429762D01*
X966268Y429903D01*
X966622Y429549D01*
X966480Y429408D01*
G37*
G36*
G01X965490Y430964D02*
X966056Y431459D01*
X966339Y431176D01*
X965844Y430610D01*
X965702Y430469D01*
X965349Y430822D01*
X965490Y430964D01*
G37*
G36*
G01X971006Y425448D02*
X971571Y425943D01*
X971854Y425660D01*
X971359Y425095D01*
X971218Y424953D01*
X970864Y425307D01*
X971006Y425448D01*
G37*
G36*
G01X970157Y425731D02*
X969591Y425236D01*
X969309Y425519D01*
X969804Y426085D01*
X969945Y426226D01*
X970299Y425872D01*
X970157Y425731D01*
G37*
G36*
G01X969167Y427287D02*
X969733Y427782D01*
X970016Y427499D01*
X969521Y426933D01*
X969379Y426792D01*
X969026Y427145D01*
X969167Y427287D01*
G37*
G36*
G01X971996Y423893D02*
X971430Y423398D01*
X971147Y423680D01*
X971642Y424246D01*
X971784Y424387D01*
X972137Y424034D01*
X971996Y423893D01*
G37*
G36*
G01X949800Y584600D02*
X949200Y585200D01*
Y586363D01*
X951837Y589000D01*
Y592851D01*
X952179Y593193D01*
Y594091D01*
X952450Y594362D01*
X955507D01*
G02X955901Y593894I0J-400D01*
G03X957987Y592445I1382J-237D01*
G02X958588Y592099I201J-346D01*
G01Y585469D01*
X957722Y584603D01*
X952856D01*
X952853Y584600D01*
X949800D01*
G37*
G36*
G01X952800Y562200D02*
X953300Y562700D01*
X954500D01*
X955000Y562200D01*
Y557262D01*
X955680Y556582D01*
Y555303D01*
X956553Y554430D01*
X958292D01*
X958588Y554134D01*
Y547669D01*
X957722Y546803D01*
X952856D01*
X952830Y546830D01*
X949670D01*
X949000Y547500D01*
Y549663D01*
X951837Y552500D01*
Y555010D01*
X952161Y555334D01*
Y556273D01*
X952800Y556912D01*
Y562200D01*
G37*
G36*
G01X1014924Y528546D02*
X1014634Y528256D01*
X1009201D01*
X1009042Y528415D01*
Y529573D01*
X1008109Y530506D01*
X1006750D01*
X1006500Y530756D01*
X956752D01*
X956100Y531408D01*
Y542400D01*
X956600Y542900D01*
X957700D01*
X958378Y542222D01*
Y537030D01*
X960308Y535100D01*
X1008572D01*
X1012859Y530813D01*
X1014632D01*
X1014924Y530521D01*
Y528546D01*
G37*
G36*
G01X965758Y575674D02*
Y574758D01*
G03X968886Y574756I1564J-1D01*
G01X968887Y574758D01*
Y575674D01*
X972688D01*
Y575212D01*
X972679Y575182D01*
G03X975351I1336J-425D01*
G01X975342Y575212D01*
Y575674D01*
X976036D01*
Y575212D01*
X976026Y575182D01*
G03X978698I1336J-425D01*
G01X978688Y575212D01*
Y575674D01*
X982728D01*
Y575212D01*
X982719Y575182D01*
G03X985391I1336J-425D01*
G01X985382Y575212D01*
Y575674D01*
X986074D01*
Y575212D01*
X986065Y575182D01*
G03X988737I1336J-425D01*
G01X988728Y575212D01*
Y575674D01*
X992768D01*
Y575212D01*
X992758Y575182D01*
G03X995430I1336J-425D01*
G01X995420Y575212D01*
Y575674D01*
X996114D01*
Y575212D01*
X996105Y575182D01*
G03X998777I1336J-425D01*
G01X998768Y575212D01*
Y575674D01*
X1002806D01*
Y575209D01*
X1002797Y575180D01*
G03X1005469Y575185I1337J-423D01*
G01X1005460Y575215D01*
Y575674D01*
X1009000D01*
G02X1009384Y575162I0J-400D01*
G03X1012148Y574028I1442J-421D01*
G02X1012851I352J-190D01*
G03X1015615Y575162I1322J713D01*
G02X1015999Y575674I384J112D01*
G01X1018132D01*
X1018766Y575040D01*
Y566864D01*
X1017908Y566005D01*
X1016030D01*
G02X1015640Y566491I1J400D01*
G03X1012851Y567528I-1467J324D01*
G02X1012148I-352J190D01*
G03X1009359Y566491I-1322J-713D01*
G02X1008969Y566005I-391J-86D01*
G01X1005460D01*
Y566367D01*
X1005469Y566397D01*
G03X1002797I-1336J425D01*
G01X1002806Y566367D01*
Y566005D01*
X1002114D01*
Y566367D01*
X1002123Y566397D01*
G03X999451I-1336J425D01*
G01X999460Y566367D01*
Y566005D01*
X995420D01*
Y566367D01*
X995430Y566397D01*
G03X992758I-1336J425D01*
G01X992768Y566367D01*
Y566005D01*
X992074D01*
Y566367D01*
X992084Y566397D01*
G03X989412I-1336J425D01*
G01X989422Y566367D01*
Y566005D01*
X985382D01*
Y566362D01*
X985391Y566391D01*
G03Y567237I-1337J423D01*
G01X985382Y567266D01*
Y567362D01*
X985314Y567430D01*
X985299Y567458D01*
G03X982719Y566386I-1245J-645D01*
G01X982728Y566356D01*
Y566005D01*
X982034D01*
Y566359D01*
X982044Y566389D01*
G03X979372I-1336J425D01*
G01X979382Y566359D01*
Y566005D01*
X975342D01*
Y566359D01*
X975351Y566389D01*
G03X972679I-1336J425D01*
G01X972688Y566359D01*
Y566005D01*
X971996D01*
Y566359D01*
X972005Y566389D01*
G03X969333I-1336J425D01*
G01X969342Y566359D01*
Y566005D01*
X965302D01*
Y566359D01*
X965312Y566389D01*
G03X962640I-1336J425D01*
G01X962650Y566359D01*
Y566005D01*
X959629D01*
X959589Y566045D01*
Y573073D01*
G02X960131Y573446I400J-1D01*
G03X961965Y575182I498J1311D01*
G01X961956Y575212D01*
Y575674D01*
X965758D01*
G37*
G36*
G01X962290Y546815D02*
G02X961921Y547370I0J400D01*
G03X961650Y548875I-1292J544D01*
G02X961942Y549548I292J273D01*
G01X964202D01*
Y550048D01*
X965702D01*
Y553952D01*
X964202D01*
Y554465D01*
X964348Y554505D01*
G03X965359Y556087I-372J1352D01*
G02X965753Y556553I394J66D01*
G01X968892D01*
G02X969286Y556087I0J-400D01*
G03X972052I1383J-230D01*
G02X972446Y556553I394J66D01*
G01X972692D01*
Y556321D01*
X972682Y556291D01*
G03X972852Y555075I1333J-434D01*
G02X972520Y554452I-332J-223D01*
G01X972098D01*
Y553402D01*
X971111D01*
X971087Y553408D01*
G03Y550592I-356J-1408D01*
G01X971111Y550598D01*
X972098D01*
Y549548D01*
X972702D01*
G02X972994Y548875I0J-400D01*
G03X972723Y547370I1021J-961D01*
G02X972354Y546815I-369J-155D01*
G01X968983D01*
G02X968614Y547370I0J400D01*
G03X966030I-1292J544D01*
G02X965661Y546815I-369J-155D01*
G01X962290D01*
G37*
G36*
G01Y584615D02*
G02X961921Y585170I0J400D01*
G03X961650Y586675I-1292J544D01*
G02X961942Y587348I292J273D01*
G01X964202D01*
Y587848D01*
X965702D01*
Y591752D01*
X964202D01*
Y592265D01*
X964348Y592305D01*
G03X965359Y593887I-372J1352D01*
G02X965753Y594353I394J66D01*
G01X968892D01*
G02X969286Y593887I0J-400D01*
G03X972052I1383J-230D01*
G02X972446Y594353I394J66D01*
G01X972692D01*
Y594121D01*
X972682Y594091D01*
G03X972852Y592875I1333J-434D01*
G02X972520Y592252I-332J-223D01*
G01X971998D01*
Y591102D01*
X971376D01*
X971337Y591120D01*
G03Y588480I-606J-1320D01*
G01X971376Y588498D01*
X971998D01*
Y587348D01*
X972702D01*
G02X972994Y586675I0J-400D01*
G03X972723Y585170I1021J-961D01*
G02X972354Y584615I-369J-155D01*
G01X968983D01*
G02X968614Y585170I0J400D01*
G03X966030I-1292J544D01*
G02X965661Y584615I-369J-155D01*
G01X962290D01*
G37*
G36*
G01X968886Y609864D02*
X968887Y613543D01*
X972688D01*
Y610570D01*
X972668Y610528D01*
G03X975362I1347J-664D01*
G01X975342Y610570D01*
Y613543D01*
X976036D01*
Y613163D01*
X976015Y613121D01*
G03X978709I1347J-664D01*
G01X978688Y613163D01*
Y613543D01*
X982728D01*
Y613163D01*
X982708Y613121D01*
G03X985402I1347J-664D01*
G01X985382Y613163D01*
Y613543D01*
X986074D01*
Y610570D01*
X986054Y610528D01*
G03X988748I1347J-664D01*
G01X988728Y610570D01*
Y613543D01*
X992768D01*
Y610570D01*
X992747Y610528D01*
G03X995441I1347J-664D01*
G01X995420Y610570D01*
Y613543D01*
X996114D01*
Y613063D01*
X996094Y613021D01*
G03X998788I1347J-664D01*
G01X998768Y613063D01*
Y613543D01*
X1002806D01*
Y613064D01*
X1002786Y613022D01*
G03X1005480I1347J-664D01*
G01X1005460Y613064D01*
Y613543D01*
X1007736D01*
X1007750Y613528D01*
X1009500D01*
Y612948D01*
X1009479Y612906D01*
G03X1012148Y611528I1347J-664D01*
G02X1012851I352J-190D01*
G03X1015520Y612906I1322J714D01*
G01X1015500Y612948D01*
Y613528D01*
X1017736D01*
X1018892Y612372D01*
Y604930D01*
X1017767Y603805D01*
X1016030D01*
G02X1015640Y604291I1J400D01*
G03X1012851Y605328I-1467J324D01*
G02X1012148I-352J190D01*
G03X1009359Y604291I-1322J-713D01*
G02X1008969Y603805I-391J-86D01*
G01X1005460D01*
Y606586D01*
X1005481Y606628D01*
G03X1002787I-1347J664D01*
G01X1002808Y606586D01*
Y603805D01*
X1002216D01*
Y604035D01*
X1002224Y604063D01*
G03X999303Y604267I-1437J436D01*
G02X998908Y603805I-395J-62D01*
G01X995951D01*
G02X995561Y604291I1J400D01*
G03X992691Y604077I-1467J323D01*
G01X992705Y604042D01*
Y603805D01*
X992074D01*
Y606586D01*
X992095Y606628D01*
G03X989401I-1347J664D01*
G01X989422Y606586D01*
Y603805D01*
X985382D01*
Y606586D01*
X985402Y606628D01*
G03X982708I-1347J664D01*
G01X982728Y606586D01*
Y603805D01*
X982097D01*
Y604042D01*
X982111Y604077D01*
G03X979241Y604291I-1403J537D01*
G02X978851Y603805I-391J-86D01*
G01X975894D01*
G02X975499Y604267I0J400D01*
G03X972578Y604063I-1484J232D01*
G01X972586Y604035D01*
Y603805D01*
X971996D01*
Y606586D01*
X972016Y606628D01*
G03X969322I-1347J664D01*
G01X969342Y606586D01*
Y603805D01*
X965302D01*
Y606586D01*
X965323Y606628D01*
G03X962629I-1347J664D01*
G01X962650Y606586D01*
Y603805D01*
X959629D01*
X959589Y603845D01*
Y608073D01*
G02X960124Y608450I400J0D01*
G03X961976Y610528I505J1414D01*
G01X961956Y610570D01*
Y613543D01*
X965758D01*
Y609864D01*
G03X968886I1564J0D01*
G37*
G36*
G01X959731Y592252D02*
X959590Y592393D01*
Y593838D01*
X960104Y594353D01*
X962199D01*
G02X962593Y593887I0J-400D01*
G03X962813Y592875I1383J-229D01*
G02X962481Y592252I-332J-223D01*
G01X959731D01*
G37*
G36*
G01X1027642Y5826D02*
Y8645D01*
X1026403Y9883D01*
Y15413D01*
X1026488Y15498D01*
X1030210D01*
Y6363D01*
X1029674Y5826D01*
X1027642D01*
G37*
G36*
G01X1002649Y7700D02*
X1002100Y7151D01*
Y2400D01*
X1001700Y2000D01*
X1000100D01*
X999500Y2600D01*
Y7125D01*
X998925Y7700D01*
G02X998596Y8327I0J400D01*
G03X996286I-1155J795D01*
G02X995957Y7700I-329J-227D01*
G01X995578D01*
G02X995249Y8327I0J400D01*
G03X992939I-1155J795D01*
G02X992610Y7700I-329J-227D01*
G01X988890D01*
G02X988560Y8325I1J400D01*
G03X988422Y10075I-1159J789D01*
G02X988714Y10748I292J273D01*
G01X989502D01*
Y11248D01*
X991002D01*
Y15152D01*
X989502D01*
Y15466D01*
G02X990089Y15819I400J0D01*
G03X992020Y17647I659J1238D01*
G02X992389Y18200I370J153D01*
G01X992453D01*
G02X992822Y17647I-1J-400D01*
G03X995366I1272J-590D01*
G02X995735Y18200I370J153D01*
G01X995900D01*
X996300Y18600D01*
Y23600D01*
X996700Y24000D01*
X998100D01*
X998700Y23400D01*
Y18646D01*
X999300Y18046D01*
Y14700D01*
X999356Y14644D01*
Y11698D01*
Y11248D01*
X1000856D01*
Y10748D01*
X1002813D01*
G02X1003106Y10076I0J-400D01*
G03X1002978Y8327I1027J-954D01*
G02X1002649Y7700I-329J-227D01*
G37*
G36*
G01X978851D02*
G02X978521Y8325I1J400D01*
G03X977004Y10470I-1159J789D01*
G02X976502Y10856I-102J386D01*
G01Y11248D01*
X978002D01*
Y15152D01*
X976502D01*
Y15652D01*
X975511D01*
G02X975179Y16275I0J400D01*
G03X975287Y17647I-1164J782D01*
G02X975656Y18200I370J153D01*
G01X975800D01*
X976000Y18400D01*
Y23400D01*
X976700Y24100D01*
X978100D01*
X978700Y23500D01*
Y18567D01*
X979067Y18200D01*
G02X979436Y17647I-1J-400D01*
G03X981980I1272J-590D01*
G02X982349Y18200I370J153D01*
G01X982414D01*
G02X982783Y17647I-1J-400D01*
G03X984478Y15720I1272J-590D01*
G02X984998Y15339I120J-381D01*
G01Y14602D01*
X984280D01*
X984256Y14608D01*
G03Y11792I-356J-1408D01*
G01X984280Y11798D01*
X984998D01*
Y10748D01*
X986088D01*
G02X986380Y10075I0J-400D01*
G03X986242Y8325I1021J-961D01*
G02X985912Y7700I-331J-225D01*
G01X985543D01*
G02X985213Y8325I1J400D01*
G03X982895I-1159J789D01*
G02X982565Y7700I-331J-225D01*
G01X978851D01*
G37*
G36*
G01X985219Y16275D02*
G03X985327Y17647I-1164J782D01*
G02X985696Y18200I370J153D01*
G01X989107D01*
G02X989476Y17647I-1J-400D01*
G03X989584Y16275I1272J-590D01*
G02X989252Y15652I-332J-223D01*
G01X985551D01*
G02X985219Y16275I0J400D01*
G37*
G36*
G01X1017150Y8000D02*
X1015617Y9533D01*
X1015602Y9579D01*
G03X1015000Y10369I-1429J-464D01*
G01Y15533D01*
X1015167Y15561D01*
G03X1016297Y17641I-248J1482D01*
G02X1016663Y18200I367J159D01*
G01X1017900D01*
X1018498Y17601D01*
Y16585D01*
X1018500Y16584D01*
Y16000D01*
X1019100Y15400D01*
X1023332D01*
X1023398Y15334D01*
Y10614D01*
X1023386Y10602D01*
X1019685D01*
X1018832Y9748D01*
X1018498Y9415D01*
Y8500D01*
X1017998Y8000D01*
X1017150D01*
G37*
G36*
G01X1020000Y-18500D02*
X1019812Y-18312D01*
Y-15407D01*
X1019817Y-15386D01*
G03X1019871Y-14784I-2296J509D01*
G01X1019870Y-14780D01*
Y-9786D01*
G03X1019817Y-9285I-2351J5D01*
G01X1019812Y-9264D01*
Y-2380D01*
X1019817Y-2359D01*
G03X1019870Y-1858I-2298J496D01*
G01Y3136D01*
X1019871Y3140D01*
G03Y3326I-2350J93D01*
G01X1019870Y3330D01*
Y6780D01*
X1019885Y6795D01*
Y9385D01*
X1020100Y9600D01*
X1025270D01*
X1026640Y8230D01*
Y5125D01*
X1026940Y4825D01*
X1030089D01*
X1031212Y5948D01*
Y15968D01*
X1030680Y16500D01*
X1020000D01*
X1019872Y16628D01*
Y22876D01*
G03Y22970I-2351J47D01*
G01Y35897D01*
Y44322D01*
X1019900Y44350D01*
X1028066D01*
X1030430Y41986D01*
Y41976D01*
X1030974Y41431D01*
X1032210D01*
X1033073Y42294D01*
Y43524D01*
X1031450Y45147D01*
Y55303D01*
X1031889Y55742D01*
Y57456D01*
X1031313Y58032D01*
X1029642D01*
X1029110Y57500D01*
X1023500D01*
X1023000Y57000D01*
X1020000D01*
X1019500Y57500D01*
Y59453D01*
G03X1019872Y60723I-1979J1269D01*
G01Y64872D01*
X1022700Y67700D01*
X1026250D01*
X1030050Y71500D01*
X1034196D01*
Y67328D01*
G03X1041027Y65735I3601J0D01*
G02X1041786Y65558I359J-177D01*
G01Y56004D01*
X1042576Y55214D01*
Y54061D01*
X1044000Y52637D01*
Y51497D01*
X1042772Y50269D01*
Y47577D01*
X1040948Y45754D01*
Y37333D01*
G02X1040274Y37043I-400J1D01*
G03X1034196Y34428I-2476J-2615D01*
G01Y29528D01*
G03X1041398I3601J0D01*
G01Y33025D01*
G02X1041740Y33166I200J0D01*
G01X1042000Y32906D01*
Y14132D01*
X1041740Y13872D01*
G02X1041398Y14013I-142J141D01*
G01Y15528D01*
G03X1034196I-3601J0D01*
G01Y10628D01*
G03X1040274Y8013I3602J0D01*
G02X1040948Y7723I274J-291D01*
G01Y3648D01*
X1037611Y311D01*
X1036324D01*
X1034029Y-1984D01*
Y-11971D01*
X1027500Y-18500D01*
X1020000D01*
G37*
G36*
G01X1019240Y55710D02*
X1021530D01*
X1023628Y53612D01*
Y48598D01*
X1023490Y48460D01*
X1021647D01*
G03X1019653I-997J-1560D01*
G01X1014910D01*
X1014705Y48665D01*
Y53095D01*
X1015590Y53980D01*
Y54343D01*
X1015600Y54373D01*
G03Y55311I-1427J469D01*
G01X1015590Y55341D01*
Y56672D01*
X1015676D01*
Y64774D01*
X1015590D01*
Y66670D01*
X1016220Y67300D01*
X1018030D01*
X1018660Y66670D01*
Y65076D01*
X1018498Y64915D01*
Y57085D01*
X1018660Y56924D01*
Y56290D01*
X1019240Y55710D01*
G37*
G36*
G01X1005086Y45893D02*
G03X1005331Y47650I-953J1028D01*
G02X1005673Y48258I342J208D01*
G01X1006990D01*
X1007014Y48251D01*
G03X1008318Y48559I356J1408D01*
G02X1008648Y48408I130J-151D01*
G01Y48348D01*
X1009530D01*
G02X1009866Y47731I0J-400D01*
G03X1010066Y45850I1260J-817D01*
G01Y45849D01*
X1010208Y45708D01*
X1009700Y45200D01*
X1005357D01*
G02X1005086Y45893I1J400D01*
G37*
G36*
G01X978321Y45892D02*
G03X977004Y48269I-960J1022D01*
G02X976502Y48656I-102J387D01*
G01Y49048D01*
X978002D01*
Y52952D01*
X976502D01*
Y53452D01*
X975510D01*
G02X975178Y54075I0J400D01*
G03X974904Y55941I-1163J782D01*
G02X975158Y56650I254J309D01*
G01X979565D01*
G02X979819Y55941I0J-400D01*
G03X981597I889J-1084D01*
G02X981851Y56650I254J309D01*
G01X982912D01*
G02X983166Y55941I0J-400D01*
G03X984478Y53520I889J-1084D01*
G02X984998Y53139I120J-381D01*
G01Y52302D01*
X984545D01*
X984506Y52320D01*
G03Y49680I-606J-1320D01*
G01X984545Y49698D01*
X984998D01*
Y48548D01*
X986088D01*
G02X986380Y47875I0J-400D01*
G03X986442Y45892I1021J-961D01*
G02X986168Y45200I-274J-292D01*
G01X985287D01*
G02X985013Y45892I0J400D01*
G03X983095I-959J1022D01*
G02X982821Y45200I-274J-292D01*
G01X978595D01*
G02X978321Y45892I0J400D01*
G37*
G36*
G01X988360D02*
G03X988422Y47875I-959J1022D01*
G02X988714Y48548I292J273D01*
G01X989502D01*
Y49048D01*
X991002D01*
Y52952D01*
X989502D01*
Y53266D01*
G02X990089Y53619I400J0D01*
G03X991637Y55941I659J1237D01*
G02X991891Y56650I254J309D01*
G01X992951D01*
G02X993205Y55941I0J-400D01*
G03X994983I889J-1084D01*
G02X995237Y56650I254J309D01*
G01X999644D01*
G02X999898Y55941I0J-400D01*
G03X1000673Y53460I889J-1084D01*
G02X1000856Y53260I-17J-199D01*
G01Y52952D01*
X999356D01*
Y49048D01*
X1000856D01*
Y48548D01*
X1002813D01*
G02X1003106Y47876I0J-400D01*
G03X1003180Y45893I1027J-955D01*
G02X1002909Y45200I-272J-293D01*
G01X998665D01*
G02X998394Y45893I1J400D01*
G03X996488I-953J1029D01*
G02X996217Y45200I-272J-293D01*
G01X995318D01*
G02X995047Y45893I1J400D01*
G03X993141I-953J1029D01*
G02X992870Y45200I-272J-293D01*
G01X988634D01*
G02X988360Y45892I0J400D01*
G37*
G36*
G01X1005360Y51060D02*
Y53452D01*
X1005189D01*
X1005057Y53802D01*
G03X1005023Y55941I-923J1055D01*
G02X1005277Y56650I254J309D01*
G01X1009490D01*
X1009718Y56422D01*
G02X1009728Y55866I-283J-283D01*
G03X1009403Y54362I1098J-1024D01*
G02X1009024Y53834I-379J-128D01*
G01X1007370D01*
G03X1006045Y51627I0J-1501D01*
G01X1006068Y51583D01*
Y51060D01*
X1005360D01*
G37*
G36*
G01X985218Y54075D02*
G03X984944Y55941I-1163J782D01*
G02X985198Y56650I254J309D01*
G01X989605D01*
G02X989859Y55941I0J-400D01*
G03X989585Y54075I889J-1084D01*
G02X989253Y53452I-332J-223D01*
G01X985550D01*
G02X985218Y54075I0J400D01*
G37*
G36*
G01X1030100Y101100D02*
X1033829D01*
X1036600Y98329D01*
Y96600D01*
X1034700Y94700D01*
X1032452D01*
Y95252D01*
X1028624D01*
Y98851D01*
X1029706Y99933D01*
Y100707D01*
X1030100Y101100D01*
G37*
G36*
G01X977137Y195598D02*
X976737Y195737D01*
Y196158D01*
X977137Y196298D01*
X977337D01*
Y195598D01*
X977137D01*
G37*
G36*
G01X973297Y185139D02*
X973481Y184757D01*
X973184Y184460D01*
X972802Y184644D01*
X972660Y184785D01*
X973155Y185280D01*
X973297Y185139D01*
G37*
G36*
G01X973120Y185528D02*
X972936Y185910D01*
X973233Y186207D01*
X973615Y186023D01*
X973756Y185881D01*
X973261Y185386D01*
X973120Y185528D01*
G37*
G36*
G01X974322Y186730D02*
X974138Y187112D01*
X974435Y187409D01*
X974817Y187225D01*
X974958Y187083D01*
X974463Y186588D01*
X974322Y186730D01*
G37*
G36*
G01X975524Y187932D02*
X975340Y188314D01*
X975637Y188611D01*
X976019Y188427D01*
X976160Y188285D01*
X975665Y187790D01*
X975524Y187932D01*
G37*
G36*
G01X974499Y186341D02*
X974683Y185959D01*
X974386Y185662D01*
X974004Y185846D01*
X973862Y185987D01*
X974357Y186482D01*
X974499Y186341D01*
G37*
G36*
G01X975701Y187543D02*
X975885Y187161D01*
X975588Y186864D01*
X975206Y187048D01*
X975064Y187189D01*
X975559Y187684D01*
X975701Y187543D01*
G37*
G36*
G01X977537Y192048D02*
X977937Y191908D01*
Y191487D01*
X977537Y191348D01*
X977337D01*
Y192048D01*
X977537D01*
G37*
G36*
G01Y193748D02*
X977937Y193608D01*
Y193187D01*
X977537Y193048D01*
X977337D01*
Y193748D01*
X977537D01*
G37*
G36*
G01Y195448D02*
X977937Y195308D01*
Y194887D01*
X977537Y194748D01*
X977337D01*
Y195448D01*
X977537D01*
G37*
G36*
G01X977137Y192198D02*
X976737Y192337D01*
Y192758D01*
X977137Y192898D01*
X977337D01*
Y192198D01*
X977137D01*
G37*
G36*
G01Y193898D02*
X976737Y194037D01*
Y194458D01*
X977137Y194598D01*
X977337D01*
Y193898D01*
X977137D01*
G37*
G36*
G01Y190498D02*
X976737Y190637D01*
Y191058D01*
X977137Y191198D01*
X977337D01*
Y190498D01*
X977137D01*
G37*
G36*
G01X977537Y190348D02*
X977937Y190208D01*
Y189787D01*
X977537Y189648D01*
X977337D01*
Y190348D01*
X977537D01*
G37*
G36*
G01X976903Y188745D02*
X977087Y188363D01*
X976790Y188066D01*
X976408Y188250D01*
X976266Y188391D01*
X976761Y188886D01*
X976903Y188745D01*
G37*
G36*
G01X971918Y184326D02*
X971734Y184707D01*
X972031Y185004D01*
X972413Y184821D01*
X972554Y184679D01*
X972059Y184184D01*
X971918Y184326D01*
G37*
G36*
G01X978337Y195598D02*
X977937Y195737D01*
Y196158D01*
X978337Y196298D01*
X978537D01*
Y195598D01*
X978337D01*
G37*
G36*
G01X974676Y214234D02*
X974006Y214583D01*
X974005Y215453D01*
X974674Y215804D01*
X974850D01*
X974851Y214234D01*
X974676D01*
G37*
G36*
G01X978054Y208324D02*
X977384Y208674D01*
Y209544D01*
X978054Y209894D01*
X978229D01*
Y208324D01*
X978054D01*
G37*
G36*
G01X978737Y195448D02*
X979137Y195308D01*
Y194887D01*
X978737Y194748D01*
X978537D01*
Y195448D01*
X978737D01*
G37*
G36*
G01X978337Y193898D02*
X977937Y194037D01*
Y194458D01*
X978337Y194598D01*
X978537D01*
Y193898D01*
X978337D01*
G37*
G36*
G01X978737Y193748D02*
X979137Y193608D01*
Y193187D01*
X978737Y193048D01*
X978537D01*
Y193748D01*
X978737D01*
G37*
G36*
G01X978337Y192198D02*
X977937Y192337D01*
Y192758D01*
X978337Y192898D01*
X978537D01*
Y192198D01*
X978337D01*
G37*
G36*
G01X978737Y192048D02*
X979137Y191908D01*
Y191487D01*
X978737Y191348D01*
X978537D01*
Y192048D01*
X978737D01*
G37*
G36*
G01X978337Y190498D02*
X977937Y190637D01*
Y191058D01*
X978337Y191198D01*
X978537D01*
Y190498D01*
X978337D01*
G37*
G36*
G01X978737Y190348D02*
X979137Y190208D01*
Y189787D01*
X978737Y189648D01*
X978537D01*
Y190348D01*
X978737D01*
G37*
G36*
G01X977575Y188285D02*
X977391Y188667D01*
X977688Y188964D01*
X978070Y188780D01*
X978211Y188638D01*
X977716Y188143D01*
X977575Y188285D01*
G37*
G36*
G01X977752Y187896D02*
X977936Y187514D01*
X977639Y187217D01*
X977257Y187401D01*
X977116Y187543D01*
X977610Y188037D01*
X977752Y187896D01*
G37*
G36*
G01X976373Y187083D02*
X976189Y187465D01*
X976486Y187762D01*
X976868Y187578D01*
X977009Y187436D01*
X976514Y186941D01*
X976373Y187083D01*
G37*
G36*
G01X976550Y186694D02*
X976734Y186312D01*
X976437Y186015D01*
X976055Y186199D01*
X975913Y186340D01*
X976408Y186835D01*
X976550Y186694D01*
G37*
G36*
G01X975171Y185881D02*
X974987Y186263D01*
X975284Y186560D01*
X975666Y186376D01*
X975807Y186234D01*
X975312Y185739D01*
X975171Y185881D01*
G37*
G36*
G01X975348Y185492D02*
X975532Y185110D01*
X975235Y184813D01*
X974853Y184997D01*
X974711Y185138D01*
X975206Y185633D01*
X975348Y185492D01*
G37*
G36*
G01X973969Y184679D02*
X973785Y185061D01*
X974082Y185358D01*
X974464Y185174D01*
X974605Y185032D01*
X974110Y184537D01*
X973969Y184679D01*
G37*
G36*
G01X974146Y184290D02*
X974330Y183908D01*
X974033Y183611D01*
X973651Y183795D01*
X973509Y183936D01*
X974004Y184431D01*
X974146Y184290D01*
G37*
G36*
G01X972767Y183477D02*
X972583Y183858D01*
X972880Y184155D01*
X973262Y183972D01*
X973403Y183830D01*
X972908Y183335D01*
X972767Y183477D01*
G37*
G36*
G01X972944Y183088D02*
X973127Y182706D01*
X972830Y182409D01*
X972449Y182593D01*
X972307Y182734D01*
X972802Y183229D01*
X972944Y183088D01*
G37*
G36*
G01X975937Y195598D02*
X975537Y195737D01*
Y196158D01*
X975937Y196298D01*
X976137D01*
Y195598D01*
X975937D01*
G37*
G36*
G01X972448Y185988D02*
X972632Y185606D01*
X972335Y185309D01*
X971953Y185493D01*
X971811Y185634D01*
X972306Y186129D01*
X972448Y185988D01*
G37*
G36*
G01X972271Y186377D02*
X972087Y186759D01*
X972384Y187056D01*
X972766Y186872D01*
X972907Y186730D01*
X972412Y186235D01*
X972271Y186377D01*
G37*
G36*
G01X973473Y187579D02*
X973289Y187961D01*
X973586Y188258D01*
X973968Y188074D01*
X974109Y187932D01*
X973614Y187437D01*
X973473Y187579D01*
G37*
G36*
G01X974675Y188781D02*
X974491Y189163D01*
X974788Y189460D01*
X975170Y189276D01*
X975311Y189134D01*
X974816Y188639D01*
X974675Y188781D01*
G37*
G36*
G01X973650Y187190D02*
X973834Y186808D01*
X973537Y186511D01*
X973155Y186695D01*
X973013Y186836D01*
X973508Y187331D01*
X973650Y187190D01*
G37*
G36*
G01X974852Y188392D02*
X975036Y188010D01*
X974739Y187713D01*
X974357Y187897D01*
X974215Y188038D01*
X974710Y188533D01*
X974852Y188392D01*
G37*
G36*
G01X976337Y195448D02*
X976737Y195308D01*
Y194887D01*
X976337Y194748D01*
X976137D01*
Y195448D01*
X976337D01*
G37*
G36*
G01Y193748D02*
X976737Y193608D01*
Y193187D01*
X976337Y193048D01*
X976137D01*
Y193748D01*
X976337D01*
G37*
G36*
G01Y192048D02*
X976737Y191908D01*
Y191487D01*
X976337Y191348D01*
X976137D01*
Y192048D01*
X976337D01*
G37*
G36*
G01X975937Y192198D02*
X975537Y192337D01*
Y192758D01*
X975937Y192898D01*
X976137D01*
Y192198D01*
X975937D01*
G37*
G36*
G01Y193898D02*
X975537Y194037D01*
Y194458D01*
X975937Y194598D01*
X976137D01*
Y193898D01*
X975937D01*
G37*
G36*
G01Y190498D02*
X975537Y190637D01*
Y191058D01*
X975937Y191198D01*
X976137D01*
Y190498D01*
X975937D01*
G37*
G36*
G01X976054Y189594D02*
X976238Y189212D01*
X975941Y188915D01*
X975559Y189099D01*
X975417Y189240D01*
X975912Y189735D01*
X976054Y189594D01*
G37*
G36*
G01X979537Y195598D02*
X979137Y195737D01*
Y196158D01*
X979537Y196298D01*
X979737D01*
Y195598D01*
X979537D01*
G37*
G36*
G01X979678Y207969D02*
X980348Y207619D01*
Y206749D01*
X979678Y206399D01*
X979503D01*
Y207969D01*
X979678D01*
G37*
G36*
G01Y211869D02*
X980348Y211519D01*
Y210649D01*
X979678Y210299D01*
X979503D01*
Y211869D01*
X979678D01*
G37*
G36*
G01X976020Y185032D02*
X975836Y185414D01*
X976133Y185711D01*
X976515Y185527D01*
X976656Y185385D01*
X976161Y184890D01*
X976020Y185032D01*
G37*
G36*
G01X977222Y186234D02*
X977038Y186616D01*
X977335Y186913D01*
X977717Y186729D01*
X977858Y186587D01*
X977363Y186092D01*
X977222Y186234D01*
G37*
G36*
G01X978424Y187436D02*
X978240Y187818D01*
X978537Y188115D01*
X978919Y187931D01*
X979061Y187790D01*
X978566Y187295D01*
X978424Y187436D01*
G37*
G36*
G01X977399Y185845D02*
X977583Y185463D01*
X977286Y185166D01*
X976904Y185350D01*
X976762Y185491D01*
X977257Y185986D01*
X977399Y185845D01*
G37*
G36*
G01X978601Y187047D02*
X978785Y186665D01*
X978488Y186368D01*
X978106Y186552D01*
X977965Y186694D01*
X978459Y187188D01*
X978601Y187047D01*
G37*
G36*
G01X979937Y192048D02*
X980337Y191908D01*
Y191487D01*
X979937Y191348D01*
X979737D01*
Y192048D01*
X979937D01*
G37*
G36*
G01Y190348D02*
X980337Y190208D01*
Y189787D01*
X979937Y189648D01*
X979737D01*
Y190348D01*
X979937D01*
G37*
G36*
G01Y193748D02*
X980337Y193608D01*
Y193187D01*
X979937Y193048D01*
X979737D01*
Y193748D01*
X979937D01*
G37*
G36*
G01Y195448D02*
X980337Y195308D01*
Y194887D01*
X979937Y194748D01*
X979737D01*
Y195448D01*
X979937D01*
G37*
G36*
G01X979537Y190498D02*
X979137Y190637D01*
Y191058D01*
X979537Y191198D01*
X979737D01*
Y190498D01*
X979537D01*
G37*
G36*
G01Y192198D02*
X979137Y192337D01*
Y192758D01*
X979537Y192898D01*
X979737D01*
Y192198D01*
X979537D01*
G37*
G36*
G01Y193898D02*
X979137Y194037D01*
Y194458D01*
X979537Y194598D01*
X979737D01*
Y193898D01*
X979537D01*
G37*
G36*
G01Y188798D02*
X979137Y188937D01*
Y189358D01*
X979537Y189498D01*
X979737D01*
Y188798D01*
X979537D01*
G37*
G36*
G01X979803Y188249D02*
X979987Y187867D01*
X979690Y187570D01*
X979308Y187754D01*
X979167Y187896D01*
X979661Y188390D01*
X979803Y188249D01*
G37*
G36*
G01X972590Y181037D02*
X972774Y180655D01*
X972477Y180358D01*
X972096Y180542D01*
X971954Y180683D01*
X972449Y181178D01*
X972590Y181037D01*
G37*
G36*
G01X972414Y181426D02*
X972230Y181807D01*
X972527Y182104D01*
X972909Y181921D01*
X973050Y181779D01*
X972555Y181284D01*
X972414Y181426D01*
G37*
G36*
G01X973616Y182628D02*
X973432Y183009D01*
X973729Y183306D01*
X974111Y183123D01*
X974252Y182981D01*
X973757Y182486D01*
X973616Y182628D01*
G37*
G36*
G01X974818Y183830D02*
X974634Y184212D01*
X974931Y184509D01*
X975313Y184325D01*
X975454Y184183D01*
X974959Y183688D01*
X974818Y183830D01*
G37*
G36*
G01X973793Y182239D02*
X973976Y181857D01*
X973679Y181560D01*
X973298Y181744D01*
X973156Y181885D01*
X973651Y182380D01*
X973793Y182239D01*
G37*
G36*
G01X974995Y183441D02*
X975179Y183059D01*
X974882Y182762D01*
X974500Y182946D01*
X974358Y183087D01*
X974853Y183582D01*
X974995Y183441D01*
G37*
G36*
G01X976197Y184643D02*
X976381Y184261D01*
X976084Y183964D01*
X975702Y184148D01*
X975560Y184289D01*
X976055Y184784D01*
X976197Y184643D01*
G37*
G36*
G01X973537Y195598D02*
X973137Y195737D01*
Y196158D01*
X973537Y196298D01*
X973737D01*
Y195598D01*
X973537D01*
G37*
G36*
G01X971775Y189277D02*
X971591Y189659D01*
X971888Y189956D01*
X972270Y189772D01*
X972411Y189630D01*
X971916Y189135D01*
X971775Y189277D01*
G37*
G36*
G01X973154Y190090D02*
X973338Y189708D01*
X973041Y189411D01*
X972659Y189595D01*
X972517Y189736D01*
X973012Y190231D01*
X973154Y190090D01*
G37*
G36*
G01X973937Y193748D02*
X974337Y193608D01*
Y193187D01*
X973937Y193048D01*
X973737D01*
Y193748D01*
X973937D01*
G37*
G36*
G01Y195448D02*
X974337Y195308D01*
Y194887D01*
X973937Y194748D01*
X973737D01*
Y195448D01*
X973937D01*
G37*
G36*
G01X973537Y193898D02*
X973137Y194037D01*
Y194458D01*
X973537Y194598D01*
X973737D01*
Y193898D01*
X973537D01*
G37*
G36*
G01Y192198D02*
X973137Y192337D01*
Y192758D01*
X973537Y192898D01*
X973737D01*
Y192198D01*
X973537D01*
G37*
G36*
G01X973937Y192048D02*
X974337Y191908D01*
Y191487D01*
X973937Y191348D01*
X973737D01*
Y192048D01*
X973937D01*
G37*
G36*
G01X972973Y207931D02*
X973642Y207578D01*
X973639Y206709D01*
X972968Y206361D01*
X972792Y206362D01*
X972798Y207931D01*
X972973D01*
G37*
G36*
G01X974737Y195598D02*
X974337Y195737D01*
Y196158D01*
X974737Y196298D01*
X974937D01*
Y195598D01*
X974737D01*
G37*
G36*
G01X972624Y188428D02*
X972440Y188810D01*
X972737Y189107D01*
X973119Y188923D01*
X973260Y188781D01*
X972765Y188286D01*
X972624Y188428D01*
G37*
G36*
G01X972801Y188039D02*
X972985Y187657D01*
X972688Y187360D01*
X972306Y187544D01*
X972164Y187685D01*
X972659Y188180D01*
X972801Y188039D01*
G37*
G36*
G01X974003Y189241D02*
X974187Y188859D01*
X973890Y188562D01*
X973508Y188746D01*
X973366Y188887D01*
X973861Y189382D01*
X974003Y189241D01*
G37*
G36*
G01X975137Y193748D02*
X975537Y193608D01*
Y193187D01*
X975137Y193048D01*
X974937D01*
Y193748D01*
X975137D01*
G37*
G36*
G01Y195448D02*
X975537Y195308D01*
Y194887D01*
X975137Y194748D01*
X974937D01*
Y195448D01*
X975137D01*
G37*
G36*
G01X974737Y192198D02*
X974337Y192337D01*
Y192758D01*
X974737Y192898D01*
X974937D01*
Y192198D01*
X974737D01*
G37*
G36*
G01Y193898D02*
X974337Y194037D01*
Y194458D01*
X974737Y194598D01*
X974937D01*
Y193898D01*
X974737D01*
G37*
G36*
G01Y190498D02*
X974337Y190637D01*
Y191058D01*
X974737Y191198D01*
X974937D01*
Y190498D01*
X974737D01*
G37*
G36*
G01X975137Y192048D02*
X975537Y191908D01*
Y191487D01*
X975137Y191348D01*
X974937D01*
Y192048D01*
X975137D01*
G37*
G36*
G01X973826Y189630D02*
X973642Y190012D01*
X973939Y190309D01*
X974321Y190125D01*
X974462Y189983D01*
X973967Y189488D01*
X973826Y189630D01*
G37*
G36*
G01X984814Y208324D02*
X984144Y208674D01*
Y209544D01*
X984814Y209894D01*
X984989D01*
Y208324D01*
X984814D01*
G37*
G36*
G01X980971Y184889D02*
X980787Y185271D01*
X981084Y185568D01*
X981466Y185384D01*
X981608Y185243D01*
X981113Y184748D01*
X980971Y184889D01*
G37*
G36*
G01X982350Y185702D02*
X982534Y185320D01*
X982237Y185023D01*
X981855Y185207D01*
X981714Y185349D01*
X982209Y185844D01*
X982350Y185702D01*
G37*
G36*
G01X983537Y190348D02*
X983937Y190208D01*
Y189787D01*
X983537Y189648D01*
X983337D01*
Y190348D01*
X983537D01*
G37*
G36*
G01Y188648D02*
X983937Y188508D01*
Y188087D01*
X983537Y187948D01*
X983337D01*
Y188648D01*
X983537D01*
G37*
G36*
G01Y192048D02*
X983937Y191908D01*
Y191487D01*
X983537Y191348D01*
X983337D01*
Y192048D01*
X983537D01*
G37*
G36*
G01Y193748D02*
X983937Y193608D01*
Y193187D01*
X983537Y193048D01*
X983337D01*
Y193748D01*
X983537D01*
G37*
G36*
G01X983137Y188798D02*
X982737Y188937D01*
Y189358D01*
X983137Y189498D01*
X983337D01*
Y188798D01*
X983137D01*
G37*
G36*
G01Y190498D02*
X982737Y190637D01*
Y191058D01*
X983137Y191198D01*
X983337D01*
Y190498D01*
X983137D01*
G37*
G36*
G01Y192198D02*
X982737Y192337D01*
Y192758D01*
X983137Y192898D01*
X983337D01*
Y192198D01*
X983137D01*
G37*
G36*
G01Y187098D02*
X982737Y187237D01*
Y187658D01*
X983137Y187798D01*
X983337D01*
Y187098D01*
X983137D01*
G37*
G36*
G01Y193898D02*
X982737Y194037D01*
Y194458D01*
X983137Y194598D01*
X983337D01*
Y193898D01*
X983137D01*
G37*
G36*
G01X982173Y186091D02*
X981989Y186473D01*
X982286Y186770D01*
X982668Y186586D01*
X982810Y186445D01*
X982315Y185950D01*
X982173Y186091D01*
G37*
G36*
G01X974961Y178879D02*
X974777Y179260D01*
X975074Y179557D01*
X975456Y179374D01*
X975597Y179232D01*
X975102Y178737D01*
X974961Y178879D01*
G37*
G36*
G01X976163Y180081D02*
X975979Y180462D01*
X976276Y180759D01*
X976658Y180576D01*
X976799Y180434D01*
X976304Y179939D01*
X976163Y180081D01*
G37*
G36*
G01X977365Y181283D02*
X977181Y181665D01*
X977478Y181962D01*
X977860Y181778D01*
X978001Y181636D01*
X977506Y181141D01*
X977365Y181283D01*
G37*
G36*
G01X978567Y182485D02*
X978383Y182867D01*
X978680Y183164D01*
X979062Y182980D01*
X979203Y182838D01*
X978708Y182343D01*
X978567Y182485D01*
G37*
G36*
G01X979769Y183687D02*
X979585Y184069D01*
X979882Y184366D01*
X980264Y184182D01*
X980405Y184040D01*
X979910Y183545D01*
X979769Y183687D01*
G37*
G36*
G01X976340Y179692D02*
X976523Y179310D01*
X976226Y179013D01*
X975845Y179197D01*
X975703Y179338D01*
X976198Y179833D01*
X976340Y179692D01*
G37*
G36*
G01X977542Y180894D02*
X977726Y180512D01*
X977429Y180215D01*
X977047Y180399D01*
X976905Y180540D01*
X977400Y181035D01*
X977542Y180894D01*
G37*
G36*
G01X978744Y182096D02*
X978928Y181714D01*
X978631Y181417D01*
X978249Y181601D01*
X978107Y181742D01*
X978602Y182237D01*
X978744Y182096D01*
G37*
G36*
G01X979946Y183298D02*
X980130Y182916D01*
X979833Y182619D01*
X979451Y182803D01*
X979309Y182944D01*
X979804Y183439D01*
X979946Y183298D01*
G37*
G36*
G01X981148Y184500D02*
X981332Y184118D01*
X981035Y183821D01*
X980653Y184005D01*
X980512Y184147D01*
X981006Y184641D01*
X981148Y184500D01*
G37*
G36*
G01X973759Y177676D02*
X973575Y178058D01*
X973872Y178355D01*
X974254Y178171D01*
X974395Y178030D01*
X973900Y177535D01*
X973759Y177676D01*
G37*
G36*
G01X975137Y178490D02*
X975321Y178108D01*
X975024Y177811D01*
X974643Y177995D01*
X974501Y178136D01*
X974996Y178631D01*
X975137Y178490D01*
G37*
G36*
G01X972733Y176085D02*
X972917Y175704D01*
X972620Y175407D01*
X972238Y175591D01*
X972097Y175732D01*
X972592Y176227D01*
X972733Y176085D01*
G37*
G36*
G01X972557Y176474D02*
X972373Y176856D01*
X972670Y177153D01*
X973052Y176969D01*
X973193Y176828D01*
X972698Y176333D01*
X972557Y176474D01*
G37*
G36*
G01X973935Y177288D02*
X974119Y176906D01*
X973822Y176609D01*
X973440Y176793D01*
X973299Y176934D01*
X973794Y177429D01*
X973935Y177288D01*
G37*
G36*
G01X983552Y186904D02*
X983736Y186522D01*
X983439Y186225D01*
X983057Y186409D01*
X982916Y186551D01*
X983411Y187046D01*
X983552Y186904D01*
G37*
G36*
G01X984605Y213583D02*
X985255Y213968D01*
X985995Y213509D01*
X985939Y212755D01*
X985846Y212606D01*
X984512Y213434D01*
X984605Y213583D01*
G37*
G36*
G01X983022Y185242D02*
X982838Y185624D01*
X983135Y185921D01*
X983517Y185737D01*
X983694Y185561D01*
X983199Y185066D01*
X983022Y185242D01*
G37*
G36*
G01X984337Y192198D02*
X983937Y192337D01*
Y192758D01*
X984337Y192898D01*
X984587D01*
Y192198D01*
X984337D01*
G37*
G36*
G01Y190498D02*
X983937Y190637D01*
Y191058D01*
X984337Y191198D01*
X984587D01*
Y190498D01*
X984337D01*
G37*
G36*
G01Y188798D02*
X983937Y188937D01*
Y189358D01*
X984337Y189498D01*
X984587D01*
Y188798D01*
X984337D01*
G37*
G36*
G01Y187098D02*
X983937Y187237D01*
Y187658D01*
X984337Y187798D01*
X984587D01*
Y187098D01*
X984337D01*
G37*
G36*
G01Y193898D02*
X983937Y194037D01*
Y194458D01*
X984337Y194598D01*
X984587D01*
Y193898D01*
X984337D01*
G37*
G36*
G01X977011Y179232D02*
X976828Y179614D01*
X977125Y179911D01*
X977506Y179727D01*
X977683Y179550D01*
X977188Y179055D01*
X977011Y179232D01*
G37*
G36*
G01X978214Y180434D02*
X978030Y180816D01*
X978327Y181113D01*
X978708Y180929D01*
X978885Y180752D01*
X978390Y180257D01*
X978214Y180434D01*
G37*
G36*
G01X979416Y181636D02*
X979232Y182018D01*
X979529Y182315D01*
X979911Y182131D01*
X980087Y181954D01*
X979592Y181459D01*
X979416Y181636D01*
G37*
G36*
G01X980618Y182838D02*
X980434Y183220D01*
X980731Y183517D01*
X981113Y183333D01*
X981289Y183156D01*
X980794Y182661D01*
X980618Y182838D01*
G37*
G36*
G01X981820Y184040D02*
X981636Y184422D01*
X981933Y184719D01*
X982315Y184535D01*
X982492Y184359D01*
X981997Y183864D01*
X981820Y184040D01*
G37*
G36*
G01X975809Y178030D02*
X975626Y178412D01*
X975922Y178709D01*
X976304Y178525D01*
X976481Y178348D01*
X975986Y177853D01*
X975809Y178030D01*
G37*
G36*
G01X972203Y174424D02*
X972019Y174806D01*
X972316Y175102D01*
X972698Y174919D01*
X972875Y174742D01*
X972380Y174247D01*
X972203Y174424D01*
G37*
G36*
G01X974607Y176828D02*
X974423Y177210D01*
X974720Y177507D01*
X975102Y177323D01*
X975279Y177146D01*
X974784Y176651D01*
X974607Y176828D01*
G37*
G36*
G01X973405Y175626D02*
X973221Y176008D01*
X973518Y176305D01*
X973900Y176121D01*
X974077Y175944D01*
X973582Y175449D01*
X973405Y175626D01*
G37*
G36*
G01X972337Y195598D02*
X971937Y195737D01*
Y196158D01*
X972337Y196298D01*
X972537D01*
Y195598D01*
X972337D01*
G37*
G36*
G01X972358Y214168D02*
X971891Y214763D01*
X972249Y215556D01*
X973004Y215599D01*
X973164Y215526D01*
X972516Y214096D01*
X972358Y214168D01*
G37*
G36*
G01X972337Y193898D02*
X971937Y194037D01*
Y194458D01*
X972337Y194598D01*
X972537D01*
Y193898D01*
X972337D01*
G37*
G36*
G01Y192198D02*
X971937Y192337D01*
Y192758D01*
X972337Y192898D01*
X972537D01*
Y192198D01*
X972337D01*
G37*
G36*
G01X972305Y190939D02*
X972489Y190557D01*
X972192Y190260D01*
X971810Y190444D01*
X971668Y190585D01*
X972163Y191080D01*
X972305Y190939D01*
G37*
G36*
G01X972737Y195448D02*
X973137Y195308D01*
Y194887D01*
X972737Y194748D01*
X972537D01*
Y195448D01*
X972737D01*
G37*
G36*
G01Y193748D02*
X973137Y193608D01*
Y193187D01*
X972737Y193048D01*
X972537D01*
Y193748D01*
X972737D01*
G37*
G36*
G01Y192048D02*
X973137Y191908D01*
Y191487D01*
X972737Y191348D01*
X972537D01*
Y192048D01*
X972737D01*
G37*
G36*
G01X980737Y195598D02*
X980337Y195737D01*
Y196158D01*
X980737Y196298D01*
X980937D01*
Y195598D01*
X980737D01*
G37*
G36*
G01X978071Y185385D02*
X977887Y185767D01*
X978184Y186064D01*
X978566Y185880D01*
X978707Y185738D01*
X978212Y185243D01*
X978071Y185385D01*
G37*
G36*
G01X979273Y186587D02*
X979089Y186969D01*
X979386Y187266D01*
X979768Y187082D01*
X979910Y186941D01*
X979415Y186446D01*
X979273Y186587D01*
G37*
G36*
G01X979450Y186198D02*
X979634Y185816D01*
X979337Y185519D01*
X978955Y185703D01*
X978814Y185845D01*
X979308Y186339D01*
X979450Y186198D01*
G37*
G36*
G01X981137Y192048D02*
X981537Y191908D01*
Y191487D01*
X981137Y191348D01*
X980937D01*
Y192048D01*
X981137D01*
G37*
G36*
G01Y190348D02*
X981537Y190208D01*
Y189787D01*
X981137Y189648D01*
X980937D01*
Y190348D01*
X981137D01*
G37*
G36*
G01Y193748D02*
X981537Y193608D01*
Y193187D01*
X981137Y193048D01*
X980937D01*
Y193748D01*
X981137D01*
G37*
G36*
G01Y195448D02*
X981537Y195308D01*
Y194887D01*
X981137Y194748D01*
X980937D01*
Y195448D01*
X981137D01*
G37*
G36*
G01X980737Y190498D02*
X980337Y190637D01*
Y191058D01*
X980737Y191198D01*
X980937D01*
Y190498D01*
X980737D01*
G37*
G36*
G01Y192198D02*
X980337Y192337D01*
Y192758D01*
X980737Y192898D01*
X980937D01*
Y192198D01*
X980737D01*
G37*
G36*
G01Y193898D02*
X980337Y194037D01*
Y194458D01*
X980737Y194598D01*
X980937D01*
Y193898D01*
X980737D01*
G37*
G36*
G01Y188798D02*
X980337Y188937D01*
Y189358D01*
X980737Y189498D01*
X980937D01*
Y188798D01*
X980737D01*
G37*
G36*
G01X980652Y187400D02*
X980836Y187018D01*
X980539Y186721D01*
X980157Y186905D01*
X980016Y187047D01*
X980510Y187541D01*
X980652Y187400D01*
G37*
G36*
G01X972061Y179374D02*
X971877Y179756D01*
X972174Y180053D01*
X972556Y179869D01*
X972697Y179728D01*
X972202Y179233D01*
X972061Y179374D01*
G37*
G36*
G01X973263Y180577D02*
X973079Y180958D01*
X973376Y181255D01*
X973758Y181072D01*
X973899Y180930D01*
X973404Y180435D01*
X973263Y180577D01*
G37*
G36*
G01X974465Y181779D02*
X974281Y182160D01*
X974578Y182457D01*
X974960Y182274D01*
X975101Y182132D01*
X974606Y181637D01*
X974465Y181779D01*
G37*
G36*
G01X975667Y182981D02*
X975483Y183363D01*
X975780Y183660D01*
X976162Y183476D01*
X976303Y183334D01*
X975808Y182839D01*
X975667Y182981D01*
G37*
G36*
G01X973439Y180188D02*
X973623Y179806D01*
X973326Y179509D01*
X972945Y179693D01*
X972803Y179834D01*
X973298Y180329D01*
X973439Y180188D01*
G37*
G36*
G01X974642Y181390D02*
X974825Y181008D01*
X974528Y180711D01*
X974147Y180895D01*
X974005Y181036D01*
X974500Y181531D01*
X974642Y181390D01*
G37*
G36*
G01X975844Y182592D02*
X976028Y182210D01*
X975731Y181913D01*
X975349Y182097D01*
X975207Y182238D01*
X975702Y182733D01*
X975844Y182592D01*
G37*
G36*
G01X977046Y183794D02*
X977230Y183412D01*
X976933Y183115D01*
X976551Y183299D01*
X976409Y183440D01*
X976904Y183935D01*
X977046Y183794D01*
G37*
G36*
G01X976869Y184183D02*
X976685Y184565D01*
X976982Y184862D01*
X977364Y184678D01*
X977505Y184536D01*
X977010Y184041D01*
X976869Y184183D01*
G37*
G36*
G01X978248Y184996D02*
X978432Y184614D01*
X978135Y184317D01*
X977753Y184501D01*
X977611Y184642D01*
X978106Y185137D01*
X978248Y184996D01*
G37*
G36*
G01X972237Y178986D02*
X972421Y178604D01*
X972124Y178307D01*
X971742Y178491D01*
X971601Y178632D01*
X972096Y179127D01*
X972237Y178986D01*
G37*
G36*
G01X981137Y188648D02*
X981537Y188508D01*
Y188087D01*
X981137Y187948D01*
X980937D01*
Y188648D01*
X981137D01*
G37*
G36*
G01X981442Y206420D02*
X980772Y206772D01*
X980775Y207642D01*
X981446Y207990D01*
X981621Y207989D01*
X981617Y206420D01*
X981442D01*
G37*
G36*
G01X981937Y195598D02*
X981537Y195737D01*
Y196158D01*
X981937Y196298D01*
X982137D01*
Y195598D01*
X981937D01*
G37*
G36*
G01X983058Y209894D02*
X983728Y209544D01*
Y208674D01*
X983058Y208324D01*
X982883D01*
Y209894D01*
X983058D01*
G37*
G36*
G01X982307Y213814D02*
X982977Y213464D01*
Y212594D01*
X982307Y212244D01*
X982132D01*
Y213814D01*
X982307D01*
G37*
G36*
G01X978920Y184536D02*
X978736Y184918D01*
X979033Y185215D01*
X979415Y185031D01*
X979556Y184889D01*
X979061Y184394D01*
X978920Y184536D01*
G37*
G36*
G01X980299Y185349D02*
X980483Y184967D01*
X980186Y184670D01*
X979804Y184854D01*
X979663Y184996D01*
X980157Y185490D01*
X980299Y185349D01*
G37*
G36*
G01X981501Y186551D02*
X981685Y186169D01*
X981388Y185872D01*
X981006Y186056D01*
X980865Y186198D01*
X981360Y186693D01*
X981501Y186551D01*
G37*
G36*
G01X982337Y190348D02*
X982737Y190208D01*
Y189787D01*
X982337Y189648D01*
X982137D01*
Y190348D01*
X982337D01*
G37*
G36*
G01Y192048D02*
X982737Y191908D01*
Y191487D01*
X982337Y191348D01*
X982137D01*
Y192048D01*
X982337D01*
G37*
G36*
G01Y193748D02*
X982737Y193608D01*
Y193187D01*
X982337Y193048D01*
X982137D01*
Y193748D01*
X982337D01*
G37*
G36*
G01Y195448D02*
X982737Y195308D01*
Y194887D01*
X982337Y194748D01*
X982137D01*
Y195448D01*
X982337D01*
G37*
G36*
G01X981937Y190498D02*
X981537Y190637D01*
Y191058D01*
X981937Y191198D01*
X982137D01*
Y190498D01*
X981937D01*
G37*
G36*
G01Y188798D02*
X981537Y188937D01*
Y189358D01*
X981937Y189498D01*
X982137D01*
Y188798D01*
X981937D01*
G37*
G36*
G01Y192198D02*
X981537Y192337D01*
Y192758D01*
X981937Y192898D01*
X982137D01*
Y192198D01*
X981937D01*
G37*
G36*
G01Y193898D02*
X981537Y194037D01*
Y194458D01*
X981937Y194598D01*
X982137D01*
Y193898D01*
X981937D01*
G37*
G36*
G01X982337Y188648D02*
X982737Y188508D01*
Y188087D01*
X982337Y187948D01*
X982137D01*
Y188648D01*
X982337D01*
G37*
G36*
G01X981324Y186940D02*
X981140Y187322D01*
X981437Y187619D01*
X981819Y187435D01*
X981961Y187294D01*
X981466Y186799D01*
X981324Y186940D01*
G37*
G36*
G01X980122Y185738D02*
X979938Y186120D01*
X980235Y186417D01*
X980617Y186233D01*
X980759Y186092D01*
X980264Y185597D01*
X980122Y185738D01*
G37*
G36*
G01X975491Y180541D02*
X975674Y180159D01*
X975377Y179862D01*
X974996Y180046D01*
X974854Y180187D01*
X975349Y180682D01*
X975491Y180541D01*
G37*
G36*
G01X976693Y181743D02*
X976877Y181361D01*
X976580Y181064D01*
X976198Y181248D01*
X976056Y181389D01*
X976551Y181884D01*
X976693Y181743D01*
G37*
G36*
G01X977895Y182945D02*
X978079Y182563D01*
X977782Y182266D01*
X977400Y182450D01*
X977258Y182591D01*
X977753Y183086D01*
X977895Y182945D01*
G37*
G36*
G01X979097Y184147D02*
X979281Y183765D01*
X978984Y183468D01*
X978602Y183652D01*
X978460Y183793D01*
X978955Y184288D01*
X979097Y184147D01*
G37*
G36*
G01X974112Y179728D02*
X973928Y180109D01*
X974225Y180406D01*
X974607Y180223D01*
X974748Y180081D01*
X974253Y179586D01*
X974112Y179728D01*
G37*
G36*
G01X975314Y180930D02*
X975130Y181311D01*
X975427Y181608D01*
X975809Y181425D01*
X975950Y181283D01*
X975455Y180788D01*
X975314Y180930D01*
G37*
G36*
G01X976516Y182132D02*
X976332Y182514D01*
X976629Y182811D01*
X977011Y182627D01*
X977152Y182485D01*
X976657Y181990D01*
X976516Y182132D01*
G37*
G36*
G01X977718Y183334D02*
X977534Y183716D01*
X977831Y184013D01*
X978213Y183829D01*
X978354Y183687D01*
X977859Y183192D01*
X977718Y183334D01*
G37*
G36*
G01X974288Y179339D02*
X974472Y178957D01*
X974175Y178660D01*
X973794Y178844D01*
X973652Y178985D01*
X974147Y179480D01*
X974288Y179339D01*
G37*
G36*
G01X971708Y177323D02*
X971524Y177705D01*
X971821Y178002D01*
X972203Y177818D01*
X972344Y177677D01*
X971849Y177182D01*
X971708Y177323D01*
G37*
G36*
G01X972910Y178525D02*
X972726Y178907D01*
X973023Y179204D01*
X973405Y179020D01*
X973546Y178879D01*
X973051Y178384D01*
X972910Y178525D01*
G37*
G36*
G01X973086Y178137D02*
X973270Y177755D01*
X972973Y177458D01*
X972591Y177642D01*
X972450Y177783D01*
X972945Y178278D01*
X973086Y178137D01*
G37*
G36*
G01X1031000Y268300D02*
X1029700Y269600D01*
Y276179D01*
X1028300Y277579D01*
X1016634D01*
X1014756Y279457D01*
Y284456D01*
X1015130Y284830D01*
X1058966D01*
Y284748D01*
X1061970D01*
Y284830D01*
X1063966D01*
Y284748D01*
X1066970D01*
Y284830D01*
X1068966D01*
Y284748D01*
X1071970D01*
Y284800D01*
X1092200D01*
X1093800Y283200D01*
Y280977D01*
X1090723Y277900D01*
X1079700D01*
X1079650Y277850D01*
X1075250D01*
X1074419Y277019D01*
Y274481D01*
X1072900Y272962D01*
X1053258D01*
Y273092D01*
X1050254D01*
Y272962D01*
X1048358D01*
Y273092D01*
X1045908D01*
X1045300Y273700D01*
Y276900D01*
X1044621Y277579D01*
X1038300D01*
X1037400Y276679D01*
Y269100D01*
X1036600Y268300D01*
X1031000D01*
G37*
G36*
G01X1057270Y301902D02*
Y301916D01*
X1059166D01*
Y301902D01*
X1062170D01*
Y301916D01*
X1064066D01*
Y301902D01*
X1067070D01*
Y301916D01*
X1068966D01*
Y301902D01*
X1071898D01*
X1072700Y301100D01*
X1074754D01*
Y301090D01*
X1077758D01*
Y301100D01*
X1079754D01*
Y301090D01*
X1082758D01*
Y301100D01*
X1084754D01*
Y301090D01*
X1087758D01*
Y301100D01*
X1089770D01*
Y300902D01*
X1092772D01*
Y301100D01*
X1094670D01*
Y300902D01*
X1097672D01*
Y301100D01*
X1099570D01*
Y300902D01*
X1102572D01*
Y301000D01*
X1103300D01*
X1105700Y303400D01*
Y313400D01*
X1107200Y314900D01*
X1107854D01*
Y314898D01*
X1110858D01*
Y314900D01*
X1111100D01*
X1112039Y315840D01*
X1112760D01*
X1113700Y314900D01*
Y312000D01*
X1112800Y311100D01*
X1108500D01*
X1107925Y310525D01*
Y297875D01*
X1107400Y297350D01*
X1106050D01*
X1105000Y296300D01*
Y296116D01*
X1104998Y296115D01*
Y286699D01*
X1104500Y286200D01*
X1096000D01*
X1094800Y287400D01*
Y294100D01*
X1094041Y294859D01*
X1037149D01*
X1037136Y294846D01*
X1015510D01*
X1014756Y295600D01*
Y301297D01*
X1015362Y301902D01*
X1018070D01*
Y301941D01*
X1019966D01*
Y301902D01*
X1022970D01*
Y301941D01*
X1024866D01*
Y301902D01*
X1027870D01*
Y301941D01*
X1029766D01*
Y301902D01*
X1032770D01*
Y301941D01*
X1034666D01*
Y301902D01*
X1037670D01*
Y301940D01*
X1039566Y301938D01*
Y301902D01*
X1042570D01*
Y301934D01*
X1044466Y301932D01*
Y301902D01*
X1047470D01*
Y301928D01*
X1049366Y301926D01*
Y301902D01*
X1052370D01*
Y301922D01*
X1054266Y301920D01*
Y301902D01*
X1057270D01*
G37*
G36*
G01X1015800Y311000D02*
X1014600D01*
X1014258Y311342D01*
Y311544D01*
X1014256Y311545D01*
Y312637D01*
X1014258Y312638D01*
Y316858D01*
X1014750Y317350D01*
X1019920D01*
X1019972Y317402D01*
X1022970D01*
Y317412D01*
X1024866D01*
Y317402D01*
X1028098D01*
X1028400Y317100D01*
Y311839D01*
X1028102Y311541D01*
X1016341D01*
X1015800Y311000D01*
G37*
G36*
G01X1070948Y317300D02*
X1070924Y317324D01*
X1029772D01*
Y320728D01*
X1030672Y321628D01*
Y325672D01*
X1031300Y326300D01*
X1033900D01*
X1035000Y327400D01*
Y328900D01*
X1035848Y329748D01*
X1039002D01*
Y330016D01*
X1040898D01*
Y329948D01*
X1043902D01*
Y330016D01*
X1045798D01*
Y329948D01*
X1048802D01*
Y330016D01*
X1050698D01*
Y329948D01*
X1053702D01*
Y329961D01*
X1054200Y330460D01*
X1073304D01*
X1073664Y330100D01*
X1074166D01*
X1074167Y330098D01*
X1077485D01*
X1077486Y330100D01*
X1078944D01*
Y330092D01*
X1079308D01*
X1081600Y327800D01*
X1083578D01*
Y327758D01*
X1085582D01*
Y327800D01*
X1086678D01*
Y327758D01*
X1088682D01*
Y327800D01*
X1090178D01*
Y327658D01*
X1092182D01*
Y327800D01*
X1093998D01*
Y327598D01*
X1096002D01*
Y327800D01*
X1099500D01*
X1102700Y324600D01*
Y317800D01*
X1102200Y317300D01*
X1070948D01*
G37*
G36*
G01X1014756Y319356D02*
Y325841D01*
X1016506Y327591D01*
X1022461D01*
X1026599Y331729D01*
X1033430D01*
Y328390D01*
X1030498D01*
X1030399Y328291D01*
Y327484D01*
X1029478Y326563D01*
Y321931D01*
X1026952Y319406D01*
X1024866D01*
Y319341D01*
X1022970D01*
Y319406D01*
X1019966D01*
Y319341D01*
X1018070D01*
Y319356D01*
X1014756D01*
G37*
G36*
G01X979066Y402601D02*
X978666Y402741D01*
Y403161D01*
X979066Y403301D01*
X979266D01*
Y402601D01*
X979066D01*
G37*
G36*
G01X979466Y402451D02*
X979866Y402311D01*
Y401891D01*
X979466Y401751D01*
X979266D01*
Y402451D01*
X979466D01*
G37*
G36*
G01X979066Y399201D02*
X978666Y399341D01*
Y399761D01*
X979066Y399901D01*
X979266D01*
Y399201D01*
X979066D01*
G37*
G36*
G01Y397501D02*
X978666Y397641D01*
Y398061D01*
X979066Y398201D01*
X979266D01*
Y397501D01*
X979066D01*
G37*
G36*
G01Y400901D02*
X978666Y401041D01*
Y401461D01*
X979066Y401601D01*
X979266D01*
Y400901D01*
X979066D01*
G37*
G36*
G01X979466Y399051D02*
X979866Y398911D01*
Y398491D01*
X979466Y398351D01*
X979266D01*
Y399051D01*
X979466D01*
G37*
G36*
G01Y397351D02*
X979866Y397211D01*
Y396791D01*
X979466Y396651D01*
X979266D01*
Y397351D01*
X979466D01*
G37*
G36*
G01Y400751D02*
X979866Y400611D01*
Y400191D01*
X979466Y400051D01*
X979266D01*
Y400751D01*
X979466D01*
G37*
G36*
G01X979066Y395801D02*
X978666Y395941D01*
Y396361D01*
X979066Y396501D01*
X979266D01*
Y395801D01*
X979066D01*
G37*
G36*
G01X980266Y402601D02*
X979866Y402741D01*
Y403161D01*
X980266Y403301D01*
X980466D01*
Y402601D01*
X980266D01*
G37*
G36*
G01X980666Y402451D02*
X981066Y402311D01*
Y401891D01*
X980666Y401751D01*
X980466D01*
Y402451D01*
X980666D01*
G37*
G36*
G01X980266Y399201D02*
X979866Y399341D01*
Y399761D01*
X980266Y399901D01*
X980466D01*
Y399201D01*
X980266D01*
G37*
G36*
G01Y397501D02*
X979866Y397641D01*
Y398061D01*
X980266Y398201D01*
X980466D01*
Y397501D01*
X980266D01*
G37*
G36*
G01Y400901D02*
X979866Y401041D01*
Y401461D01*
X980266Y401601D01*
X980466D01*
Y400901D01*
X980266D01*
G37*
G36*
G01X980666Y399051D02*
X981066Y398911D01*
Y398491D01*
X980666Y398351D01*
X980466D01*
Y399051D01*
X980666D01*
G37*
G36*
G01Y397351D02*
X981066Y397211D01*
Y396791D01*
X980666Y396651D01*
X980466D01*
Y397351D01*
X980666D01*
G37*
G36*
G01Y400751D02*
X981066Y400611D01*
Y400191D01*
X980666Y400051D01*
X980466D01*
Y400751D01*
X980666D01*
G37*
G36*
G01X980266Y395801D02*
X979866Y395941D01*
Y396361D01*
X980266Y396501D01*
X980466D01*
Y395801D01*
X980266D01*
G37*
G36*
G01X978266Y402451D02*
X978666Y402311D01*
Y401891D01*
X978266Y401751D01*
X978066D01*
Y402451D01*
X978266D01*
G37*
G36*
G01X977866Y402601D02*
X977466Y402741D01*
Y403161D01*
X977866Y403301D01*
X978066D01*
Y402601D01*
X977866D01*
G37*
G36*
G01X978266Y399051D02*
X978666Y398911D01*
Y398491D01*
X978266Y398351D01*
X978066D01*
Y399051D01*
X978266D01*
G37*
G36*
G01Y397351D02*
X978666Y397211D01*
Y396791D01*
X978266Y396651D01*
X978066D01*
Y397351D01*
X978266D01*
G37*
G36*
G01Y400751D02*
X978666Y400611D01*
Y400191D01*
X978266Y400051D01*
X978066D01*
Y400751D01*
X978266D01*
G37*
G36*
G01X977866Y395801D02*
X977466Y395941D01*
Y396361D01*
X977866Y396501D01*
X978066D01*
Y395801D01*
X977866D01*
G37*
G36*
G01Y399201D02*
X977466Y399341D01*
Y399761D01*
X977866Y399901D01*
X978066D01*
Y399201D01*
X977866D01*
G37*
G36*
G01Y397501D02*
X977466Y397641D01*
Y398061D01*
X977866Y398201D01*
X978066D01*
Y397501D01*
X977866D01*
G37*
G36*
G01Y400901D02*
X977466Y401041D01*
Y401461D01*
X977866Y401601D01*
X978066D01*
Y400901D01*
X977866D01*
G37*
G36*
G01X981466Y402601D02*
X981066Y402741D01*
Y403161D01*
X981466Y403301D01*
X981666D01*
Y402601D01*
X981466D01*
G37*
G36*
G01X981866Y402451D02*
X982266Y402311D01*
Y401891D01*
X981866Y401751D01*
X981666D01*
Y402451D01*
X981866D01*
G37*
G36*
G01X981466Y399201D02*
X981066Y399341D01*
Y399761D01*
X981466Y399901D01*
X981666D01*
Y399201D01*
X981466D01*
G37*
G36*
G01Y397501D02*
X981066Y397641D01*
Y398061D01*
X981466Y398201D01*
X981666D01*
Y397501D01*
X981466D01*
G37*
G36*
G01Y400901D02*
X981066Y401041D01*
Y401461D01*
X981466Y401601D01*
X981666D01*
Y400901D01*
X981466D01*
G37*
G36*
G01X981866Y399051D02*
X982266Y398911D01*
Y398491D01*
X981866Y398351D01*
X981666D01*
Y399051D01*
X981866D01*
G37*
G36*
G01Y397351D02*
X982266Y397211D01*
Y396791D01*
X981866Y396651D01*
X981666D01*
Y397351D01*
X981866D01*
G37*
G36*
G01Y400751D02*
X982266Y400611D01*
Y400191D01*
X981866Y400051D01*
X981666D01*
Y400751D01*
X981866D01*
G37*
G36*
G01X981466Y395801D02*
X981066Y395941D01*
Y396361D01*
X981466Y396501D01*
X981666D01*
Y395801D01*
X981466D01*
G37*
G36*
G01X975866Y402451D02*
X976266Y402311D01*
Y401891D01*
X975866Y401751D01*
X975666D01*
Y402451D01*
X975866D01*
G37*
G36*
G01X975466Y402601D02*
X975066Y402741D01*
Y403161D01*
X975466Y403301D01*
X975666D01*
Y402601D01*
X975466D01*
G37*
G36*
G01X975866Y399051D02*
X976266Y398911D01*
Y398491D01*
X975866Y398351D01*
X975666D01*
Y399051D01*
X975866D01*
G37*
G36*
G01Y397351D02*
X976266Y397211D01*
Y396791D01*
X975866Y396651D01*
X975666D01*
Y397351D01*
X975866D01*
G37*
G36*
G01Y400751D02*
X976266Y400611D01*
Y400191D01*
X975866Y400051D01*
X975666D01*
Y400751D01*
X975866D01*
G37*
G36*
G01X975466Y400901D02*
X975066Y401041D01*
Y401461D01*
X975466Y401601D01*
X975666D01*
Y400901D01*
X975466D01*
G37*
G36*
G01Y397501D02*
X975066Y397641D01*
Y398061D01*
X975466Y398201D01*
X975666D01*
Y397501D01*
X975466D01*
G37*
G36*
G01X976666Y402601D02*
X976266Y402741D01*
Y403161D01*
X976666Y403301D01*
X976866D01*
Y402601D01*
X976666D01*
G37*
G36*
G01X977066Y402451D02*
X977466Y402311D01*
Y401891D01*
X977066Y401751D01*
X976866D01*
Y402451D01*
X977066D01*
G37*
G36*
G01X976666Y397501D02*
X976266Y397641D01*
Y398061D01*
X976666Y398201D01*
X976866D01*
Y397501D01*
X976666D01*
G37*
G36*
G01Y399201D02*
X976266Y399341D01*
Y399761D01*
X976666Y399901D01*
X976866D01*
Y399201D01*
X976666D01*
G37*
G36*
G01Y400901D02*
X976266Y401041D01*
Y401461D01*
X976666Y401601D01*
X976866D01*
Y400901D01*
X976666D01*
G37*
G36*
G01X977066Y399051D02*
X977466Y398911D01*
Y398491D01*
X977066Y398351D01*
X976866D01*
Y399051D01*
X977066D01*
G37*
G36*
G01Y397351D02*
X977466Y397211D01*
Y396791D01*
X977066Y396651D01*
X976866D01*
Y397351D01*
X977066D01*
G37*
G36*
G01Y400751D02*
X977466Y400611D01*
Y400191D01*
X977066Y400051D01*
X976866D01*
Y400751D01*
X977066D01*
G37*
G36*
G01X976666Y395801D02*
X976266Y395941D01*
Y396361D01*
X976666Y396501D01*
X976866D01*
Y395801D01*
X976666D01*
G37*
G36*
G01X985066Y402601D02*
X984666Y402741D01*
Y403161D01*
X985066Y403301D01*
X985266D01*
Y402601D01*
X985066D01*
G37*
G36*
G01X985466Y402451D02*
X985866Y402311D01*
Y401891D01*
X985466Y401751D01*
X985266D01*
Y402451D01*
X985466D01*
G37*
G36*
G01X985066Y400901D02*
X984666Y401041D01*
Y401461D01*
X985066Y401601D01*
X985266D01*
Y400901D01*
X985066D01*
G37*
G36*
G01Y399201D02*
X984666Y399341D01*
Y399761D01*
X985066Y399901D01*
X985266D01*
Y399201D01*
X985066D01*
G37*
G36*
G01Y397501D02*
X984666Y397641D01*
Y398061D01*
X985066Y398201D01*
X985266D01*
Y397501D01*
X985066D01*
G37*
G36*
G01X985466Y400751D02*
X985866Y400611D01*
Y400191D01*
X985466Y400051D01*
X985266D01*
Y400751D01*
X985466D01*
G37*
G36*
G01Y399051D02*
X985866Y398911D01*
Y398491D01*
X985466Y398351D01*
X985266D01*
Y399051D01*
X985466D01*
G37*
G36*
G01Y397351D02*
X985866Y397211D01*
Y396791D01*
X985466Y396651D01*
X985266D01*
Y397351D01*
X985466D01*
G37*
G36*
G01X985066Y395801D02*
X984666Y395941D01*
Y396361D01*
X985066Y396501D01*
X985266D01*
Y395801D01*
X985066D01*
G37*
G36*
G01X986266Y402601D02*
X985866Y402741D01*
Y403161D01*
X986266Y403301D01*
X986516D01*
Y402601D01*
X986266D01*
G37*
G36*
G01Y400901D02*
X985866Y401041D01*
Y401461D01*
X986266Y401601D01*
X986516D01*
Y400901D01*
X986266D01*
G37*
G36*
G01Y399201D02*
X985866Y399341D01*
Y399761D01*
X986266Y399901D01*
X986516D01*
Y399201D01*
X986266D01*
G37*
G36*
G01Y397501D02*
X985866Y397641D01*
Y398061D01*
X986266Y398201D01*
X986516D01*
Y397501D01*
X986266D01*
G37*
G36*
G01Y395801D02*
X985866Y395941D01*
Y396361D01*
X986266Y396501D01*
X986516D01*
Y395801D01*
X986266D01*
G37*
G36*
G01X973581Y382712D02*
X972943Y382307D01*
X972190Y382742D01*
X972222Y383497D01*
X972309Y383649D01*
X973669Y382863D01*
X973581Y382712D01*
G37*
G36*
G01X983066Y402451D02*
X983466Y402311D01*
Y401891D01*
X983066Y401751D01*
X982866D01*
Y402451D01*
X983066D01*
G37*
G36*
G01X982666Y402601D02*
X982266Y402741D01*
Y403161D01*
X982666Y403301D01*
X982866D01*
Y402601D01*
X982666D01*
G37*
G36*
G01Y400901D02*
X982266Y401041D01*
Y401461D01*
X982666Y401601D01*
X982866D01*
Y400901D01*
X982666D01*
G37*
G36*
G01Y399201D02*
X982266Y399341D01*
Y399761D01*
X982666Y399901D01*
X982866D01*
Y399201D01*
X982666D01*
G37*
G36*
G01Y397501D02*
X982266Y397641D01*
Y398061D01*
X982666Y398201D01*
X982866D01*
Y397501D01*
X982666D01*
G37*
G36*
G01X983066Y400751D02*
X983466Y400611D01*
Y400191D01*
X983066Y400051D01*
X982866D01*
Y400751D01*
X983066D01*
G37*
G36*
G01Y399051D02*
X983466Y398911D01*
Y398491D01*
X983066Y398351D01*
X982866D01*
Y399051D01*
X983066D01*
G37*
G36*
G01Y397351D02*
X983466Y397211D01*
Y396791D01*
X983066Y396651D01*
X982866D01*
Y397351D01*
X983066D01*
G37*
G36*
G01X982666Y395801D02*
X982266Y395941D01*
Y396361D01*
X982666Y396501D01*
X982866D01*
Y395801D01*
X982666D01*
G37*
G36*
G01X983866Y402601D02*
X983466Y402741D01*
Y403161D01*
X983866Y403301D01*
X984066D01*
Y402601D01*
X983866D01*
G37*
G36*
G01X984266Y402451D02*
X984666Y402311D01*
Y401891D01*
X984266Y401751D01*
X984066D01*
Y402451D01*
X984266D01*
G37*
G36*
G01X983866Y399201D02*
X983466Y399341D01*
Y399761D01*
X983866Y399901D01*
X984066D01*
Y399201D01*
X983866D01*
G37*
G36*
G01Y397501D02*
X983466Y397641D01*
Y398061D01*
X983866Y398201D01*
X984066D01*
Y397501D01*
X983866D01*
G37*
G36*
G01Y400901D02*
X983466Y401041D01*
Y401461D01*
X983866Y401601D01*
X984066D01*
Y400901D01*
X983866D01*
G37*
G36*
G01X984266Y400751D02*
X984666Y400611D01*
Y400191D01*
X984266Y400051D01*
X984066D01*
Y400751D01*
X984266D01*
G37*
G36*
G01Y399051D02*
X984666Y398911D01*
Y398491D01*
X984266Y398351D01*
X984066D01*
Y399051D01*
X984266D01*
G37*
G36*
G01Y397351D02*
X984666Y397211D01*
Y396791D01*
X984266Y396651D01*
X984066D01*
Y397351D01*
X984266D01*
G37*
G36*
G01X983866Y395801D02*
X983466Y395941D01*
Y396361D01*
X983866Y396501D01*
X984066D01*
Y395801D01*
X983866D01*
G37*
G36*
G01X972137Y415549D02*
X972703Y416044D01*
X972986Y415761D01*
X972491Y415195D01*
X972349Y415054D01*
X971996Y415407D01*
X972137Y415549D01*
G37*
G36*
G01X973127Y413993D02*
X972561Y413498D01*
X972279Y413781D01*
X972774Y414347D01*
X972915Y414488D01*
X973268Y414135D01*
X973127Y413993D01*
G37*
G36*
G01X973976Y413710D02*
X974541Y414205D01*
X974824Y413922D01*
X974329Y413357D01*
X974188Y413215D01*
X973834Y413569D01*
X973976Y413710D01*
G37*
G36*
G01X975814Y411872D02*
X976380Y412367D01*
X976663Y412084D01*
X976168Y411518D01*
X976026Y411377D01*
X975673Y411730D01*
X975814Y411872D01*
G37*
G36*
G01X974966Y412155D02*
X974400Y411660D01*
X974117Y411942D01*
X974612Y412508D01*
X974753Y412650D01*
X975107Y412296D01*
X974966Y412155D01*
G37*
G36*
G01X976356Y409861D02*
X975956Y410001D01*
Y410421D01*
X976356Y410561D01*
X976556D01*
Y409861D01*
X976356D01*
G37*
G36*
G01X977806Y407833D02*
X977424Y407649D01*
X977127Y407946D01*
X977311Y408328D01*
X977452Y408469D01*
X977947Y407974D01*
X977806Y407833D01*
G37*
G36*
G01X976992Y409211D02*
X977374Y409395D01*
X977671Y409098D01*
X977487Y408716D01*
X977346Y408575D01*
X976851Y409070D01*
X976992Y409211D01*
G37*
G36*
G01X978195Y408009D02*
X978576Y408193D01*
X978873Y407896D01*
X978689Y407514D01*
X978548Y407373D01*
X978053Y407868D01*
X978195Y408009D01*
G37*
G36*
G01X979066Y404301D02*
X978666Y404441D01*
Y404861D01*
X979066Y405001D01*
X979266D01*
Y404301D01*
X979066D01*
G37*
G36*
G01X979466Y404151D02*
X979866Y404011D01*
Y403591D01*
X979466Y403451D01*
X979266D01*
Y404151D01*
X979466D01*
G37*
G36*
G01Y405851D02*
X979866Y405711D01*
Y405291D01*
X979466Y405151D01*
X979266D01*
Y405851D01*
X979466D01*
G37*
G36*
G01X972385Y416928D02*
X971819Y416433D01*
X971536Y416715D01*
X972031Y417281D01*
X972172Y417423D01*
X972526Y417069D01*
X972385Y416928D01*
G37*
G36*
G01X973233Y416645D02*
X973799Y417140D01*
X974082Y416857D01*
X973587Y416291D01*
X973445Y416150D01*
X973092Y416503D01*
X973233Y416645D01*
G37*
G36*
G01X976910Y412968D02*
X977476Y413463D01*
X977759Y413180D01*
X977264Y412614D01*
X977122Y412473D01*
X976769Y412826D01*
X976910Y412968D01*
G37*
G36*
G01X975072Y414806D02*
X975637Y415301D01*
X975920Y415018D01*
X975425Y414453D01*
X975284Y414311D01*
X974930Y414665D01*
X975072Y414806D01*
G37*
G36*
G01X976062Y413251D02*
X975496Y412756D01*
X975213Y413038D01*
X975708Y413604D01*
X975849Y413746D01*
X976203Y413392D01*
X976062Y413251D01*
G37*
G36*
G01X974223Y415089D02*
X973657Y414594D01*
X973375Y414877D01*
X973870Y415443D01*
X974011Y415584D01*
X974364Y415231D01*
X974223Y415089D01*
G37*
G36*
G01X977956Y411411D02*
X978356Y411271D01*
Y410851D01*
X977956Y410711D01*
X977756D01*
Y411411D01*
X977956D01*
G37*
G36*
G01X978655Y408682D02*
X978273Y408498D01*
X977976Y408795D01*
X978160Y409177D01*
X978301Y409318D01*
X978796Y408823D01*
X978655Y408682D01*
G37*
G36*
G01X979044Y408858D02*
X979425Y409042D01*
X979722Y408745D01*
X979538Y408363D01*
X979397Y408222D01*
X978902Y408717D01*
X979044Y408858D01*
G37*
G36*
G01X980266Y406001D02*
X979866Y406141D01*
Y406561D01*
X980266Y406701D01*
X980466D01*
Y406001D01*
X980266D01*
G37*
G36*
G01X979857Y407480D02*
X979475Y407296D01*
X979178Y407593D01*
X979362Y407975D01*
X979503Y408116D01*
X979998Y407621D01*
X979857Y407480D01*
G37*
G36*
G01X980266Y404301D02*
X979866Y404441D01*
Y404861D01*
X980266Y405001D01*
X980466D01*
Y404301D01*
X980266D01*
G37*
G36*
G01X980666Y404151D02*
X981066Y404011D01*
Y403591D01*
X980666Y403451D01*
X980466D01*
Y404151D01*
X980666D01*
G37*
G36*
G01Y405851D02*
X981066Y405711D01*
Y405291D01*
X980666Y405151D01*
X980466D01*
Y405851D01*
X980666D01*
G37*
G36*
G01X977556Y409861D02*
X977156Y410001D01*
Y410421D01*
X977556Y410561D01*
X977756D01*
Y409861D01*
X977556D01*
G37*
G36*
G01X980246Y407656D02*
X980627Y407840D01*
X980924Y407543D01*
X980740Y407161D01*
X980599Y407020D01*
X980104Y407515D01*
X980246Y407656D01*
G37*
G36*
G01X972880Y412614D02*
X973445Y413109D01*
X973728Y412826D01*
X973233Y412261D01*
X973092Y412119D01*
X972738Y412473D01*
X972880Y412614D01*
G37*
G36*
G01X974718Y410776D02*
X975284Y411271D01*
X975567Y410988D01*
X975072Y410422D01*
X974930Y410281D01*
X974577Y410634D01*
X974718Y410776D01*
G37*
G36*
G01X973870Y411059D02*
X973304Y410564D01*
X973021Y410846D01*
X973516Y411412D01*
X973657Y411554D01*
X974011Y411200D01*
X973870Y411059D01*
G37*
G36*
G01X976957Y406984D02*
X976575Y406800D01*
X976278Y407097D01*
X976462Y407479D01*
X976603Y407620D01*
X977098Y407125D01*
X976957Y406984D01*
G37*
G36*
G01X976143Y408362D02*
X976525Y408546D01*
X976822Y408249D01*
X976638Y407867D01*
X976497Y407726D01*
X976002Y408221D01*
X976143Y408362D01*
G37*
G36*
G01X977346Y407160D02*
X977727Y407344D01*
X978024Y407047D01*
X977840Y406665D01*
X977699Y406524D01*
X977204Y407019D01*
X977346Y407160D01*
G37*
G36*
G01X975755Y408186D02*
X975373Y408002D01*
X975076Y408299D01*
X975260Y408681D01*
X975401Y408822D01*
X975896Y408327D01*
X975755Y408186D01*
G37*
G36*
G01X975556Y409711D02*
X975956Y409571D01*
Y409151D01*
X975556Y409011D01*
X975356D01*
Y409711D01*
X975556D01*
G37*
G36*
G01X977866Y404301D02*
X977466Y404441D01*
Y404861D01*
X977866Y405001D01*
X978066D01*
Y404301D01*
X977866D01*
G37*
G36*
G01X978266Y404151D02*
X978666Y404011D01*
Y403591D01*
X978266Y403451D01*
X978066D01*
Y404151D01*
X978266D01*
G37*
G36*
G01Y405851D02*
X978666Y405711D01*
Y405291D01*
X978266Y405151D01*
X978066D01*
Y405851D01*
X978266D01*
G37*
G36*
G01X974329Y417741D02*
X974895Y418236D01*
X975178Y417953D01*
X974683Y417387D01*
X974541Y417246D01*
X974188Y417599D01*
X974329Y417741D01*
G37*
G36*
G01X972491Y419579D02*
X973056Y420074D01*
X973339Y419791D01*
X972844Y419226D01*
X972703Y419084D01*
X972349Y419438D01*
X972491Y419579D01*
G37*
G36*
G01X973481Y418024D02*
X972915Y417529D01*
X972632Y417811D01*
X973127Y418377D01*
X973268Y418519D01*
X973622Y418165D01*
X973481Y418024D01*
G37*
G36*
G01X976168Y415902D02*
X976733Y416397D01*
X977016Y416114D01*
X976521Y415549D01*
X976380Y415407D01*
X976026Y415761D01*
X976168Y415902D01*
G37*
G36*
G01X975319Y416185D02*
X974753Y415690D01*
X974471Y415973D01*
X974966Y416539D01*
X975107Y416680D01*
X975460Y416327D01*
X975319Y416185D01*
G37*
G36*
G01X978006Y414064D02*
X978572Y414559D01*
X978855Y414276D01*
X978360Y413710D01*
X978218Y413569D01*
X977865Y413922D01*
X978006Y414064D01*
G37*
G36*
G01X977158Y414347D02*
X976592Y413852D01*
X976309Y414134D01*
X976804Y414700D01*
X976945Y414842D01*
X977299Y414488D01*
X977158Y414347D01*
G37*
G36*
G01X979156Y411411D02*
X979556Y411271D01*
Y410851D01*
X979156Y410711D01*
X978956D01*
Y411411D01*
X979156D01*
G37*
G36*
G01X978756Y411561D02*
X978356Y411701D01*
Y412121D01*
X978756Y412261D01*
X978956D01*
Y411561D01*
X978756D01*
G37*
G36*
G01X981466Y406001D02*
X981066Y406141D01*
Y406561D01*
X981466Y406701D01*
X981666D01*
Y406001D01*
X981466D01*
G37*
G36*
G01X980706Y408328D02*
X980324Y408145D01*
X980027Y408442D01*
X980211Y408823D01*
X980352Y408965D01*
X980847Y408470D01*
X980706Y408328D01*
G37*
G36*
G01X979893Y409707D02*
X980274Y409891D01*
X980571Y409594D01*
X980387Y409212D01*
X980246Y409071D01*
X979751Y409566D01*
X979893Y409707D01*
G37*
G36*
G01X981095Y408505D02*
X981476Y408689D01*
X981773Y408392D01*
X981589Y408010D01*
X981448Y407869D01*
X980953Y408364D01*
X981095Y408505D01*
G37*
G36*
G01X979504Y409530D02*
X979122Y409347D01*
X978825Y409644D01*
X979009Y410025D01*
X979150Y410167D01*
X979645Y409672D01*
X979504Y409530D01*
G37*
G36*
G01X981866Y407547D02*
X982266Y407407D01*
Y406987D01*
X981866Y406847D01*
X981666D01*
Y407547D01*
X981866D01*
G37*
G36*
G01X981466Y404301D02*
X981066Y404441D01*
Y404861D01*
X981466Y405001D01*
X981666D01*
Y404301D01*
X981466D01*
G37*
G36*
G01X981866Y404151D02*
X982266Y404011D01*
Y403591D01*
X981866Y403451D01*
X981666D01*
Y404151D01*
X981866D01*
G37*
G36*
G01Y405851D02*
X982266Y405711D01*
Y405291D01*
X981866Y405151D01*
X981666D01*
Y405851D01*
X981866D01*
G37*
G36*
G01X973243Y407867D02*
X973625Y408050D01*
X973922Y407753D01*
X973738Y407372D01*
X973597Y407230D01*
X973102Y407725D01*
X973243Y407867D01*
G37*
G36*
G01X972526Y408584D02*
X973092Y409079D01*
X973375Y408796D01*
X972880Y408230D01*
X972738Y408089D01*
X972385Y408442D01*
X972526Y408584D01*
G37*
G36*
G01X974445Y406664D02*
X974827Y406848D01*
X975124Y406551D01*
X974940Y406169D01*
X974799Y406028D01*
X974304Y406523D01*
X974445Y406664D01*
G37*
G36*
G01X974057Y406488D02*
X973675Y406304D01*
X973378Y406601D01*
X973562Y406983D01*
X973703Y407124D01*
X974198Y406629D01*
X974057Y406488D01*
G37*
G36*
G01X975259Y405286D02*
X974877Y405102D01*
X974580Y405399D01*
X974764Y405781D01*
X974905Y405922D01*
X975400Y405427D01*
X975259Y405286D01*
G37*
G36*
G01X975866Y404151D02*
X976266Y404011D01*
Y403591D01*
X975866Y403451D01*
X975666D01*
Y404151D01*
X975866D01*
G37*
G36*
G01X971784Y411518D02*
X972349Y412013D01*
X972632Y411730D01*
X972137Y411165D01*
X971996Y411023D01*
X971642Y411377D01*
X971784Y411518D01*
G37*
G36*
G01X972774Y409963D02*
X972208Y409468D01*
X971925Y409750D01*
X972420Y410316D01*
X972561Y410458D01*
X972915Y410104D01*
X972774Y409963D01*
G37*
G36*
G01X974906Y407337D02*
X974524Y407153D01*
X974227Y407450D01*
X974411Y407832D01*
X974552Y407973D01*
X975047Y407478D01*
X974906Y407337D01*
G37*
G36*
G01X973624Y409678D02*
X974189Y410173D01*
X974472Y409890D01*
X973977Y409325D01*
X973836Y409183D01*
X973482Y409537D01*
X973624Y409678D01*
G37*
G36*
G01X975294Y407513D02*
X975676Y407697D01*
X975973Y407400D01*
X975789Y407018D01*
X975648Y406877D01*
X975153Y407372D01*
X975294Y407513D01*
G37*
G36*
G01X976108Y406135D02*
X975726Y405951D01*
X975429Y406248D01*
X975613Y406630D01*
X975754Y406771D01*
X976249Y406276D01*
X976108Y406135D01*
G37*
G36*
G01X976496Y406311D02*
X976878Y406495D01*
X977175Y406198D01*
X976991Y405816D01*
X976850Y405675D01*
X976355Y406170D01*
X976496Y406311D01*
G37*
G36*
G01X976666Y404301D02*
X976266Y404441D01*
Y404861D01*
X976666Y405001D01*
X976866D01*
Y404301D01*
X976666D01*
G37*
G36*
G01X977066Y404151D02*
X977466Y404011D01*
Y403591D01*
X977066Y403451D01*
X976866D01*
Y404151D01*
X977066D01*
G37*
G36*
G01X981294Y417352D02*
X981860Y417847D01*
X982143Y417564D01*
X981648Y416998D01*
X981506Y416857D01*
X981153Y417210D01*
X981294Y417352D01*
G37*
G36*
G01X980446Y417635D02*
X979880Y417140D01*
X979597Y417422D01*
X980092Y417988D01*
X980233Y418130D01*
X980587Y417776D01*
X980446Y417635D01*
G37*
G36*
G01X982286Y415795D02*
X981720Y415300D01*
X981437Y415582D01*
X981932Y416148D01*
X982073Y416290D01*
X982427Y415936D01*
X982286Y415795D01*
G37*
G36*
G01X979456Y419190D02*
X980021Y419685D01*
X980304Y419402D01*
X979809Y418837D01*
X979668Y418695D01*
X979314Y419049D01*
X979456Y419190D01*
G37*
G36*
G01X977617Y421029D02*
X978183Y421524D01*
X978466Y421241D01*
X977971Y420675D01*
X977829Y420534D01*
X977476Y420887D01*
X977617Y421029D01*
G37*
G36*
G01X978607Y419473D02*
X978041Y418978D01*
X977759Y419261D01*
X978254Y419827D01*
X978395Y419968D01*
X978748Y419615D01*
X978607Y419473D01*
G37*
G36*
G01X982356Y413261D02*
X981956Y413401D01*
Y413821D01*
X982356Y413961D01*
X982556D01*
Y413261D01*
X982356D01*
G37*
G36*
G01X982756Y414811D02*
X983156Y414671D01*
Y414251D01*
X982756Y414111D01*
X982556D01*
Y414811D01*
X982756D01*
G37*
G36*
G01X983253Y410875D02*
X982871Y410692D01*
X982574Y410989D01*
X982758Y411370D01*
X982899Y411512D01*
X983394Y411017D01*
X983253Y410875D01*
G37*
G36*
G01X983642Y411052D02*
X984023Y411236D01*
X984320Y410939D01*
X984137Y410557D01*
X983995Y410416D01*
X983500Y410911D01*
X983642Y411052D01*
G37*
G36*
G01X982756Y413111D02*
X983156Y412971D01*
Y412551D01*
X982756Y412411D01*
X982556D01*
Y413111D01*
X982756D01*
G37*
G36*
G01X985066Y406001D02*
X984666Y406141D01*
Y406561D01*
X985066Y406701D01*
X985266D01*
Y406001D01*
X985066D01*
G37*
G36*
G01Y407701D02*
X984666Y407841D01*
Y408261D01*
X985066Y408401D01*
X985266D01*
Y407701D01*
X985066D01*
G37*
G36*
G01X985466Y407551D02*
X985866Y407411D01*
Y406991D01*
X985466Y406851D01*
X985266D01*
Y407551D01*
X985466D01*
G37*
G36*
G01X984844Y409850D02*
X985225Y410034D01*
X985522Y409737D01*
X985339Y409355D01*
X985197Y409214D01*
X984702Y409709D01*
X984844Y409850D01*
G37*
G36*
G01X984455Y409673D02*
X984073Y409490D01*
X983776Y409787D01*
X983960Y410168D01*
X984101Y410310D01*
X984596Y409815D01*
X984455Y409673D01*
G37*
G36*
G01X985066Y404301D02*
X984666Y404441D01*
Y404861D01*
X985066Y405001D01*
X985266D01*
Y404301D01*
X985066D01*
G37*
G36*
G01X985466Y404151D02*
X985866Y404011D01*
Y403591D01*
X985466Y403451D01*
X985266D01*
Y404151D01*
X985466D01*
G37*
G36*
G01Y405851D02*
X985866Y405711D01*
Y405291D01*
X985466Y405151D01*
X985266D01*
Y405851D01*
X985466D01*
G37*
G36*
G01X972102Y426544D02*
X972667Y427039D01*
X972950Y426756D01*
X972455Y426191D01*
X972314Y426049D01*
X971960Y426403D01*
X972102Y426544D01*
G37*
G36*
G01X973092Y424989D02*
X972526Y424494D01*
X972243Y424776D01*
X972738Y425342D01*
X972880Y425483D01*
X973233Y425130D01*
X973092Y424989D01*
G37*
G36*
G01X973940Y424706D02*
X974506Y425201D01*
X974789Y424918D01*
X974294Y424352D01*
X974152Y424211D01*
X973799Y424564D01*
X973940Y424706D01*
G37*
G36*
G01X974930Y423150D02*
X974364Y422655D01*
X974082Y422938D01*
X974577Y423504D01*
X974718Y423645D01*
X975072Y423291D01*
X974930Y423150D01*
G37*
G36*
G01X976769Y421312D02*
X976203Y420817D01*
X975920Y421099D01*
X976415Y421665D01*
X976556Y421807D01*
X976910Y421453D01*
X976769Y421312D01*
G37*
G36*
G01X975779Y422867D02*
X976344Y423362D01*
X976627Y423079D01*
X976132Y422514D01*
X975991Y422372D01*
X975637Y422726D01*
X975779Y422867D01*
G37*
G36*
G01X983381Y416890D02*
X982816Y416395D01*
X982533Y416678D01*
X983028Y417244D01*
X983204Y417421D01*
X983558Y417067D01*
X983381Y416890D01*
G37*
G36*
G01X981541Y418730D02*
X980976Y418235D01*
X980693Y418518D01*
X981188Y419084D01*
X981364Y419261D01*
X981718Y418907D01*
X981541Y418730D01*
G37*
G36*
G01X979703Y420569D02*
X979137Y420074D01*
X978854Y420357D01*
X979349Y420922D01*
X979526Y421099D01*
X979879Y420746D01*
X979703Y420569D01*
G37*
G36*
G01X985303Y410522D02*
X984922Y410338D01*
X984625Y410635D01*
X984808Y411017D01*
X984985Y411194D01*
X985480Y410699D01*
X985303Y410522D01*
G37*
G36*
G01X983556Y413261D02*
X983156Y413401D01*
Y413821D01*
X983556Y413961D01*
X983806D01*
Y413261D01*
X983556D01*
G37*
G36*
G01Y414961D02*
X983156Y415101D01*
Y415521D01*
X983556Y415661D01*
X983806D01*
Y414961D01*
X983556D01*
G37*
G36*
G01X986266Y406001D02*
X985866Y406141D01*
Y406561D01*
X986266Y406701D01*
X986516D01*
Y406001D01*
X986266D01*
G37*
G36*
G01Y407701D02*
X985866Y407841D01*
Y408261D01*
X986266Y408401D01*
X986516D01*
Y407701D01*
X986266D01*
G37*
G36*
G01Y404301D02*
X985866Y404441D01*
Y404861D01*
X986266Y405001D01*
X986516D01*
Y404301D01*
X986266D01*
G37*
G36*
G01X974187Y426084D02*
X973622Y425589D01*
X973339Y425872D01*
X973834Y426438D01*
X974011Y426614D01*
X974364Y426261D01*
X974187Y426084D01*
G37*
G36*
G01X976026Y424246D02*
X975460Y423751D01*
X975177Y424034D01*
X975672Y424599D01*
X975849Y424776D01*
X976203Y424422D01*
X976026Y424246D01*
G37*
G36*
G01X977864Y422407D02*
X977299Y421912D01*
X977016Y422195D01*
X977511Y422761D01*
X977687Y422938D01*
X978041Y422584D01*
X977864Y422407D01*
G37*
G36*
G01X984101Y411724D02*
X983720Y411540D01*
X983423Y411837D01*
X983606Y412219D01*
X983783Y412396D01*
X984278Y411901D01*
X984101Y411724D01*
G37*
G36*
G01X972420Y405932D02*
X971854Y405437D01*
X971571Y405719D01*
X972066Y406285D01*
X972207Y406427D01*
X972561Y406073D01*
X972420Y405932D01*
G37*
G36*
G01X971748Y422514D02*
X972314Y423009D01*
X972597Y422726D01*
X972102Y422160D01*
X971960Y422019D01*
X971607Y422372D01*
X971748Y422514D01*
G37*
G36*
G01X973587Y420675D02*
X974152Y421170D01*
X974435Y420887D01*
X973940Y420322D01*
X973799Y420180D01*
X973445Y420534D01*
X973587Y420675D01*
G37*
G36*
G01X974577Y419120D02*
X974011Y418625D01*
X973728Y418907D01*
X974223Y419473D01*
X974364Y419615D01*
X974718Y419261D01*
X974577Y419120D01*
G37*
G36*
G01X972738Y420958D02*
X972172Y420463D01*
X971890Y420746D01*
X972385Y421312D01*
X972526Y421453D01*
X972880Y421099D01*
X972738Y420958D01*
G37*
G36*
G01X976415Y417281D02*
X975849Y416786D01*
X975567Y417069D01*
X976062Y417635D01*
X976203Y417776D01*
X976556Y417423D01*
X976415Y417281D01*
G37*
G36*
G01X977264Y416998D02*
X977829Y417493D01*
X978112Y417210D01*
X977617Y416645D01*
X977476Y416503D01*
X977122Y416857D01*
X977264Y416998D01*
G37*
G36*
G01X975425Y418837D02*
X975991Y419332D01*
X976274Y419049D01*
X975779Y418483D01*
X975637Y418342D01*
X975284Y418695D01*
X975425Y418837D01*
G37*
G36*
G01X978254Y415443D02*
X977688Y414948D01*
X977405Y415230D01*
X977900Y415796D01*
X978041Y415938D01*
X978395Y415584D01*
X978254Y415443D01*
G37*
G36*
G01X979102Y415160D02*
X979668Y415655D01*
X979951Y415372D01*
X979456Y414806D01*
X979314Y414665D01*
X978961Y415018D01*
X979102Y415160D01*
G37*
G36*
G01X980742Y410556D02*
X981123Y410740D01*
X981420Y410443D01*
X981236Y410061D01*
X981095Y409920D01*
X980600Y410415D01*
X980742Y410556D01*
G37*
G36*
G01X979956Y411561D02*
X979556Y411701D01*
Y412121D01*
X979956Y412261D01*
X980156D01*
Y411561D01*
X979956D01*
G37*
G36*
G01X980356Y413111D02*
X980756Y412971D01*
Y412551D01*
X980356Y412411D01*
X980156D01*
Y413111D01*
X980356D01*
G37*
G36*
G01X983066Y407551D02*
X983466Y407411D01*
Y406991D01*
X983066Y406851D01*
X982866D01*
Y407551D01*
X983066D01*
G37*
G36*
G01X981555Y409177D02*
X981173Y408994D01*
X980876Y409291D01*
X981060Y409672D01*
X981201Y409814D01*
X981696Y409319D01*
X981555Y409177D01*
G37*
G36*
G01X981944Y409354D02*
X982325Y409538D01*
X982622Y409241D01*
X982439Y408859D01*
X982297Y408718D01*
X981802Y409213D01*
X981944Y409354D01*
G37*
G36*
G01X982666Y406001D02*
X982266Y406141D01*
Y406561D01*
X982666Y406701D01*
X982866D01*
Y406001D01*
X982666D01*
G37*
G36*
G01X983066Y404151D02*
X983466Y404011D01*
Y403591D01*
X983066Y403451D01*
X982866D01*
Y404151D01*
X983066D01*
G37*
G36*
G01Y405851D02*
X983466Y405711D01*
Y405291D01*
X983066Y405151D01*
X982866D01*
Y405851D01*
X983066D01*
G37*
G36*
G01X982666Y404301D02*
X982266Y404441D01*
Y404861D01*
X982666Y405001D01*
X982866D01*
Y404301D01*
X982666D01*
G37*
G36*
G01X975673Y420216D02*
X975107Y419721D01*
X974824Y420003D01*
X975319Y420569D01*
X975460Y420711D01*
X975814Y420357D01*
X975673Y420216D01*
G37*
G36*
G01X980198Y416256D02*
X980764Y416751D01*
X981047Y416468D01*
X980552Y415902D01*
X980410Y415761D01*
X980057Y416114D01*
X980198Y416256D01*
G37*
G36*
G01X978360Y418094D02*
X978925Y418589D01*
X979208Y418306D01*
X978713Y417741D01*
X978572Y417599D01*
X978218Y417953D01*
X978360Y418094D01*
G37*
G36*
G01X979350Y416539D02*
X978784Y416044D01*
X978501Y416326D01*
X978996Y416892D01*
X979137Y417034D01*
X979491Y416680D01*
X979350Y416539D01*
G37*
G36*
G01X976521Y419933D02*
X977087Y420428D01*
X977370Y420145D01*
X976875Y419579D01*
X976733Y419438D01*
X976380Y419791D01*
X976521Y419933D01*
G37*
G36*
G01X977511Y418377D02*
X976945Y417882D01*
X976663Y418165D01*
X977158Y418731D01*
X977299Y418872D01*
X977652Y418519D01*
X977511Y418377D01*
G37*
G36*
G01X981556Y414811D02*
X981956Y414671D01*
Y414251D01*
X981556Y414111D01*
X981356D01*
Y414811D01*
X981556D01*
G37*
G36*
G01X981156Y413261D02*
X980756Y413401D01*
Y413821D01*
X981156Y413961D01*
X981356D01*
Y413261D01*
X981156D01*
G37*
G36*
G01X982404Y410026D02*
X982022Y409843D01*
X981725Y410140D01*
X981909Y410521D01*
X982050Y410663D01*
X982545Y410168D01*
X982404Y410026D01*
G37*
G36*
G01X981591Y411405D02*
X981972Y411589D01*
X982269Y411292D01*
X982085Y410910D01*
X981944Y410769D01*
X981449Y411264D01*
X981591Y411405D01*
G37*
G36*
G01X982793Y410203D02*
X983174Y410387D01*
X983471Y410090D01*
X983288Y409708D01*
X983146Y409567D01*
X982651Y410062D01*
X982793Y410203D01*
G37*
G36*
G01X981156Y411561D02*
X980756Y411701D01*
Y412121D01*
X981156Y412261D01*
X981356D01*
Y411561D01*
X981156D01*
G37*
G36*
G01X981556Y413111D02*
X981956Y412971D01*
Y412551D01*
X981556Y412411D01*
X981356D01*
Y413111D01*
X981556D01*
G37*
G36*
G01X983866Y406001D02*
X983466Y406141D01*
Y406561D01*
X983866Y406701D01*
X984066D01*
Y406001D01*
X983866D01*
G37*
G36*
G01X984266Y407551D02*
X984666Y407411D01*
Y406991D01*
X984266Y406851D01*
X984066D01*
Y407551D01*
X984266D01*
G37*
G36*
G01X983866Y407701D02*
X983466Y407841D01*
Y408261D01*
X983866Y408401D01*
X984066D01*
Y407701D01*
X983866D01*
G37*
G36*
G01X983606Y408824D02*
X983224Y408641D01*
X982927Y408938D01*
X983111Y409319D01*
X983252Y409461D01*
X983747Y408966D01*
X983606Y408824D01*
G37*
G36*
G01X983866Y404301D02*
X983466Y404441D01*
Y404861D01*
X983866Y405001D01*
X984066D01*
Y404301D01*
X983866D01*
G37*
G36*
G01X984266Y404151D02*
X984666Y404011D01*
Y403591D01*
X984266Y403451D01*
X984066D01*
Y404151D01*
X984266D01*
G37*
G36*
G01Y405851D02*
X984666Y405711D01*
Y405291D01*
X984266Y405151D01*
X984066D01*
Y405851D01*
X984266D01*
G37*
G36*
G01X972844Y423610D02*
X973410Y424105D01*
X973693Y423822D01*
X973198Y423256D01*
X973056Y423115D01*
X972703Y423468D01*
X972844Y423610D01*
G37*
G36*
G01X974683Y421771D02*
X975248Y422266D01*
X975531Y421983D01*
X975036Y421418D01*
X974895Y421276D01*
X974541Y421630D01*
X974683Y421771D01*
G37*
G36*
G01X973834Y422054D02*
X973268Y421559D01*
X972986Y421842D01*
X973481Y422408D01*
X973622Y422549D01*
X973976Y422195D01*
X973834Y422054D01*
G37*
G36*
G01X1036751Y506612D02*
Y503568D01*
X1035149Y501966D01*
X1029961D01*
X1028779Y503148D01*
Y507408D01*
X1028862Y507491D01*
X1032627D01*
X1033370Y508234D01*
X1035129D01*
X1036751Y506612D01*
G37*
G36*
G01X1025294Y587506D02*
X1025200Y587600D01*
Y592106D01*
X1024729Y592577D01*
X1022794D01*
X1022406Y592965D01*
Y594252D01*
X1023006Y594852D01*
X1027761D01*
X1028898Y593714D01*
Y587606D01*
X1028799Y587506D01*
X1025294D01*
G37*
G36*
G01X1018444Y584900D02*
X1018085Y585259D01*
Y586178D01*
X1017063Y587200D01*
X1014200D01*
X1013600Y587800D01*
Y591500D01*
X1014100Y592000D01*
X1015484D01*
X1016445Y592961D01*
Y594245D01*
X1017000Y594800D01*
X1017700D01*
X1018847Y593653D01*
X1018853Y593580D01*
G03X1018886Y593369I1447J118D01*
G01X1018892Y593346D01*
Y592829D01*
X1019643Y592078D01*
X1021692D01*
X1022098Y591670D01*
Y586972D01*
X1020026Y584900D01*
X1018444D01*
G37*
G36*
G01X1015900Y546200D02*
X1015600Y546500D01*
Y548400D01*
X1014800Y549200D01*
Y553100D01*
X1015600Y553900D01*
X1018684D01*
X1018885Y553698D01*
X1023198D01*
Y548498D01*
X1023700D01*
Y547500D01*
X1022502Y546302D01*
X1020085D01*
X1019984Y546200D01*
X1015900D01*
G37*
G36*
G01X979023Y546815D02*
G02X978654Y547370I0J400D01*
G03X977081Y549288I-1292J544D01*
G02X976602Y549680I-79J392D01*
G01Y550048D01*
X978102D01*
Y553952D01*
X976602D01*
Y554452D01*
X975510D01*
G02X975178Y555075I0J400D01*
G03X975398Y556087I-1163J783D01*
G02X975792Y556553I394J66D01*
G01X978931D01*
G02X979325Y556087I0J-400D01*
G03X982091I1383J-230D01*
G02X982485Y556553I394J66D01*
G01X982732D01*
Y556321D01*
X982722Y556291D01*
G03X984478Y554520I1333J-434D01*
G02X984998Y554139I120J-381D01*
G01Y553402D01*
X984280D01*
X984256Y553408D01*
G03Y550592I-356J-1408D01*
G01X984280Y550598D01*
X984998D01*
Y549548D01*
X986088D01*
G02X986380Y548875I0J-400D01*
G03X986109Y547370I1021J-961D01*
G02X985740Y546815I-369J-155D01*
G01X985715D01*
G02X985346Y547370I0J400D01*
G03X982762I-1292J544D01*
G02X982393Y546815I-369J-155D01*
G01X979023D01*
G37*
G36*
G01X989062D02*
G02X988693Y547370I0J400D01*
G03X988422Y548875I-1292J544D01*
G02X988714Y549548I292J273D01*
G01X989502D01*
Y550048D01*
X991002D01*
Y553952D01*
X989502D01*
Y554266D01*
G02X990089Y554619I400J0D01*
G03X992131Y556087I659J1238D01*
G02X992525Y556553I394J66D01*
G01X992771D01*
Y556321D01*
X992761Y556291D01*
G03X995477Y556087I1333J-434D01*
G02X995871Y556553I394J66D01*
G01X999010D01*
G02X999404Y556087I0J-400D01*
G03X1000673Y554460I1383J-230D01*
G02X1000856Y554260I-17J-199D01*
G01Y553952D01*
X999356D01*
Y550048D01*
X1000856D01*
Y549548D01*
X1002813D01*
G02X1003106Y548876I0J-400D01*
G03X1002843Y547372I1027J-955D01*
G02X1002476Y546815I-368J-157D01*
G01X999098D01*
G02X998731Y547372I1J400D01*
G03X996151I-1290J550D01*
G02X995784Y546815I-368J-157D01*
G01X995751D01*
G02X995384Y547372I1J400D01*
G03X992804I-1290J550D01*
G02X992437Y546815I-368J-157D01*
G01X989062D01*
G37*
G36*
G01X1005790D02*
G02X1005423Y547372I1J400D01*
G03X1004771Y549170I-1290J549D01*
G01X1004662Y549226D01*
Y549548D01*
X1005111D01*
X1005450Y549210D01*
X1006502D01*
X1006541Y549191D01*
G03X1007753I606J1320D01*
G01X1007792Y549210D01*
X1009300D01*
Y547815D01*
X1008300Y546815D01*
X1005790D01*
G37*
G36*
G01X1008160Y554152D02*
G03X1006541Y554431I-1013J-1041D01*
G01X1006502Y554412D01*
X1005360D01*
Y554452D01*
X1005189D01*
X1005057Y554802D01*
G03X1005517Y556087I-923J1055D01*
G02X1005911Y556553I394J66D01*
G01X1008700D01*
X1009300Y555953D01*
Y554152D01*
X1008160D01*
G37*
G36*
G01X985218Y555075D02*
G03X985438Y556087I-1163J783D01*
G02X985832Y556553I394J66D01*
G01X988971D01*
G02X989365Y556087I0J-400D01*
G03X989585Y555075I1383J-229D01*
G02X989253Y554452I-332J-223D01*
G01X985550D01*
G02X985218Y555075I0J400D01*
G37*
G36*
G01X1005423Y585172D02*
G03X1005372Y586378I-1290J550D01*
G02X1005726Y586964I354J186D01*
G01X1006026D01*
X1006050Y586958D01*
G03X1006980Y587032I356J1408D01*
G01X1007018Y587048D01*
X1008400D01*
Y585215D01*
X1007800Y584615D01*
X1005790D01*
G02X1005423Y585172I1J400D01*
G37*
G36*
G01X979023Y584615D02*
G02X978654Y585170I0J400D01*
G03X977004Y587069I-1292J544D01*
G02X976502Y587456I-102J387D01*
G01Y587848D01*
X978002D01*
Y591752D01*
X976502D01*
Y592252D01*
X975510D01*
G02X975178Y592875I0J400D01*
G03X975398Y593887I-1163J783D01*
G02X975792Y594353I394J66D01*
G01X978931D01*
G02X979325Y593887I0J-400D01*
G03X982091I1383J-230D01*
G02X982485Y594353I394J66D01*
G01X982732D01*
Y594121D01*
X982722Y594091D01*
G03X984478Y592320I1333J-434D01*
G02X984998Y591939I120J-381D01*
G01Y591102D01*
X984545D01*
X984506Y591120D01*
G03Y588480I-606J-1320D01*
G01X984545Y588498D01*
X984998D01*
Y587348D01*
X986088D01*
G02X986380Y586675I0J-400D01*
G03X986109Y585170I1021J-961D01*
G02X985740Y584615I-369J-155D01*
G01X985715D01*
G02X985346Y585170I0J400D01*
G03X982762I-1292J544D01*
G02X982393Y584615I-369J-155D01*
G01X979023D01*
G37*
G36*
G01X989062D02*
G02X988693Y585170I0J400D01*
G03X988422Y586675I-1292J544D01*
G02X988714Y587348I292J273D01*
G01X989502D01*
Y587848D01*
X991002D01*
Y591752D01*
X989502D01*
Y592066D01*
G02X990089Y592419I400J0D01*
G03X992131Y593887I659J1238D01*
G02X992525Y594353I394J66D01*
G01X992771D01*
Y594121D01*
X992761Y594091D01*
G03X995477Y593887I1333J-434D01*
G02X995871Y594353I394J66D01*
G01X997913D01*
X997943Y594323D01*
X999005D01*
G02X999400Y593864I0J-400D01*
G03X1000673Y592260I1387J-207D01*
G02X1000856Y592060I-17J-199D01*
G01Y591752D01*
X999356D01*
Y587848D01*
X1000856D01*
Y587348D01*
X1002813D01*
G02X1003106Y586676I0J-400D01*
G03X1002843Y585172I1027J-955D01*
G02X1002476Y584615I-368J-157D01*
G01X999098D01*
G02X998731Y585172I1J400D01*
G03X996151I-1290J550D01*
G02X995784Y584615I-368J-157D01*
G01X995751D01*
G02X995384Y585172I1J400D01*
G03X992804I-1290J550D01*
G02X992437Y584615I-368J-157D01*
G01X989062D01*
G37*
G36*
G01X1022500Y534500D02*
X1019688Y537312D01*
Y544488D01*
X1020500Y545300D01*
X1025552D01*
G03X1027448I948J1100D01*
G01X1028930D01*
X1030763Y547133D01*
Y554215D01*
X1030278Y554700D01*
X1019300D01*
X1019179Y554821D01*
Y556225D01*
X1019875Y556921D01*
Y582761D01*
X1023562Y586448D01*
X1029431D01*
X1029900Y586917D01*
Y594168D01*
X1028200Y595868D01*
X1022572D01*
X1021339Y594635D01*
Y593224D01*
X1021194Y593079D01*
X1020058D01*
X1019893Y593244D01*
Y620293D01*
X1020400Y620800D01*
X1029900D01*
X1031900Y618800D01*
Y607000D01*
X1034816Y604084D01*
G03X1035700Y603177I2981J2021D01*
G01Y595057D01*
G03X1034196Y592129I2098J-2928D01*
G01Y587229D01*
G03X1035700Y584301I3602J0D01*
G01Y582100D01*
X1035600Y582000D01*
Y576059D01*
G03X1034196Y573205I2197J-2853D01*
G01Y568305D01*
G03X1035600Y565451I3601J-1D01*
G01Y557183D01*
G03X1034196Y554329I2197J-2853D01*
G01Y549429D01*
G03X1035600Y546575I3601J-1D01*
G01Y539900D01*
X1030200Y534500D01*
X1022500D01*
G37*
G36*
G01X985218Y592875D02*
G03X985438Y593887I-1163J783D01*
G02X985832Y594353I394J66D01*
G01X988971D01*
G02X989365Y593887I0J-400D01*
G03X989585Y592875I1383J-229D01*
G02X989253Y592252I-332J-223D01*
G01X985550D01*
G02X985218Y592875I0J400D01*
G37*
G36*
G01X1092500Y-2200D02*
Y-9400D01*
X1091200Y-10700D01*
X1089626D01*
G02X1089241Y-10192I0J400D01*
G03X1086349I-1446J406D01*
G02X1085964Y-10700I-385J-108D01*
G01X1082962D01*
G02X1082571Y-10216I0J400D01*
G03X1079633I-1469J315D01*
G02X1079242Y-10700I-391J-84D01*
G01X1076240D01*
G02X1075855Y-10192I0J400D01*
G03X1073046Y-10416I-1446J406D01*
G01X1073064Y-10456D01*
Y-10700D01*
X1072392D01*
Y-7808D01*
X1072412Y-7767D01*
G03X1069718Y-7778I-1350J659D01*
G01X1069738Y-7820D01*
Y-10700D01*
X1065696D01*
Y-7812D01*
X1065717Y-7770D01*
G03X1063023Y-7774I-1348J662D01*
G01X1063044Y-7816D01*
Y-10700D01*
X1059004D01*
Y-7812D01*
X1059024Y-7770D01*
G03X1056330Y-7774I-1348J662D01*
G01X1056350Y-7816D01*
Y-10700D01*
X1055723D01*
Y-10464D01*
X1055736Y-10430D01*
G03X1052861Y-10216I-1406J529D01*
G02X1052470Y-10700I-391J-84D01*
G01X1049700D01*
X1049125Y-10125D01*
X1049133Y-10032D01*
G03X1047506Y-8405I-1496J131D01*
G01X1047413Y-8413D01*
X1047052Y-8051D01*
Y-7707D01*
X1045800Y-6456D01*
Y-1900D01*
X1046500Y-1200D01*
X1049086D01*
G02X1049485Y-1630I0J-400D01*
G03X1052454Y-1440I1498J-113D01*
G01X1052450Y-1420D01*
Y-1200D01*
X1053004D01*
Y-3830D01*
X1052983Y-3872D01*
G03X1055677I1347J-664D01*
G01X1055656Y-3830D01*
Y-1200D01*
X1059459D01*
Y-4536D01*
G03X1062587I1564J0D01*
G01X1062588D01*
Y-3051D01*
G02X1063278Y-2776I400J0D01*
G03X1065867Y-1630I1091J1033D01*
G02X1066266Y-1200I399J30D01*
G01X1069223D01*
G02X1069620Y-1647I0J-400D01*
G03X1072504I1442J-170D01*
G02X1072901Y-1200I397J47D01*
G01X1075858D01*
G02X1076257Y-1630I0J-400D01*
G03X1079253I1498J-113D01*
G02X1079652Y-1200I399J30D01*
G01X1082551D01*
G02X1082950Y-1630I0J-400D01*
G03X1085919Y-1440I1498J-113D01*
G01X1085915Y-1420D01*
Y-1200D01*
X1086468D01*
Y-3830D01*
X1086448Y-3872D01*
G03X1089142I1347J-664D01*
G01X1089122Y-3830D01*
Y-1200D01*
X1091500D01*
X1092500Y-2200D01*
G37*
G36*
G01X1059460Y36500D02*
Y35957D01*
G03X1062580Y35797I1564J0D01*
G02X1062978Y35799I199J-20D01*
G03X1063034Y35534I1393J156D01*
G01X1063044Y35505D01*
Y35409D01*
X1063111Y35341D01*
X1063126Y35313D01*
G03X1065740Y36257I1245J645D01*
G01X1065736Y36278D01*
Y36500D01*
X1066050D01*
X1066700Y37150D01*
Y41400D01*
X1067350Y42050D01*
X1068050D01*
X1068700Y41400D01*
Y37250D01*
X1069450Y36500D01*
X1075961D01*
G02X1076359Y36068I-1J-400D01*
G03X1076419Y35537I1398J-111D01*
G01X1076428Y35508D01*
Y35410D01*
X1076497Y35341D01*
X1076512Y35313D01*
G03X1079155Y36068I1245J644D01*
G02X1079553Y36500I399J32D01*
G01X1082654D01*
G02X1083052Y36068I-1J-400D01*
G03X1083112Y35537I1398J-111D01*
G01X1083122Y35508D01*
Y35410D01*
X1083190Y35341D01*
X1083205Y35313D01*
G03X1085819Y36257I1245J645D01*
G01X1085815Y36278D01*
Y36500D01*
X1086432D01*
Y36278D01*
X1086428Y36257D01*
G03X1089195Y36068I1369J-300D01*
G02X1089593Y36500I399J32D01*
G01X1091800D01*
X1092800Y35500D01*
Y29200D01*
X1090900Y27300D01*
X1089122D01*
Y27561D01*
X1089131Y27591D01*
G03X1086552Y28666I-1334J430D01*
G01X1086537Y28638D01*
X1086468Y28569D01*
Y28471D01*
X1086459Y28442D01*
G03Y27602I1338J-420D01*
G01X1086468Y27573D01*
Y27300D01*
X1082979D01*
G02X1082584Y27765I0J400D01*
G03X1079620I-1482J242D01*
G02X1079225Y27300I-395J-65D01*
G01X1076286D01*
G02X1075891Y27765I0J400D01*
G03X1072975Y27560I-1482J242D01*
G01X1072984Y27530D01*
Y27300D01*
X1072390D01*
Y27564D01*
X1072399Y27594D01*
G03X1069819Y28666I-1335J427D01*
G01X1069804Y28638D01*
X1069736Y28570D01*
Y28474D01*
X1069727Y28445D01*
G03Y27599I1337J-423D01*
G01X1069736Y27570D01*
Y27300D01*
X1065696D01*
Y27564D01*
X1065706Y27594D01*
G03X1063126Y28666I-1335J427D01*
G01X1063111Y28638D01*
X1063044Y28570D01*
Y28474D01*
X1063034Y28445D01*
G03Y27599I1337J-423D01*
G01X1063044Y27570D01*
Y27300D01*
X1059554D01*
G02X1059159Y27765I0J400D01*
G03X1056243Y27560I-1482J242D01*
G01X1056252Y27530D01*
Y27300D01*
X1055656D01*
Y27564D01*
X1055666Y27594D01*
G03X1053086Y28666I-1335J427D01*
G01X1053071Y28638D01*
X1053004Y28570D01*
Y28474D01*
X1052994Y28445D01*
G03Y27599I1337J-423D01*
G01X1053004Y27570D01*
Y27300D01*
X1049500D01*
X1049109Y27691D01*
X1049123Y27790D01*
G03X1047420Y29493I-1486J217D01*
G01X1047321Y29479D01*
X1046100Y30700D01*
Y35850D01*
X1046650Y36400D01*
Y41600D01*
X1047100Y42050D01*
X1048150D01*
X1048650Y41550D01*
Y37300D01*
X1049450Y36500D01*
X1049620D01*
Y36278D01*
X1049616Y36257D01*
G03X1049648Y35534I1369J-302D01*
G01X1049658Y35505D01*
Y35409D01*
X1049725Y35341D01*
X1049740Y35313D01*
G03X1052354Y36257I1245J645D01*
G01X1052350Y36278D01*
Y36500D01*
X1052966D01*
Y36278D01*
X1052962Y36257D01*
G03X1055729Y36068I1369J-300D01*
G02X1056127Y36500I399J32D01*
G01X1059460D01*
G37*
G36*
G01X1048405Y7295D02*
X1047200Y8500D01*
Y15240D01*
G02X1047608Y15640I400J0D01*
G03X1048783Y17849I29J1402D01*
G01X1048687Y17987D01*
X1049480Y18780D01*
X1053108D01*
G02X1053379Y18086I0J-400D01*
G03X1053168Y16275I952J-1029D01*
G02X1052836Y15652I-332J-223D01*
G01X1052056D01*
Y15152D01*
X1050556D01*
Y11248D01*
X1052056D01*
Y10748D01*
X1053011D01*
G02X1053304Y10076I0J-400D01*
G03X1055358I1027J-954D01*
G02X1055651Y10748I293J272D01*
G01X1056560D01*
Y11948D01*
X1057054D01*
X1057099Y11924D01*
G03Y14476I693J1276D01*
G01X1057054Y14452D01*
X1056560D01*
Y15389D01*
G02X1057119Y15756I400J0D01*
G03X1058616Y18083I558J1286D01*
G02X1058884Y18780I268J297D01*
G01X1063148D01*
G02X1063419Y18086I0J-400D01*
G03X1064315Y15656I952J-1029D01*
G02X1064506Y15456I-9J-200D01*
G01Y15152D01*
X1063006D01*
Y11248D01*
X1064506D01*
Y10723D01*
G02X1064315Y10523I-200J0D01*
G03X1065398Y10076I56J-1401D01*
G02X1065691Y10748I293J272D01*
G01X1069010D01*
Y11948D01*
X1070240D01*
G03Y14452I736J1252D01*
G01X1069010D01*
Y15652D01*
X1065866D01*
G02X1065534Y16275I0J400D01*
G03X1065323Y18086I-1163J782D01*
G02X1065594Y18780I271J294D01*
G01X1069841D01*
G02X1070112Y18086I0J-400D01*
G03X1072016I952J-1029D01*
G02X1072287Y18780I271J294D01*
G01X1073202D01*
G02X1073470Y18083I0J-400D01*
G03X1075348I939J-1041D01*
G02X1075616Y18780I268J297D01*
G01X1079895D01*
G02X1080163Y18083I0J-400D01*
G03X1079931Y16271I939J-1041D01*
G02X1079597Y15652I-334J-219D01*
G01X1077506D01*
Y15152D01*
X1076006D01*
Y11248D01*
X1077506D01*
Y10510D01*
X1077363Y10467D01*
G03X1078784Y10076I394J-1345D01*
G02X1079077Y10748I293J272D01*
G01X1082010D01*
Y11948D01*
X1082378D01*
X1082423Y11924D01*
G03Y14476I693J1276D01*
G01X1082378Y14452D01*
X1082010D01*
Y15973D01*
G03X1082041Y18083I-908J1069D01*
G02X1082309Y18780I268J297D01*
G01X1086569D01*
G02X1086841Y18087I0J-400D01*
G03X1088749I954J-1028D01*
G02X1089021Y18780I272J293D01*
G01X1092220D01*
X1093257Y17743D01*
X1093202Y17618D01*
G03X1093448Y16118I1286J-559D01*
G01X1093500Y16061D01*
Y15652D01*
X1089864D01*
Y15152D01*
X1088364D01*
Y11248D01*
X1089864D01*
Y10748D01*
X1093500D01*
Y10117D01*
G03X1093131Y8770I988J-995D01*
G01X1093160Y8660D01*
X1091795Y7295D01*
X1048405D01*
G37*
G36*
G01X1046050Y67643D02*
Y69969D01*
X1046253Y70172D01*
X1069772D01*
X1071600Y72000D01*
X1092000D01*
X1093000Y73000D01*
Y74500D01*
X1102500D01*
Y70000D01*
X1099000Y66500D01*
X1096500D01*
X1095500Y67500D01*
X1046193D01*
X1046050Y67643D01*
G37*
G36*
G01X1065315Y45886D02*
G03X1065398Y47876I-944J1036D01*
G02X1065691Y48548I293J272D01*
G01X1069010D01*
Y49748D01*
X1070240D01*
G03Y52252I736J1252D01*
G01X1069010D01*
Y53452D01*
X1065866D01*
G02X1065534Y54075I0J400D01*
G03X1065260Y55941I-1163J782D01*
G02X1065514Y56650I254J309D01*
G01X1069921D01*
G02X1070175Y55941I0J-400D01*
G03X1071953I889J-1084D01*
G02X1072207Y56650I254J309D01*
G01X1086650D01*
G02X1086904Y55941I0J-400D01*
G03X1088686I891J-1082D01*
G02X1088940Y56650I254J309D01*
G01X1092250D01*
X1093293Y55607D01*
X1093230Y55478D01*
G03X1093326Y54075I1258J-619D01*
G02X1092994Y53452I-332J-223D01*
G01X1089864D01*
Y52952D01*
X1088364D01*
Y49048D01*
X1089864D01*
Y48548D01*
X1093168D01*
G02X1093461Y47876I0J-400D01*
G03X1093464Y45964I1027J-954D01*
G01X1092690Y45190D01*
X1089011D01*
G02X1088741Y45886I-1J400D01*
G03X1086853I-944J1036D01*
G02X1086583Y45190I-269J-296D01*
G01X1085664D01*
G02X1085394Y45886I-1J400D01*
G03X1083506I-944J1036D01*
G02X1083236Y45190I-269J-296D01*
G01X1078971D01*
G02X1078701Y45886I-1J400D01*
G03X1078784Y47876I-944J1036D01*
G02X1079077Y48548I293J272D01*
G01X1082010D01*
Y49748D01*
X1082378D01*
X1082423Y49724D01*
G03Y52276I693J1276D01*
G01X1082378Y52252D01*
X1082010D01*
Y53773D01*
G03X1079931Y54071I-908J1069D01*
G02X1079597Y53452I-334J-219D01*
G01X1077506D01*
Y52952D01*
X1076006D01*
Y49048D01*
X1077506D01*
Y48310D01*
X1077363Y48267D01*
G03X1076813Y45886I394J-1345D01*
G02X1076543Y45190I-269J-296D01*
G01X1071778D01*
Y45715D01*
G03X1070348Y45716I-714J1207D01*
G01Y45190D01*
X1065585D01*
G02X1065315Y45886I-1J400D01*
G37*
G36*
G01X1048510Y45190D02*
X1047300Y46400D01*
Y47717D01*
X1047552Y47968D01*
Y50851D01*
X1048500Y51800D01*
Y53737D01*
G03X1048911Y55427I-863J1105D01*
G01X1048853Y55553D01*
X1049950Y56650D01*
X1053188D01*
G02X1053442Y55941I0J-400D01*
G03X1053168Y54075I889J-1084D01*
G02X1052836Y53452I-332J-223D01*
G01X1052056D01*
Y52952D01*
X1050556D01*
Y49048D01*
X1052056D01*
Y48548D01*
X1053011D01*
G02X1053304Y47876I0J-400D01*
G03X1053387Y45886I1027J-954D01*
G02X1053117Y45190I-269J-296D01*
G01X1052199D01*
G02X1051929Y45886I-1J400D01*
G03X1050041I-944J1036D01*
G02X1049771Y45190I-269J-296D01*
G01X1048510D01*
G37*
G36*
G01X1055275Y45886D02*
G03X1055358Y47876I-944J1036D01*
G02X1055651Y48548I293J272D01*
G01X1056560D01*
Y49748D01*
X1057054D01*
X1057099Y49724D01*
G03Y52276I693J1276D01*
G01X1057054Y52252D01*
X1056560D01*
Y53189D01*
G02X1057119Y53556I400J0D01*
G03X1056506Y54071I558J1286D01*
G02X1056172Y53452I-334J-219D01*
G01X1055826D01*
G02X1055494Y54075I0J400D01*
G03X1055220Y55941I-1163J782D01*
G02X1055474Y56650I254J309D01*
G01X1059600D01*
X1060000Y57050D01*
Y61150D01*
X1060600Y61750D01*
X1061450D01*
X1062050Y61150D01*
Y57050D01*
X1062450Y56650D01*
X1063228D01*
G02X1063482Y55941I0J-400D01*
G03X1064315Y53456I889J-1084D01*
G02X1064506Y53256I-9J-200D01*
G01Y52952D01*
X1063006D01*
Y49048D01*
X1064506D01*
Y48523D01*
G02X1064315Y48323I-200J0D01*
G03X1063427Y45886I56J-1401D01*
G02X1063157Y45190I-269J-296D01*
G01X1062238D01*
G02X1061968Y45886I-1J400D01*
G03X1060080I-944J1036D01*
G02X1059810Y45190I-269J-296D01*
G01X1055545D01*
G02X1055275Y45886I-1J400D01*
G37*
G36*
G01X1072281Y170722D02*
X1071531Y170772D01*
Y171172D01*
X1072281Y171222D01*
X1072481D01*
Y170722D01*
X1072281D01*
G37*
G36*
G01Y168122D02*
X1071531Y168172D01*
Y168572D01*
X1072281Y168622D01*
X1072481D01*
Y168122D01*
X1072281D01*
G37*
G36*
G01Y165522D02*
X1071531Y165572D01*
Y165972D01*
X1072281Y166022D01*
X1072481D01*
Y165522D01*
X1072281D01*
G37*
G36*
G01X1072681Y172522D02*
X1073431Y172472D01*
Y172072D01*
X1072681Y172022D01*
X1072481D01*
Y172522D01*
X1072681D01*
G37*
G36*
G01Y169922D02*
X1073431Y169872D01*
Y169472D01*
X1072681Y169422D01*
X1072481D01*
Y169922D01*
X1072681D01*
G37*
G36*
G01Y167322D02*
X1073431Y167272D01*
Y166872D01*
X1072681Y166822D01*
X1072481D01*
Y167322D01*
X1072681D01*
G37*
G36*
G01X1072281Y181122D02*
X1071531Y181172D01*
Y181572D01*
X1072281Y181622D01*
X1072481D01*
Y181122D01*
X1072281D01*
G37*
G36*
G01Y183722D02*
X1071531Y183772D01*
Y184172D01*
X1072281Y184222D01*
X1072481D01*
Y183722D01*
X1072281D01*
G37*
G36*
G01Y186322D02*
X1071531Y186372D01*
Y186772D01*
X1072281Y186822D01*
X1072481D01*
Y186322D01*
X1072281D01*
G37*
G36*
G01Y188922D02*
X1071531Y188972D01*
Y189372D01*
X1072281Y189422D01*
X1072481D01*
Y188922D01*
X1072281D01*
G37*
G36*
G01Y191522D02*
X1071531Y191572D01*
Y191972D01*
X1072281Y192022D01*
X1072481D01*
Y191522D01*
X1072281D01*
G37*
G36*
G01Y194122D02*
X1071531Y194172D01*
Y194572D01*
X1072281Y194622D01*
X1072481D01*
Y194122D01*
X1072281D01*
G37*
G36*
G01Y178522D02*
X1071531Y178572D01*
Y178972D01*
X1072281Y179022D01*
X1072481D01*
Y178522D01*
X1072281D01*
G37*
G36*
G01Y175922D02*
X1071531Y175972D01*
Y176372D01*
X1072281Y176422D01*
X1072481D01*
Y175922D01*
X1072281D01*
G37*
G36*
G01Y173322D02*
X1071531Y173372D01*
Y173772D01*
X1072281Y173822D01*
X1072481D01*
Y173322D01*
X1072281D01*
G37*
G36*
G01X1072681Y182922D02*
X1073431Y182872D01*
Y182472D01*
X1072681Y182422D01*
X1072481D01*
Y182922D01*
X1072681D01*
G37*
G36*
G01Y185522D02*
X1073431Y185472D01*
Y185072D01*
X1072681Y185022D01*
X1072481D01*
Y185522D01*
X1072681D01*
G37*
G36*
G01Y188122D02*
X1073431Y188072D01*
Y187672D01*
X1072681Y187622D01*
X1072481D01*
Y188122D01*
X1072681D01*
G37*
G36*
G01Y190722D02*
X1073431Y190672D01*
Y190272D01*
X1072681Y190222D01*
X1072481D01*
Y190722D01*
X1072681D01*
G37*
G36*
G01Y193322D02*
X1073431Y193272D01*
Y192872D01*
X1072681Y192822D01*
X1072481D01*
Y193322D01*
X1072681D01*
G37*
G36*
G01Y180322D02*
X1073431Y180272D01*
Y179872D01*
X1072681Y179822D01*
X1072481D01*
Y180322D01*
X1072681D01*
G37*
G36*
G01Y177722D02*
X1073431Y177672D01*
Y177272D01*
X1072681Y177222D01*
X1072481D01*
Y177722D01*
X1072681D01*
G37*
G36*
G01Y175122D02*
X1073431Y175072D01*
Y174672D01*
X1072681Y174622D01*
X1072481D01*
Y175122D01*
X1072681D01*
G37*
G36*
G01X1073831Y170722D02*
X1073081Y170772D01*
Y171172D01*
X1073831Y171222D01*
X1074031D01*
Y170722D01*
X1073831D01*
G37*
G36*
G01Y168122D02*
X1073081Y168172D01*
Y168572D01*
X1073831Y168622D01*
X1074031D01*
Y168122D01*
X1073831D01*
G37*
G36*
G01Y165522D02*
X1073081Y165572D01*
Y165972D01*
X1073831Y166022D01*
X1074031D01*
Y165522D01*
X1073831D01*
G37*
G36*
G01X1074231Y172522D02*
X1074981Y172472D01*
Y172072D01*
X1074231Y172022D01*
X1074031D01*
Y172522D01*
X1074231D01*
G37*
G36*
G01Y169922D02*
X1074981Y169872D01*
Y169472D01*
X1074231Y169422D01*
X1074031D01*
Y169922D01*
X1074231D01*
G37*
G36*
G01Y167322D02*
X1074981Y167272D01*
Y166872D01*
X1074231Y166822D01*
X1074031D01*
Y167322D01*
X1074231D01*
G37*
G36*
G01X1073831Y175922D02*
X1073081Y175972D01*
Y176372D01*
X1073831Y176422D01*
X1074031D01*
Y175922D01*
X1073831D01*
G37*
G36*
G01Y173322D02*
X1073081Y173372D01*
Y173772D01*
X1073831Y173822D01*
X1074031D01*
Y173322D01*
X1073831D01*
G37*
G36*
G01Y178522D02*
X1073081Y178572D01*
Y178972D01*
X1073831Y179022D01*
X1074031D01*
Y178522D01*
X1073831D01*
G37*
G36*
G01Y181122D02*
X1073081Y181172D01*
Y181572D01*
X1073831Y181622D01*
X1074031D01*
Y181122D01*
X1073831D01*
G37*
G36*
G01Y183722D02*
X1073081Y183772D01*
Y184172D01*
X1073831Y184222D01*
X1074031D01*
Y183722D01*
X1073831D01*
G37*
G36*
G01Y186322D02*
X1073081Y186372D01*
Y186772D01*
X1073831Y186822D01*
X1074031D01*
Y186322D01*
X1073831D01*
G37*
G36*
G01Y188922D02*
X1073081Y188972D01*
Y189372D01*
X1073831Y189422D01*
X1074031D01*
Y188922D01*
X1073831D01*
G37*
G36*
G01Y191522D02*
X1073081Y191572D01*
Y191972D01*
X1073831Y192022D01*
X1074031D01*
Y191522D01*
X1073831D01*
G37*
G36*
G01Y194122D02*
X1073081Y194172D01*
Y194572D01*
X1073831Y194622D01*
X1074031D01*
Y194122D01*
X1073831D01*
G37*
G36*
G01X1074231Y177722D02*
X1074981Y177672D01*
Y177272D01*
X1074231Y177222D01*
X1074031D01*
Y177722D01*
X1074231D01*
G37*
G36*
G01Y175122D02*
X1074981Y175072D01*
Y174672D01*
X1074231Y174622D01*
X1074031D01*
Y175122D01*
X1074231D01*
G37*
G36*
G01Y180322D02*
X1074981Y180272D01*
Y179872D01*
X1074231Y179822D01*
X1074031D01*
Y180322D01*
X1074231D01*
G37*
G36*
G01Y182922D02*
X1074981Y182872D01*
Y182472D01*
X1074231Y182422D01*
X1074031D01*
Y182922D01*
X1074231D01*
G37*
G36*
G01Y185522D02*
X1074981Y185472D01*
Y185072D01*
X1074231Y185022D01*
X1074031D01*
Y185522D01*
X1074231D01*
G37*
G36*
G01Y188122D02*
X1074981Y188072D01*
Y187672D01*
X1074231Y187622D01*
X1074031D01*
Y188122D01*
X1074231D01*
G37*
G36*
G01Y190722D02*
X1074981Y190672D01*
Y190272D01*
X1074231Y190222D01*
X1074031D01*
Y190722D01*
X1074231D01*
G37*
G36*
G01Y193322D02*
X1074981Y193272D01*
Y192872D01*
X1074231Y192822D01*
X1074031D01*
Y193322D01*
X1074231D01*
G37*
G36*
G01X1084681Y170722D02*
X1083931Y170772D01*
Y171172D01*
X1084681Y171222D01*
X1084881D01*
Y170722D01*
X1084681D01*
G37*
G36*
G01Y168122D02*
X1083931Y168172D01*
Y168572D01*
X1084681Y168622D01*
X1084881D01*
Y168122D01*
X1084681D01*
G37*
G36*
G01Y165522D02*
X1083931Y165572D01*
Y165972D01*
X1084681Y166022D01*
X1084881D01*
Y165522D01*
X1084681D01*
G37*
G36*
G01X1085081Y172522D02*
X1085831Y172472D01*
Y172072D01*
X1085081Y172022D01*
X1084881D01*
Y172522D01*
X1085081D01*
G37*
G36*
G01Y169922D02*
X1085831Y169872D01*
Y169472D01*
X1085081Y169422D01*
X1084881D01*
Y169922D01*
X1085081D01*
G37*
G36*
G01Y167322D02*
X1085831Y167272D01*
Y166872D01*
X1085081Y166822D01*
X1084881D01*
Y167322D01*
X1085081D01*
G37*
G36*
G01X1084681Y175922D02*
X1083931Y175972D01*
Y176372D01*
X1084681Y176422D01*
X1084881D01*
Y175922D01*
X1084681D01*
G37*
G36*
G01Y173322D02*
X1083931Y173372D01*
Y173772D01*
X1084681Y173822D01*
X1084881D01*
Y173322D01*
X1084681D01*
G37*
G36*
G01Y178522D02*
X1083931Y178572D01*
Y178972D01*
X1084681Y179022D01*
X1084881D01*
Y178522D01*
X1084681D01*
G37*
G36*
G01Y181122D02*
X1083931Y181172D01*
Y181572D01*
X1084681Y181622D01*
X1084881D01*
Y181122D01*
X1084681D01*
G37*
G36*
G01Y183722D02*
X1083931Y183772D01*
Y184172D01*
X1084681Y184222D01*
X1084881D01*
Y183722D01*
X1084681D01*
G37*
G36*
G01Y186322D02*
X1083931Y186372D01*
Y186772D01*
X1084681Y186822D01*
X1084881D01*
Y186322D01*
X1084681D01*
G37*
G36*
G01Y188922D02*
X1083931Y188972D01*
Y189372D01*
X1084681Y189422D01*
X1084881D01*
Y188922D01*
X1084681D01*
G37*
G36*
G01Y191522D02*
X1083931Y191572D01*
Y191972D01*
X1084681Y192022D01*
X1084881D01*
Y191522D01*
X1084681D01*
G37*
G36*
G01Y194122D02*
X1083931Y194172D01*
Y194572D01*
X1084681Y194622D01*
X1084881D01*
Y194122D01*
X1084681D01*
G37*
G36*
G01X1085081Y177722D02*
X1085831Y177672D01*
Y177272D01*
X1085081Y177222D01*
X1084881D01*
Y177722D01*
X1085081D01*
G37*
G36*
G01Y175122D02*
X1085831Y175072D01*
Y174672D01*
X1085081Y174622D01*
X1084881D01*
Y175122D01*
X1085081D01*
G37*
G36*
G01Y180322D02*
X1085831Y180272D01*
Y179872D01*
X1085081Y179822D01*
X1084881D01*
Y180322D01*
X1085081D01*
G37*
G36*
G01Y182922D02*
X1085831Y182872D01*
Y182472D01*
X1085081Y182422D01*
X1084881D01*
Y182922D01*
X1085081D01*
G37*
G36*
G01Y185522D02*
X1085831Y185472D01*
Y185072D01*
X1085081Y185022D01*
X1084881D01*
Y185522D01*
X1085081D01*
G37*
G36*
G01Y188122D02*
X1085831Y188072D01*
Y187672D01*
X1085081Y187622D01*
X1084881D01*
Y188122D01*
X1085081D01*
G37*
G36*
G01Y190722D02*
X1085831Y190672D01*
Y190272D01*
X1085081Y190222D01*
X1084881D01*
Y190722D01*
X1085081D01*
G37*
G36*
G01Y193322D02*
X1085831Y193272D01*
Y192872D01*
X1085081Y192822D01*
X1084881D01*
Y193322D01*
X1085081D01*
G37*
G36*
G01X1086631Y172522D02*
X1087381Y172472D01*
Y172072D01*
X1086631Y172022D01*
X1086431D01*
Y172522D01*
X1086631D01*
G37*
G36*
G01Y169922D02*
X1087381Y169872D01*
Y169472D01*
X1086631Y169422D01*
X1086431D01*
Y169922D01*
X1086631D01*
G37*
G36*
G01Y167322D02*
X1087381Y167272D01*
Y166872D01*
X1086631Y166822D01*
X1086431D01*
Y167322D01*
X1086631D01*
G37*
G36*
G01X1086231Y170722D02*
X1085481Y170772D01*
Y171172D01*
X1086231Y171222D01*
X1086431D01*
Y170722D01*
X1086231D01*
G37*
G36*
G01Y168122D02*
X1085481Y168172D01*
Y168572D01*
X1086231Y168622D01*
X1086431D01*
Y168122D01*
X1086231D01*
G37*
G36*
G01Y165522D02*
X1085481Y165572D01*
Y165972D01*
X1086231Y166022D01*
X1086431D01*
Y165522D01*
X1086231D01*
G37*
G36*
G01X1086631Y182922D02*
X1087381Y182872D01*
Y182472D01*
X1086631Y182422D01*
X1086431D01*
Y182922D01*
X1086631D01*
G37*
G36*
G01Y185522D02*
X1087381Y185472D01*
Y185072D01*
X1086631Y185022D01*
X1086431D01*
Y185522D01*
X1086631D01*
G37*
G36*
G01Y188122D02*
X1087381Y188072D01*
Y187672D01*
X1086631Y187622D01*
X1086431D01*
Y188122D01*
X1086631D01*
G37*
G36*
G01Y190722D02*
X1087381Y190672D01*
Y190272D01*
X1086631Y190222D01*
X1086431D01*
Y190722D01*
X1086631D01*
G37*
G36*
G01Y193322D02*
X1087381Y193272D01*
Y192872D01*
X1086631Y192822D01*
X1086431D01*
Y193322D01*
X1086631D01*
G37*
G36*
G01Y180322D02*
X1087381Y180272D01*
Y179872D01*
X1086631Y179822D01*
X1086431D01*
Y180322D01*
X1086631D01*
G37*
G36*
G01Y177722D02*
X1087381Y177672D01*
Y177272D01*
X1086631Y177222D01*
X1086431D01*
Y177722D01*
X1086631D01*
G37*
G36*
G01Y175122D02*
X1087381Y175072D01*
Y174672D01*
X1086631Y174622D01*
X1086431D01*
Y175122D01*
X1086631D01*
G37*
G36*
G01X1086231Y183722D02*
X1085481Y183772D01*
Y184172D01*
X1086231Y184222D01*
X1086431D01*
Y183722D01*
X1086231D01*
G37*
G36*
G01Y186322D02*
X1085481Y186372D01*
Y186772D01*
X1086231Y186822D01*
X1086431D01*
Y186322D01*
X1086231D01*
G37*
G36*
G01Y188922D02*
X1085481Y188972D01*
Y189372D01*
X1086231Y189422D01*
X1086431D01*
Y188922D01*
X1086231D01*
G37*
G36*
G01Y191522D02*
X1085481Y191572D01*
Y191972D01*
X1086231Y192022D01*
X1086431D01*
Y191522D01*
X1086231D01*
G37*
G36*
G01Y194122D02*
X1085481Y194172D01*
Y194572D01*
X1086231Y194622D01*
X1086431D01*
Y194122D01*
X1086231D01*
G37*
G36*
G01Y181122D02*
X1085481Y181172D01*
Y181572D01*
X1086231Y181622D01*
X1086431D01*
Y181122D01*
X1086231D01*
G37*
G36*
G01Y178522D02*
X1085481Y178572D01*
Y178972D01*
X1086231Y179022D01*
X1086431D01*
Y178522D01*
X1086231D01*
G37*
G36*
G01Y175922D02*
X1085481Y175972D01*
Y176372D01*
X1086231Y176422D01*
X1086431D01*
Y175922D01*
X1086231D01*
G37*
G36*
G01Y173322D02*
X1085481Y173372D01*
Y173772D01*
X1086231Y173822D01*
X1086431D01*
Y173322D01*
X1086231D01*
G37*
G36*
G01X1069181Y170722D02*
X1068431Y170772D01*
Y171172D01*
X1069181Y171222D01*
X1069381D01*
Y170722D01*
X1069181D01*
G37*
G36*
G01Y168122D02*
X1068431Y168172D01*
Y168572D01*
X1069181Y168622D01*
X1069381D01*
Y168122D01*
X1069181D01*
G37*
G36*
G01Y165522D02*
X1068431Y165572D01*
Y165972D01*
X1069181Y166022D01*
X1069381D01*
Y165522D01*
X1069181D01*
G37*
G36*
G01X1069581Y172522D02*
X1070331Y172472D01*
Y172072D01*
X1069581Y172022D01*
X1069381D01*
Y172522D01*
X1069581D01*
G37*
G36*
G01Y169922D02*
X1070331Y169872D01*
Y169472D01*
X1069581Y169422D01*
X1069381D01*
Y169922D01*
X1069581D01*
G37*
G36*
G01Y167322D02*
X1070331Y167272D01*
Y166872D01*
X1069581Y166822D01*
X1069381D01*
Y167322D01*
X1069581D01*
G37*
G36*
G01X1069181Y183722D02*
X1068431Y183772D01*
Y184172D01*
X1069181Y184222D01*
X1069381D01*
Y183722D01*
X1069181D01*
G37*
G36*
G01Y186322D02*
X1068431Y186372D01*
Y186772D01*
X1069181Y186822D01*
X1069381D01*
Y186322D01*
X1069181D01*
G37*
G36*
G01Y188922D02*
X1068431Y188972D01*
Y189372D01*
X1069181Y189422D01*
X1069381D01*
Y188922D01*
X1069181D01*
G37*
G36*
G01Y191522D02*
X1068431Y191572D01*
Y191972D01*
X1069181Y192022D01*
X1069381D01*
Y191522D01*
X1069181D01*
G37*
G36*
G01Y194122D02*
X1068431Y194172D01*
Y194572D01*
X1069181Y194622D01*
X1069381D01*
Y194122D01*
X1069181D01*
G37*
G36*
G01Y181122D02*
X1068431Y181172D01*
Y181572D01*
X1069181Y181622D01*
X1069381D01*
Y181122D01*
X1069181D01*
G37*
G36*
G01Y178522D02*
X1068431Y178572D01*
Y178972D01*
X1069181Y179022D01*
X1069381D01*
Y178522D01*
X1069181D01*
G37*
G36*
G01Y175922D02*
X1068431Y175972D01*
Y176372D01*
X1069181Y176422D01*
X1069381D01*
Y175922D01*
X1069181D01*
G37*
G36*
G01Y173322D02*
X1068431Y173372D01*
Y173772D01*
X1069181Y173822D01*
X1069381D01*
Y173322D01*
X1069181D01*
G37*
G36*
G01X1069581Y182922D02*
X1070331Y182872D01*
Y182472D01*
X1069581Y182422D01*
X1069381D01*
Y182922D01*
X1069581D01*
G37*
G36*
G01Y185522D02*
X1070331Y185472D01*
Y185072D01*
X1069581Y185022D01*
X1069381D01*
Y185522D01*
X1069581D01*
G37*
G36*
G01Y188122D02*
X1070331Y188072D01*
Y187672D01*
X1069581Y187622D01*
X1069381D01*
Y188122D01*
X1069581D01*
G37*
G36*
G01Y190722D02*
X1070331Y190672D01*
Y190272D01*
X1069581Y190222D01*
X1069381D01*
Y190722D01*
X1069581D01*
G37*
G36*
G01Y193322D02*
X1070331Y193272D01*
Y192872D01*
X1069581Y192822D01*
X1069381D01*
Y193322D01*
X1069581D01*
G37*
G36*
G01Y180322D02*
X1070331Y180272D01*
Y179872D01*
X1069581Y179822D01*
X1069381D01*
Y180322D01*
X1069581D01*
G37*
G36*
G01Y177722D02*
X1070331Y177672D01*
Y177272D01*
X1069581Y177222D01*
X1069381D01*
Y177722D01*
X1069581D01*
G37*
G36*
G01Y175122D02*
X1070331Y175072D01*
Y174672D01*
X1069581Y174622D01*
X1069381D01*
Y175122D01*
X1069581D01*
G37*
G36*
G01X1070731Y170722D02*
X1069981Y170772D01*
Y171172D01*
X1070731Y171222D01*
X1070931D01*
Y170722D01*
X1070731D01*
G37*
G36*
G01Y168122D02*
X1069981Y168172D01*
Y168572D01*
X1070731Y168622D01*
X1070931D01*
Y168122D01*
X1070731D01*
G37*
G36*
G01Y165522D02*
X1069981Y165572D01*
Y165972D01*
X1070731Y166022D01*
X1070931D01*
Y165522D01*
X1070731D01*
G37*
G36*
G01X1071131Y172522D02*
X1071881Y172472D01*
Y172072D01*
X1071131Y172022D01*
X1070931D01*
Y172522D01*
X1071131D01*
G37*
G36*
G01Y169922D02*
X1071881Y169872D01*
Y169472D01*
X1071131Y169422D01*
X1070931D01*
Y169922D01*
X1071131D01*
G37*
G36*
G01Y167322D02*
X1071881Y167272D01*
Y166872D01*
X1071131Y166822D01*
X1070931D01*
Y167322D01*
X1071131D01*
G37*
G36*
G01X1070731Y175922D02*
X1069981Y175972D01*
Y176372D01*
X1070731Y176422D01*
X1070931D01*
Y175922D01*
X1070731D01*
G37*
G36*
G01Y173322D02*
X1069981Y173372D01*
Y173772D01*
X1070731Y173822D01*
X1070931D01*
Y173322D01*
X1070731D01*
G37*
G36*
G01Y178522D02*
X1069981Y178572D01*
Y178972D01*
X1070731Y179022D01*
X1070931D01*
Y178522D01*
X1070731D01*
G37*
G36*
G01Y181122D02*
X1069981Y181172D01*
Y181572D01*
X1070731Y181622D01*
X1070931D01*
Y181122D01*
X1070731D01*
G37*
G36*
G01Y183722D02*
X1069981Y183772D01*
Y184172D01*
X1070731Y184222D01*
X1070931D01*
Y183722D01*
X1070731D01*
G37*
G36*
G01Y186322D02*
X1069981Y186372D01*
Y186772D01*
X1070731Y186822D01*
X1070931D01*
Y186322D01*
X1070731D01*
G37*
G36*
G01Y188922D02*
X1069981Y188972D01*
Y189372D01*
X1070731Y189422D01*
X1070931D01*
Y188922D01*
X1070731D01*
G37*
G36*
G01Y191522D02*
X1069981Y191572D01*
Y191972D01*
X1070731Y192022D01*
X1070931D01*
Y191522D01*
X1070731D01*
G37*
G36*
G01Y194122D02*
X1069981Y194172D01*
Y194572D01*
X1070731Y194622D01*
X1070931D01*
Y194122D01*
X1070731D01*
G37*
G36*
G01X1071131Y177722D02*
X1071881Y177672D01*
Y177272D01*
X1071131Y177222D01*
X1070931D01*
Y177722D01*
X1071131D01*
G37*
G36*
G01Y175122D02*
X1071881Y175072D01*
Y174672D01*
X1071131Y174622D01*
X1070931D01*
Y175122D01*
X1071131D01*
G37*
G36*
G01Y180322D02*
X1071881Y180272D01*
Y179872D01*
X1071131Y179822D01*
X1070931D01*
Y180322D01*
X1071131D01*
G37*
G36*
G01Y182922D02*
X1071881Y182872D01*
Y182472D01*
X1071131Y182422D01*
X1070931D01*
Y182922D01*
X1071131D01*
G37*
G36*
G01Y185522D02*
X1071881Y185472D01*
Y185072D01*
X1071131Y185022D01*
X1070931D01*
Y185522D01*
X1071131D01*
G37*
G36*
G01Y188122D02*
X1071881Y188072D01*
Y187672D01*
X1071131Y187622D01*
X1070931D01*
Y188122D01*
X1071131D01*
G37*
G36*
G01Y190722D02*
X1071881Y190672D01*
Y190272D01*
X1071131Y190222D01*
X1070931D01*
Y190722D01*
X1071131D01*
G37*
G36*
G01Y193322D02*
X1071881Y193272D01*
Y192872D01*
X1071131Y192822D01*
X1070931D01*
Y193322D01*
X1071131D01*
G37*
G36*
G01X1070204Y205334D02*
X1070874Y204984D01*
Y204114D01*
X1070204Y203764D01*
X1070029D01*
Y205334D01*
X1070204D01*
G37*
G36*
G01X1073018Y208593D02*
X1073026Y207838D01*
X1072260Y207426D01*
X1071635Y207851D01*
X1071552Y208006D01*
X1072935Y208748D01*
X1073018Y208593D01*
G37*
G36*
G01X1081581Y170722D02*
X1080831Y170772D01*
Y171172D01*
X1081581Y171222D01*
X1081781D01*
Y170722D01*
X1081581D01*
G37*
G36*
G01Y168122D02*
X1080831Y168172D01*
Y168572D01*
X1081581Y168622D01*
X1081781D01*
Y168122D01*
X1081581D01*
G37*
G36*
G01Y165522D02*
X1080831Y165572D01*
Y165972D01*
X1081581Y166022D01*
X1081781D01*
Y165522D01*
X1081581D01*
G37*
G36*
G01X1081981Y172522D02*
X1082731Y172472D01*
Y172072D01*
X1081981Y172022D01*
X1081781D01*
Y172522D01*
X1081981D01*
G37*
G36*
G01Y169922D02*
X1082731Y169872D01*
Y169472D01*
X1081981Y169422D01*
X1081781D01*
Y169922D01*
X1081981D01*
G37*
G36*
G01Y167322D02*
X1082731Y167272D01*
Y166872D01*
X1081981Y166822D01*
X1081781D01*
Y167322D01*
X1081981D01*
G37*
G36*
G01X1081581Y181122D02*
X1080831Y181172D01*
Y181572D01*
X1081581Y181622D01*
X1081781D01*
Y181122D01*
X1081581D01*
G37*
G36*
G01Y183722D02*
X1080831Y183772D01*
Y184172D01*
X1081581Y184222D01*
X1081781D01*
Y183722D01*
X1081581D01*
G37*
G36*
G01Y186322D02*
X1080831Y186372D01*
Y186772D01*
X1081581Y186822D01*
X1081781D01*
Y186322D01*
X1081581D01*
G37*
G36*
G01Y188922D02*
X1080831Y188972D01*
Y189372D01*
X1081581Y189422D01*
X1081781D01*
Y188922D01*
X1081581D01*
G37*
G36*
G01Y191522D02*
X1080831Y191572D01*
Y191972D01*
X1081581Y192022D01*
X1081781D01*
Y191522D01*
X1081581D01*
G37*
G36*
G01Y194122D02*
X1080831Y194172D01*
Y194572D01*
X1081581Y194622D01*
X1081781D01*
Y194122D01*
X1081581D01*
G37*
G36*
G01Y178522D02*
X1080831Y178572D01*
Y178972D01*
X1081581Y179022D01*
X1081781D01*
Y178522D01*
X1081581D01*
G37*
G36*
G01Y175922D02*
X1080831Y175972D01*
Y176372D01*
X1081581Y176422D01*
X1081781D01*
Y175922D01*
X1081581D01*
G37*
G36*
G01Y173322D02*
X1080831Y173372D01*
Y173772D01*
X1081581Y173822D01*
X1081781D01*
Y173322D01*
X1081581D01*
G37*
G36*
G01X1081981Y182922D02*
X1082731Y182872D01*
Y182472D01*
X1081981Y182422D01*
X1081781D01*
Y182922D01*
X1081981D01*
G37*
G36*
G01Y185522D02*
X1082731Y185472D01*
Y185072D01*
X1081981Y185022D01*
X1081781D01*
Y185522D01*
X1081981D01*
G37*
G36*
G01Y188122D02*
X1082731Y188072D01*
Y187672D01*
X1081981Y187622D01*
X1081781D01*
Y188122D01*
X1081981D01*
G37*
G36*
G01Y190722D02*
X1082731Y190672D01*
Y190272D01*
X1081981Y190222D01*
X1081781D01*
Y190722D01*
X1081981D01*
G37*
G36*
G01Y193322D02*
X1082731Y193272D01*
Y192872D01*
X1081981Y192822D01*
X1081781D01*
Y193322D01*
X1081981D01*
G37*
G36*
G01Y180322D02*
X1082731Y180272D01*
Y179872D01*
X1081981Y179822D01*
X1081781D01*
Y180322D01*
X1081981D01*
G37*
G36*
G01Y177722D02*
X1082731Y177672D01*
Y177272D01*
X1081981Y177222D01*
X1081781D01*
Y177722D01*
X1081981D01*
G37*
G36*
G01Y175122D02*
X1082731Y175072D01*
Y174672D01*
X1081981Y174622D01*
X1081781D01*
Y175122D01*
X1081981D01*
G37*
G36*
G01X1083131Y170722D02*
X1082381Y170772D01*
Y171172D01*
X1083131Y171222D01*
X1083331D01*
Y170722D01*
X1083131D01*
G37*
G36*
G01Y168122D02*
X1082381Y168172D01*
Y168572D01*
X1083131Y168622D01*
X1083331D01*
Y168122D01*
X1083131D01*
G37*
G36*
G01Y165522D02*
X1082381Y165572D01*
Y165972D01*
X1083131Y166022D01*
X1083331D01*
Y165522D01*
X1083131D01*
G37*
G36*
G01X1083531Y172522D02*
X1084281Y172472D01*
Y172072D01*
X1083531Y172022D01*
X1083331D01*
Y172522D01*
X1083531D01*
G37*
G36*
G01Y169922D02*
X1084281Y169872D01*
Y169472D01*
X1083531Y169422D01*
X1083331D01*
Y169922D01*
X1083531D01*
G37*
G36*
G01Y167322D02*
X1084281Y167272D01*
Y166872D01*
X1083531Y166822D01*
X1083331D01*
Y167322D01*
X1083531D01*
G37*
G36*
G01X1083131Y175922D02*
X1082381Y175972D01*
Y176372D01*
X1083131Y176422D01*
X1083331D01*
Y175922D01*
X1083131D01*
G37*
G36*
G01Y173322D02*
X1082381Y173372D01*
Y173772D01*
X1083131Y173822D01*
X1083331D01*
Y173322D01*
X1083131D01*
G37*
G36*
G01Y178522D02*
X1082381Y178572D01*
Y178972D01*
X1083131Y179022D01*
X1083331D01*
Y178522D01*
X1083131D01*
G37*
G36*
G01Y181122D02*
X1082381Y181172D01*
Y181572D01*
X1083131Y181622D01*
X1083331D01*
Y181122D01*
X1083131D01*
G37*
G36*
G01Y183722D02*
X1082381Y183772D01*
Y184172D01*
X1083131Y184222D01*
X1083331D01*
Y183722D01*
X1083131D01*
G37*
G36*
G01Y186322D02*
X1082381Y186372D01*
Y186772D01*
X1083131Y186822D01*
X1083331D01*
Y186322D01*
X1083131D01*
G37*
G36*
G01Y188922D02*
X1082381Y188972D01*
Y189372D01*
X1083131Y189422D01*
X1083331D01*
Y188922D01*
X1083131D01*
G37*
G36*
G01Y191522D02*
X1082381Y191572D01*
Y191972D01*
X1083131Y192022D01*
X1083331D01*
Y191522D01*
X1083131D01*
G37*
G36*
G01Y194122D02*
X1082381Y194172D01*
Y194572D01*
X1083131Y194622D01*
X1083331D01*
Y194122D01*
X1083131D01*
G37*
G36*
G01X1083531Y177722D02*
X1084281Y177672D01*
Y177272D01*
X1083531Y177222D01*
X1083331D01*
Y177722D01*
X1083531D01*
G37*
G36*
G01Y175122D02*
X1084281Y175072D01*
Y174672D01*
X1083531Y174622D01*
X1083331D01*
Y175122D01*
X1083531D01*
G37*
G36*
G01Y180322D02*
X1084281Y180272D01*
Y179872D01*
X1083531Y179822D01*
X1083331D01*
Y180322D01*
X1083531D01*
G37*
G36*
G01Y182922D02*
X1084281Y182872D01*
Y182472D01*
X1083531Y182422D01*
X1083331D01*
Y182922D01*
X1083531D01*
G37*
G36*
G01Y185522D02*
X1084281Y185472D01*
Y185072D01*
X1083531Y185022D01*
X1083331D01*
Y185522D01*
X1083531D01*
G37*
G36*
G01Y188122D02*
X1084281Y188072D01*
Y187672D01*
X1083531Y187622D01*
X1083331D01*
Y188122D01*
X1083531D01*
G37*
G36*
G01Y190722D02*
X1084281Y190672D01*
Y190272D01*
X1083531Y190222D01*
X1083331D01*
Y190722D01*
X1083531D01*
G37*
G36*
G01Y193322D02*
X1084281Y193272D01*
Y192872D01*
X1083531Y192822D01*
X1083331D01*
Y193322D01*
X1083531D01*
G37*
G36*
G01X1076931Y170722D02*
X1076181Y170772D01*
Y171172D01*
X1076931Y171222D01*
X1077131D01*
Y170722D01*
X1076931D01*
G37*
G36*
G01Y168122D02*
X1076181Y168172D01*
Y168572D01*
X1076931Y168622D01*
X1077131D01*
Y168122D01*
X1076931D01*
G37*
G36*
G01Y165522D02*
X1076181Y165572D01*
Y165972D01*
X1076931Y166022D01*
X1077131D01*
Y165522D01*
X1076931D01*
G37*
G36*
G01X1077331Y172522D02*
X1078081Y172472D01*
Y172072D01*
X1077331Y172022D01*
X1077131D01*
Y172522D01*
X1077331D01*
G37*
G36*
G01Y169922D02*
X1078081Y169872D01*
Y169472D01*
X1077331Y169422D01*
X1077131D01*
Y169922D01*
X1077331D01*
G37*
G36*
G01Y167322D02*
X1078081Y167272D01*
Y166872D01*
X1077331Y166822D01*
X1077131D01*
Y167322D01*
X1077331D01*
G37*
G36*
G01X1076931Y175922D02*
X1076181Y175972D01*
Y176372D01*
X1076931Y176422D01*
X1077131D01*
Y175922D01*
X1076931D01*
G37*
G36*
G01Y173322D02*
X1076181Y173372D01*
Y173772D01*
X1076931Y173822D01*
X1077131D01*
Y173322D01*
X1076931D01*
G37*
G36*
G01Y178522D02*
X1076181Y178572D01*
Y178972D01*
X1076931Y179022D01*
X1077131D01*
Y178522D01*
X1076931D01*
G37*
G36*
G01Y181122D02*
X1076181Y181172D01*
Y181572D01*
X1076931Y181622D01*
X1077131D01*
Y181122D01*
X1076931D01*
G37*
G36*
G01Y183722D02*
X1076181Y183772D01*
Y184172D01*
X1076931Y184222D01*
X1077131D01*
Y183722D01*
X1076931D01*
G37*
G36*
G01Y186322D02*
X1076181Y186372D01*
Y186772D01*
X1076931Y186822D01*
X1077131D01*
Y186322D01*
X1076931D01*
G37*
G36*
G01Y188922D02*
X1076181Y188972D01*
Y189372D01*
X1076931Y189422D01*
X1077131D01*
Y188922D01*
X1076931D01*
G37*
G36*
G01Y191522D02*
X1076181Y191572D01*
Y191972D01*
X1076931Y192022D01*
X1077131D01*
Y191522D01*
X1076931D01*
G37*
G36*
G01Y194122D02*
X1076181Y194172D01*
Y194572D01*
X1076931Y194622D01*
X1077131D01*
Y194122D01*
X1076931D01*
G37*
G36*
G01X1077331Y177722D02*
X1078081Y177672D01*
Y177272D01*
X1077331Y177222D01*
X1077131D01*
Y177722D01*
X1077331D01*
G37*
G36*
G01Y175122D02*
X1078081Y175072D01*
Y174672D01*
X1077331Y174622D01*
X1077131D01*
Y175122D01*
X1077331D01*
G37*
G36*
G01Y180322D02*
X1078081Y180272D01*
Y179872D01*
X1077331Y179822D01*
X1077131D01*
Y180322D01*
X1077331D01*
G37*
G36*
G01Y182922D02*
X1078081Y182872D01*
Y182472D01*
X1077331Y182422D01*
X1077131D01*
Y182922D01*
X1077331D01*
G37*
G36*
G01Y185522D02*
X1078081Y185472D01*
Y185072D01*
X1077331Y185022D01*
X1077131D01*
Y185522D01*
X1077331D01*
G37*
G36*
G01Y188122D02*
X1078081Y188072D01*
Y187672D01*
X1077331Y187622D01*
X1077131D01*
Y188122D01*
X1077331D01*
G37*
G36*
G01Y190722D02*
X1078081Y190672D01*
Y190272D01*
X1077331Y190222D01*
X1077131D01*
Y190722D01*
X1077331D01*
G37*
G36*
G01Y193322D02*
X1078081Y193272D01*
Y192872D01*
X1077331Y192822D01*
X1077131D01*
Y193322D01*
X1077331D01*
G37*
G36*
G01X1078481Y170722D02*
X1077731Y170772D01*
Y171172D01*
X1078481Y171222D01*
X1078681D01*
Y170722D01*
X1078481D01*
G37*
G36*
G01Y168122D02*
X1077731Y168172D01*
Y168572D01*
X1078481Y168622D01*
X1078681D01*
Y168122D01*
X1078481D01*
G37*
G36*
G01Y165522D02*
X1077731Y165572D01*
Y165972D01*
X1078481Y166022D01*
X1078681D01*
Y165522D01*
X1078481D01*
G37*
G36*
G01X1078881Y172522D02*
X1079631Y172472D01*
Y172072D01*
X1078881Y172022D01*
X1078681D01*
Y172522D01*
X1078881D01*
G37*
G36*
G01Y167322D02*
X1079631Y167272D01*
Y166872D01*
X1078881Y166822D01*
X1078681D01*
Y167322D01*
X1078881D01*
G37*
G36*
G01X1078481Y181122D02*
X1077731Y181172D01*
Y181572D01*
X1078481Y181622D01*
X1078681D01*
Y181122D01*
X1078481D01*
G37*
G36*
G01Y183722D02*
X1077731Y183772D01*
Y184172D01*
X1078481Y184222D01*
X1078681D01*
Y183722D01*
X1078481D01*
G37*
G36*
G01Y186322D02*
X1077731Y186372D01*
Y186772D01*
X1078481Y186822D01*
X1078681D01*
Y186322D01*
X1078481D01*
G37*
G36*
G01Y188922D02*
X1077731Y188972D01*
Y189372D01*
X1078481Y189422D01*
X1078681D01*
Y188922D01*
X1078481D01*
G37*
G36*
G01Y191522D02*
X1077731Y191572D01*
Y191972D01*
X1078481Y192022D01*
X1078681D01*
Y191522D01*
X1078481D01*
G37*
G36*
G01Y194122D02*
X1077731Y194172D01*
Y194572D01*
X1078481Y194622D01*
X1078681D01*
Y194122D01*
X1078481D01*
G37*
G36*
G01Y178522D02*
X1077731Y178572D01*
Y178972D01*
X1078481Y179022D01*
X1078681D01*
Y178522D01*
X1078481D01*
G37*
G36*
G01Y175922D02*
X1077731Y175972D01*
Y176372D01*
X1078481Y176422D01*
X1078681D01*
Y175922D01*
X1078481D01*
G37*
G36*
G01Y173322D02*
X1077731Y173372D01*
Y173772D01*
X1078481Y173822D01*
X1078681D01*
Y173322D01*
X1078481D01*
G37*
G36*
G01X1078881Y182922D02*
X1079631Y182872D01*
Y182472D01*
X1078881Y182422D01*
X1078681D01*
Y182922D01*
X1078881D01*
G37*
G36*
G01Y185522D02*
X1079631Y185472D01*
Y185072D01*
X1078881Y185022D01*
X1078681D01*
Y185522D01*
X1078881D01*
G37*
G36*
G01Y188122D02*
X1079631Y188072D01*
Y187672D01*
X1078881Y187622D01*
X1078681D01*
Y188122D01*
X1078881D01*
G37*
G36*
G01Y190722D02*
X1079631Y190672D01*
Y190272D01*
X1078881Y190222D01*
X1078681D01*
Y190722D01*
X1078881D01*
G37*
G36*
G01Y193322D02*
X1079631Y193272D01*
Y192872D01*
X1078881Y192822D01*
X1078681D01*
Y193322D01*
X1078881D01*
G37*
G36*
G01Y180322D02*
X1079631Y180272D01*
Y179872D01*
X1078881Y179822D01*
X1078681D01*
Y180322D01*
X1078881D01*
G37*
G36*
G01Y177722D02*
X1079631Y177672D01*
Y177272D01*
X1078881Y177222D01*
X1078681D01*
Y177722D01*
X1078881D01*
G37*
G36*
G01Y175122D02*
X1079631Y175072D01*
Y174672D01*
X1078881Y174622D01*
X1078681D01*
Y175122D01*
X1078881D01*
G37*
G36*
G01Y169922D02*
X1079631Y169872D01*
Y169472D01*
X1078881Y169422D01*
X1078681D01*
Y169922D01*
X1078881D01*
G37*
G36*
G01X1075381Y170722D02*
X1074631Y170772D01*
Y171172D01*
X1075381Y171222D01*
X1075581D01*
Y170722D01*
X1075381D01*
G37*
G36*
G01Y168122D02*
X1074631Y168172D01*
Y168572D01*
X1075381Y168622D01*
X1075581D01*
Y168122D01*
X1075381D01*
G37*
G36*
G01Y165522D02*
X1074631Y165572D01*
Y165972D01*
X1075381Y166022D01*
X1075581D01*
Y165522D01*
X1075381D01*
G37*
G36*
G01X1075781Y172522D02*
X1076531Y172472D01*
Y172072D01*
X1075781Y172022D01*
X1075581D01*
Y172522D01*
X1075781D01*
G37*
G36*
G01Y169922D02*
X1076531Y169872D01*
Y169472D01*
X1075781Y169422D01*
X1075581D01*
Y169922D01*
X1075781D01*
G37*
G36*
G01Y167322D02*
X1076531Y167272D01*
Y166872D01*
X1075781Y166822D01*
X1075581D01*
Y167322D01*
X1075781D01*
G37*
G36*
G01X1075381Y175922D02*
X1074631Y175972D01*
Y176372D01*
X1075381Y176422D01*
X1075581D01*
Y175922D01*
X1075381D01*
G37*
G36*
G01Y173322D02*
X1074631Y173372D01*
Y173772D01*
X1075381Y173822D01*
X1075581D01*
Y173322D01*
X1075381D01*
G37*
G36*
G01Y178522D02*
X1074631Y178572D01*
Y178972D01*
X1075381Y179022D01*
X1075581D01*
Y178522D01*
X1075381D01*
G37*
G36*
G01Y181122D02*
X1074631Y181172D01*
Y181572D01*
X1075381Y181622D01*
X1075581D01*
Y181122D01*
X1075381D01*
G37*
G36*
G01Y183722D02*
X1074631Y183772D01*
Y184172D01*
X1075381Y184222D01*
X1075581D01*
Y183722D01*
X1075381D01*
G37*
G36*
G01Y186322D02*
X1074631Y186372D01*
Y186772D01*
X1075381Y186822D01*
X1075581D01*
Y186322D01*
X1075381D01*
G37*
G36*
G01Y188922D02*
X1074631Y188972D01*
Y189372D01*
X1075381Y189422D01*
X1075581D01*
Y188922D01*
X1075381D01*
G37*
G36*
G01Y191522D02*
X1074631Y191572D01*
Y191972D01*
X1075381Y192022D01*
X1075581D01*
Y191522D01*
X1075381D01*
G37*
G36*
G01Y194122D02*
X1074631Y194172D01*
Y194572D01*
X1075381Y194622D01*
X1075581D01*
Y194122D01*
X1075381D01*
G37*
G36*
G01X1075781Y177722D02*
X1076531Y177672D01*
Y177272D01*
X1075781Y177222D01*
X1075581D01*
Y177722D01*
X1075781D01*
G37*
G36*
G01Y175122D02*
X1076531Y175072D01*
Y174672D01*
X1075781Y174622D01*
X1075581D01*
Y175122D01*
X1075781D01*
G37*
G36*
G01Y180322D02*
X1076531Y180272D01*
Y179872D01*
X1075781Y179822D01*
X1075581D01*
Y180322D01*
X1075781D01*
G37*
G36*
G01Y182922D02*
X1076531Y182872D01*
Y182472D01*
X1075781Y182422D01*
X1075581D01*
Y182922D01*
X1075781D01*
G37*
G36*
G01Y185522D02*
X1076531Y185472D01*
Y185072D01*
X1075781Y185022D01*
X1075581D01*
Y185522D01*
X1075781D01*
G37*
G36*
G01Y188122D02*
X1076531Y188072D01*
Y187672D01*
X1075781Y187622D01*
X1075581D01*
Y188122D01*
X1075781D01*
G37*
G36*
G01Y190722D02*
X1076531Y190672D01*
Y190272D01*
X1075781Y190222D01*
X1075581D01*
Y190722D01*
X1075781D01*
G37*
G36*
G01Y193322D02*
X1076531Y193272D01*
Y192872D01*
X1075781Y192822D01*
X1075581D01*
Y193322D01*
X1075781D01*
G37*
G36*
G01X1080031Y170722D02*
X1079281Y170772D01*
Y171172D01*
X1080031Y171222D01*
X1080231D01*
Y170722D01*
X1080031D01*
G37*
G36*
G01Y168122D02*
X1079281Y168172D01*
Y168572D01*
X1080031Y168622D01*
X1080231D01*
Y168122D01*
X1080031D01*
G37*
G36*
G01Y165522D02*
X1079281Y165572D01*
Y165972D01*
X1080031Y166022D01*
X1080231D01*
Y165522D01*
X1080031D01*
G37*
G36*
G01X1080431Y172522D02*
X1081181Y172472D01*
Y172072D01*
X1080431Y172022D01*
X1080231D01*
Y172522D01*
X1080431D01*
G37*
G36*
G01Y169922D02*
X1081181Y169872D01*
Y169472D01*
X1080431Y169422D01*
X1080231D01*
Y169922D01*
X1080431D01*
G37*
G36*
G01Y167322D02*
X1081181Y167272D01*
Y166872D01*
X1080431Y166822D01*
X1080231D01*
Y167322D01*
X1080431D01*
G37*
G36*
G01X1080031Y181122D02*
X1079281Y181172D01*
Y181572D01*
X1080031Y181622D01*
X1080231D01*
Y181122D01*
X1080031D01*
G37*
G36*
G01Y183722D02*
X1079281Y183772D01*
Y184172D01*
X1080031Y184222D01*
X1080231D01*
Y183722D01*
X1080031D01*
G37*
G36*
G01Y186322D02*
X1079281Y186372D01*
Y186772D01*
X1080031Y186822D01*
X1080231D01*
Y186322D01*
X1080031D01*
G37*
G36*
G01Y188922D02*
X1079281Y188972D01*
Y189372D01*
X1080031Y189422D01*
X1080231D01*
Y188922D01*
X1080031D01*
G37*
G36*
G01Y191522D02*
X1079281Y191572D01*
Y191972D01*
X1080031Y192022D01*
X1080231D01*
Y191522D01*
X1080031D01*
G37*
G36*
G01Y194122D02*
X1079281Y194172D01*
Y194572D01*
X1080031Y194622D01*
X1080231D01*
Y194122D01*
X1080031D01*
G37*
G36*
G01Y178522D02*
X1079281Y178572D01*
Y178972D01*
X1080031Y179022D01*
X1080231D01*
Y178522D01*
X1080031D01*
G37*
G36*
G01Y175922D02*
X1079281Y175972D01*
Y176372D01*
X1080031Y176422D01*
X1080231D01*
Y175922D01*
X1080031D01*
G37*
G36*
G01Y173322D02*
X1079281Y173372D01*
Y173772D01*
X1080031Y173822D01*
X1080231D01*
Y173322D01*
X1080031D01*
G37*
G36*
G01X1080431Y182922D02*
X1081181Y182872D01*
Y182472D01*
X1080431Y182422D01*
X1080231D01*
Y182922D01*
X1080431D01*
G37*
G36*
G01Y185522D02*
X1081181Y185472D01*
Y185072D01*
X1080431Y185022D01*
X1080231D01*
Y185522D01*
X1080431D01*
G37*
G36*
G01Y188122D02*
X1081181Y188072D01*
Y187672D01*
X1080431Y187622D01*
X1080231D01*
Y188122D01*
X1080431D01*
G37*
G36*
G01Y190722D02*
X1081181Y190672D01*
Y190272D01*
X1080431Y190222D01*
X1080231D01*
Y190722D01*
X1080431D01*
G37*
G36*
G01Y193322D02*
X1081181Y193272D01*
Y192872D01*
X1080431Y192822D01*
X1080231D01*
Y193322D01*
X1080431D01*
G37*
G36*
G01Y180322D02*
X1081181Y180272D01*
Y179872D01*
X1080431Y179822D01*
X1080231D01*
Y180322D01*
X1080431D01*
G37*
G36*
G01Y177722D02*
X1081181Y177672D01*
Y177272D01*
X1080431Y177222D01*
X1080231D01*
Y177722D01*
X1080431D01*
G37*
G36*
G01Y175122D02*
X1081181Y175072D01*
Y174672D01*
X1080431Y174622D01*
X1080231D01*
Y175122D01*
X1080431D01*
G37*
G36*
G01X1093206Y194252D02*
X1093956Y194202D01*
Y193802D01*
X1093206Y193752D01*
X1093006D01*
Y194252D01*
X1093206D01*
G37*
G36*
G01Y191652D02*
X1093956Y191602D01*
Y191202D01*
X1093206Y191152D01*
X1093006D01*
Y191652D01*
X1093206D01*
G37*
G36*
G01X1092806Y192452D02*
X1092056Y192502D01*
Y192902D01*
X1092806Y192952D01*
X1093006D01*
Y192452D01*
X1092806D01*
G37*
G36*
G01Y189852D02*
X1092056Y189902D01*
Y190302D01*
X1092806Y190352D01*
X1093006D01*
Y189852D01*
X1092806D01*
G37*
G36*
G01X1093468Y200577D02*
X1092798Y200927D01*
Y201797D01*
X1093468Y202147D01*
X1093643D01*
Y200577D01*
X1093468D01*
G37*
G36*
G01X1094467Y183979D02*
X1095032Y184474D01*
X1095315Y184191D01*
X1094820Y183626D01*
X1094679Y183484D01*
X1094325Y183838D01*
X1094467Y183979D01*
G37*
G36*
G01X1095457Y182424D02*
X1094891Y181929D01*
X1094608Y182212D01*
X1095103Y182777D01*
X1095244Y182919D01*
X1095598Y182565D01*
X1095457Y182424D01*
G37*
G36*
G01X1093618Y184262D02*
X1093052Y183767D01*
X1092770Y184050D01*
X1093264Y184616D01*
X1093406Y184757D01*
X1093759Y184404D01*
X1093618Y184262D01*
G37*
G36*
G01X1093206Y189052D02*
X1093956Y189002D01*
Y188602D01*
X1093206Y188552D01*
X1093006D01*
Y189052D01*
X1093206D01*
G37*
G36*
G01Y186452D02*
X1093956Y186402D01*
Y186002D01*
X1093206Y185952D01*
X1093006D01*
Y186452D01*
X1093206D01*
G37*
G36*
G01X1092806Y187252D02*
X1092056Y187302D01*
Y187702D01*
X1092806Y187752D01*
X1093006D01*
Y187252D01*
X1092806D01*
G37*
G36*
G01X1094756Y191652D02*
X1095506Y191602D01*
Y191202D01*
X1094756Y191152D01*
X1094556D01*
Y191652D01*
X1094756D01*
G37*
G36*
G01Y194252D02*
X1095506Y194202D01*
Y193802D01*
X1094756Y193752D01*
X1094556D01*
Y194252D01*
X1094756D01*
G37*
G36*
G01X1094356Y189852D02*
X1093606Y189902D01*
Y190302D01*
X1094356Y190352D01*
X1094556D01*
Y189852D01*
X1094356D01*
G37*
G36*
G01Y192452D02*
X1093606Y192502D01*
Y192902D01*
X1094356Y192952D01*
X1094556D01*
Y192452D01*
X1094356D01*
G37*
G36*
G01Y195052D02*
X1093606Y195102D01*
Y195502D01*
X1094356Y195552D01*
X1094556D01*
Y195052D01*
X1094356D01*
G37*
G36*
G01X1094568Y202650D02*
X1095238Y202300D01*
Y201430D01*
X1094568Y201080D01*
X1094393D01*
Y202650D01*
X1094568D01*
G37*
G36*
G01X1094756Y189052D02*
X1095506Y189002D01*
Y188602D01*
X1094756Y188552D01*
X1094556D01*
Y189052D01*
X1094756D01*
G37*
G36*
G01X1094356Y187252D02*
X1093606Y187302D01*
Y187702D01*
X1094356Y187752D01*
X1094556D01*
Y187252D01*
X1094356D01*
G37*
G36*
G01X1089706Y192452D02*
X1088956Y192502D01*
Y192902D01*
X1089706Y192952D01*
X1089906D01*
Y192452D01*
X1089706D01*
G37*
G36*
G01Y189852D02*
X1088956Y189902D01*
Y190302D01*
X1089706Y190352D01*
X1089906D01*
Y189852D01*
X1089706D01*
G37*
G36*
G01Y187252D02*
X1088956Y187302D01*
Y187702D01*
X1089706Y187752D01*
X1089906D01*
Y187252D01*
X1089706D01*
G37*
G36*
G01Y184652D02*
X1088956Y184702D01*
Y185102D01*
X1089706Y185152D01*
X1089906D01*
Y184652D01*
X1089706D01*
G37*
G36*
G01X1090106Y191652D02*
X1090856Y191602D01*
Y191202D01*
X1090106Y191152D01*
X1089906D01*
Y191652D01*
X1090106D01*
G37*
G36*
G01Y189052D02*
X1090856Y189002D01*
Y188602D01*
X1090106Y188552D01*
X1089906D01*
Y189052D01*
X1090106D01*
G37*
G36*
G01Y186452D02*
X1090856Y186402D01*
Y186002D01*
X1090106Y185952D01*
X1089906D01*
Y186452D01*
X1090106D01*
G37*
G36*
G01Y194252D02*
X1090856Y194202D01*
Y193802D01*
X1090106Y193752D01*
X1089906D01*
Y194252D01*
X1090106D01*
G37*
G36*
G01X1089706Y195052D02*
X1088956Y195102D01*
Y195502D01*
X1089706Y195552D01*
X1089906D01*
Y195052D01*
X1089706D01*
G37*
G36*
G01X1088831Y199906D02*
X1088161Y200256D01*
Y201126D01*
X1088831Y201476D01*
X1089006D01*
Y199906D01*
X1088831D01*
G37*
G36*
G01X1095102Y178392D02*
X1094536Y177897D01*
X1094253Y178180D01*
X1094748Y178746D01*
X1094890Y178887D01*
X1095243Y178534D01*
X1095102Y178392D01*
G37*
G36*
G01X1093264Y180231D02*
X1092698Y179736D01*
X1092415Y180019D01*
X1092910Y180584D01*
X1093051Y180726D01*
X1093405Y180372D01*
X1093264Y180231D01*
G37*
G36*
G01X1091425Y182069D02*
X1090859Y181574D01*
X1090577Y181857D01*
X1091071Y182423D01*
X1091213Y182564D01*
X1091566Y182211D01*
X1091425Y182069D01*
G37*
G36*
G01X1094112Y179948D02*
X1094678Y180443D01*
X1094961Y180160D01*
X1094466Y179594D01*
X1094324Y179453D01*
X1093971Y179806D01*
X1094112Y179948D01*
G37*
G36*
G01X1092274Y181786D02*
X1092839Y182281D01*
X1093122Y181998D01*
X1092627Y181433D01*
X1092486Y181291D01*
X1092132Y181645D01*
X1092274Y181786D01*
G37*
G36*
G01X1090435Y183625D02*
X1091001Y184120D01*
X1091284Y183837D01*
X1090789Y183271D01*
X1090647Y183130D01*
X1090294Y183483D01*
X1090435Y183625D01*
G37*
G36*
G01X1091656Y191652D02*
X1092406Y191602D01*
Y191202D01*
X1091656Y191152D01*
X1091456D01*
Y191652D01*
X1091656D01*
G37*
G36*
G01X1091256Y189852D02*
X1090506Y189902D01*
Y190302D01*
X1091256Y190352D01*
X1091456D01*
Y189852D01*
X1091256D01*
G37*
G36*
G01Y192452D02*
X1090506Y192502D01*
Y192902D01*
X1091256Y192952D01*
X1091456D01*
Y192452D01*
X1091256D01*
G37*
G36*
G01Y195052D02*
X1090506Y195102D01*
Y195502D01*
X1091256Y195552D01*
X1091456D01*
Y195052D01*
X1091256D01*
G37*
G36*
G01X1091656Y194252D02*
X1092406Y194202D01*
Y193802D01*
X1091656Y193752D01*
X1091456D01*
Y194252D01*
X1091656D01*
G37*
G36*
G01X1090473Y205281D02*
X1091143Y204931D01*
Y204061D01*
X1090473Y203711D01*
X1090298D01*
Y205281D01*
X1090473D01*
G37*
G36*
G01X1093370Y182883D02*
X1093936Y183378D01*
X1094219Y183095D01*
X1093724Y182529D01*
X1093582Y182388D01*
X1093229Y182741D01*
X1093370Y182883D01*
G37*
G36*
G01X1094360Y181327D02*
X1093794Y180832D01*
X1093511Y181115D01*
X1094006Y181681D01*
X1094148Y181822D01*
X1094501Y181469D01*
X1094360Y181327D01*
G37*
G36*
G01X1092522Y183166D02*
X1091956Y182671D01*
X1091673Y182953D01*
X1092168Y183519D01*
X1092309Y183661D01*
X1092663Y183307D01*
X1092522Y183166D01*
G37*
G36*
G01X1091656Y186452D02*
X1092406Y186402D01*
Y186002D01*
X1091656Y185952D01*
X1091456D01*
Y186452D01*
X1091656D01*
G37*
G36*
G01Y189052D02*
X1092406Y189002D01*
Y188602D01*
X1091656Y188552D01*
X1091456D01*
Y189052D01*
X1091656D01*
G37*
G36*
G01X1091256Y187252D02*
X1090506Y187302D01*
Y187702D01*
X1091256Y187752D01*
X1091456D01*
Y187252D01*
X1091256D01*
G37*
G36*
G01X1101490Y273966D02*
G03X1100242Y274751I-1290J-666D01*
G01X1100163Y274754D01*
X1098443Y276474D01*
X1096266D01*
Y276974D01*
X1093262D01*
Y274500D01*
X1092502D01*
Y274502D01*
X1090498D01*
Y274500D01*
X1089002D01*
Y274502D01*
X1086998D01*
Y274500D01*
X1085502D01*
Y274502D01*
X1083498D01*
Y274500D01*
X1081502D01*
Y274502D01*
X1079498D01*
Y274500D01*
X1078002D01*
Y274502D01*
X1076000D01*
Y276500D01*
X1079600D01*
X1079800Y276700D01*
X1090723D01*
X1090921Y276898D01*
X1091138D01*
X1094802Y280562D01*
Y280778D01*
X1095600Y281577D01*
Y283641D01*
X1096100Y284141D01*
X1096404D01*
Y284090D01*
X1099408D01*
Y284141D01*
X1101404D01*
Y284090D01*
X1104408D01*
Y284092D01*
X1106000Y285685D01*
Y295700D01*
X1106500Y296200D01*
X1107998D01*
Y293998D01*
X1108200D01*
Y292502D01*
X1107998D01*
Y290498D01*
X1108200D01*
Y289002D01*
X1107998D01*
Y286998D01*
X1108200D01*
Y285502D01*
X1107998D01*
Y283341D01*
X1105956D01*
X1105458Y282842D01*
X1105354D01*
Y282740D01*
X1105256Y282641D01*
Y280356D01*
X1103719Y278818D01*
X1103674D01*
Y278773D01*
X1103219Y278318D01*
X1102674D01*
Y276316D01*
X1103208D01*
Y274292D01*
X1102881Y273966D01*
X1101490D01*
G37*
G36*
G01X1040450Y263636D02*
X1039864D01*
X1039600Y263900D01*
Y276578D01*
X1044206D01*
X1044298Y276485D01*
Y273285D01*
X1044446Y273138D01*
Y271168D01*
X1044466Y271148D01*
X1045354D01*
Y271090D01*
X1048358D01*
Y271148D01*
X1050254D01*
Y271090D01*
X1053259D01*
X1053548Y270800D01*
X1074609D01*
X1075635Y269774D01*
Y266646D01*
X1077047Y265234D01*
Y264065D01*
X1076628Y263646D01*
X1050454D01*
X1050443Y263636D01*
X1040450D01*
G37*
G36*
G01X1094300Y302906D02*
Y315148D01*
X1097302D01*
Y315341D01*
X1099298D01*
Y315148D01*
X1102258D01*
X1104698Y312708D01*
Y304746D01*
X1102774Y302822D01*
X1102572Y302906D01*
X1099570D01*
Y302804D01*
X1097672D01*
Y302906D01*
X1094300D01*
G37*
G36*
G01X1074582Y331100D02*
X1073341Y332341D01*
X1073316D01*
Y332464D01*
X1070314D01*
Y332341D01*
X1068416D01*
Y332464D01*
X1065414D01*
Y332341D01*
X1063516D01*
Y332464D01*
X1060514D01*
Y332341D01*
X1058616D01*
Y332464D01*
X1055614D01*
Y332341D01*
X1035256D01*
Y336341D01*
X1038347Y339432D01*
X1054165D01*
X1054733Y340000D01*
X1072600D01*
X1073800Y338800D01*
Y334920D01*
X1075010Y333710D01*
X1075268D01*
Y333278D01*
X1077400D01*
Y331430D01*
X1077070Y331100D01*
X1074582D01*
G37*
G36*
G01X1092600Y287000D02*
X1059300D01*
X1058700Y287600D01*
Y292800D01*
X1059700Y293800D01*
X1093300D01*
X1093550Y293550D01*
Y287950D01*
X1092600Y287000D01*
G37*
G36*
G01X1077758Y303000D02*
Y303092D01*
X1074754D01*
Y303046D01*
X1073762Y304038D01*
X1059500D01*
X1059010Y304528D01*
Y315010D01*
X1059142Y315142D01*
X1092358D01*
X1092900Y314600D01*
Y311600D01*
X1093298Y311202D01*
Y303198D01*
X1093100Y303000D01*
X1087758D01*
Y303092D01*
X1084754D01*
Y303000D01*
X1082758D01*
Y303092D01*
X1079754D01*
Y303000D01*
X1077758D01*
G37*
G36*
G01X1088875Y400687D02*
X1088207Y401038D01*
X1088209Y401908D01*
X1088880Y402256D01*
X1089055D01*
X1089051Y400686D01*
X1088875Y400687D01*
G37*
G36*
G01X1090473Y404206D02*
X1091143Y403856D01*
Y402986D01*
X1090473Y402636D01*
X1090298D01*
Y404206D01*
X1090473D01*
G37*
G36*
G01X1077231Y395005D02*
X1076593Y394600D01*
X1075840Y395034D01*
X1075872Y395789D01*
X1075959Y395942D01*
X1077318Y395156D01*
X1077231Y395005D01*
G37*
G36*
G01X1076953Y404158D02*
X1077623Y403808D01*
Y402938D01*
X1076953Y402588D01*
X1076778D01*
Y404158D01*
X1076953D01*
G37*
G36*
G01X1086220Y398713D02*
X1085550Y399063D01*
Y399933D01*
X1086220Y400283D01*
X1086395D01*
Y398713D01*
X1086220D01*
G37*
G36*
G01X1087093Y402257D02*
X1087763Y401907D01*
Y401037D01*
X1087093Y400687D01*
X1086918D01*
Y402257D01*
X1087093D01*
G37*
G36*
G01X1083713Y400281D02*
X1084383Y399931D01*
Y399061D01*
X1083713Y398711D01*
X1083538D01*
Y400281D01*
X1083713D01*
G37*
G36*
G01X1083712Y404208D02*
X1084382Y403858D01*
Y402988D01*
X1083712Y402638D01*
X1083537D01*
Y404208D01*
X1083712D01*
G37*
G36*
G01X1082039Y396815D02*
X1081402Y397222D01*
X1081478Y398088D01*
X1082176Y398378D01*
X1082350Y398363D01*
X1082214Y396800D01*
X1082039Y396815D01*
G37*
G36*
G01X1082089Y400637D02*
X1081419Y400987D01*
Y401857D01*
X1082089Y402207D01*
X1082264D01*
Y400637D01*
X1082089D01*
G37*
G36*
G01X1075756Y417123D02*
X1074996Y417473D01*
Y418373D01*
X1075756Y418723D01*
X1075931D01*
Y417123D01*
X1075756D01*
G37*
G36*
G01Y413623D02*
X1074996Y413973D01*
Y414873D01*
X1075756Y415223D01*
X1075931D01*
Y413623D01*
X1075756D01*
G37*
G36*
G01X1078136Y410182D02*
X1077351Y409892D01*
X1076715Y410528D01*
X1077005Y411313D01*
X1077128Y411437D01*
X1078260Y410305D01*
X1078136Y410182D01*
G37*
G36*
G01X1075731Y422834D02*
X1076481Y422784D01*
Y422384D01*
X1075731Y422334D01*
X1075531D01*
Y422834D01*
X1075731D01*
G37*
G36*
G01Y425434D02*
X1076481Y425384D01*
Y424984D01*
X1075731Y424934D01*
X1075531D01*
Y425434D01*
X1075731D01*
G37*
G36*
G01Y428034D02*
X1076481Y427984D01*
Y427584D01*
X1075731Y427534D01*
X1075531D01*
Y428034D01*
X1075731D01*
G37*
G36*
G01Y430634D02*
X1076481Y430584D01*
Y430184D01*
X1075731Y430134D01*
X1075531D01*
Y430634D01*
X1075731D01*
G37*
G36*
G01Y433234D02*
X1076481Y433184D01*
Y432784D01*
X1075731Y432734D01*
X1075531D01*
Y433234D01*
X1075731D01*
G37*
G36*
G01Y438434D02*
X1076481Y438384D01*
Y437984D01*
X1075731Y437934D01*
X1075531D01*
Y438434D01*
X1075731D01*
G37*
G36*
G01Y435834D02*
X1076481Y435784D01*
Y435384D01*
X1075731Y435334D01*
X1075531D01*
Y435834D01*
X1075731D01*
G37*
G36*
G01X1075331Y421034D02*
X1074581Y421084D01*
Y421484D01*
X1075331Y421534D01*
X1075531D01*
Y421034D01*
X1075331D01*
G37*
G36*
G01Y423634D02*
X1074581Y423684D01*
Y424084D01*
X1075331Y424134D01*
X1075531D01*
Y423634D01*
X1075331D01*
G37*
G36*
G01Y426234D02*
X1074581Y426284D01*
Y426684D01*
X1075331Y426734D01*
X1075531D01*
Y426234D01*
X1075331D01*
G37*
G36*
G01Y428834D02*
X1074581Y428884D01*
Y429284D01*
X1075331Y429334D01*
X1075531D01*
Y428834D01*
X1075331D01*
G37*
G36*
G01Y431434D02*
X1074581Y431484D01*
Y431884D01*
X1075331Y431934D01*
X1075531D01*
Y431434D01*
X1075331D01*
G37*
G36*
G01Y434034D02*
X1074581Y434084D01*
Y434484D01*
X1075331Y434534D01*
X1075531D01*
Y434034D01*
X1075331D01*
G37*
G36*
G01Y439234D02*
X1074581Y439284D01*
Y439684D01*
X1075331Y439734D01*
X1075531D01*
Y439234D01*
X1075331D01*
G37*
G36*
G01Y436634D02*
X1074581Y436684D01*
Y437084D01*
X1075331Y437134D01*
X1075531D01*
Y436634D01*
X1075331D01*
G37*
G36*
G01X1079282Y402895D02*
X1078522Y403245D01*
Y404145D01*
X1079282Y404495D01*
X1079457D01*
Y402895D01*
X1079282D01*
G37*
G36*
G01X1076856Y418723D02*
X1077616Y418373D01*
Y417473D01*
X1076856Y417123D01*
X1076681D01*
Y418723D01*
X1076856D01*
G37*
G36*
G01Y415223D02*
X1077616Y414873D01*
Y413973D01*
X1076856Y413623D01*
X1076681D01*
Y415223D01*
X1076856D01*
G37*
G36*
G01X1077783Y412091D02*
X1078568Y412381D01*
X1079204Y411745D01*
X1078914Y410960D01*
X1078791Y410836D01*
X1077659Y411968D01*
X1077783Y412091D01*
G37*
G36*
G01X1080382Y407495D02*
X1081142Y407145D01*
Y406245D01*
X1080382Y405895D01*
X1080207D01*
Y407495D01*
X1080382D01*
G37*
G36*
G01X1077281Y422834D02*
X1078031Y422784D01*
Y422384D01*
X1077281Y422334D01*
X1077081D01*
Y422834D01*
X1077281D01*
G37*
G36*
G01Y425434D02*
X1078031Y425384D01*
Y424984D01*
X1077281Y424934D01*
X1077081D01*
Y425434D01*
X1077281D01*
G37*
G36*
G01Y428034D02*
X1078031Y427984D01*
Y427584D01*
X1077281Y427534D01*
X1077081D01*
Y428034D01*
X1077281D01*
G37*
G36*
G01Y430634D02*
X1078031Y430584D01*
Y430184D01*
X1077281Y430134D01*
X1077081D01*
Y430634D01*
X1077281D01*
G37*
G36*
G01Y433234D02*
X1078031Y433184D01*
Y432784D01*
X1077281Y432734D01*
X1077081D01*
Y433234D01*
X1077281D01*
G37*
G36*
G01Y438434D02*
X1078031Y438384D01*
Y437984D01*
X1077281Y437934D01*
X1077081D01*
Y438434D01*
X1077281D01*
G37*
G36*
G01Y435834D02*
X1078031Y435784D01*
Y435384D01*
X1077281Y435334D01*
X1077081D01*
Y435834D01*
X1077281D01*
G37*
G36*
G01X1076881Y421034D02*
X1076131Y421084D01*
Y421484D01*
X1076881Y421534D01*
X1077081D01*
Y421034D01*
X1076881D01*
G37*
G36*
G01Y423634D02*
X1076131Y423684D01*
Y424084D01*
X1076881Y424134D01*
X1077081D01*
Y423634D01*
X1076881D01*
G37*
G36*
G01Y426234D02*
X1076131Y426284D01*
Y426684D01*
X1076881Y426734D01*
X1077081D01*
Y426234D01*
X1076881D01*
G37*
G36*
G01Y428834D02*
X1076131Y428884D01*
Y429284D01*
X1076881Y429334D01*
X1077081D01*
Y428834D01*
X1076881D01*
G37*
G36*
G01Y431434D02*
X1076131Y431484D01*
Y431884D01*
X1076881Y431934D01*
X1077081D01*
Y431434D01*
X1076881D01*
G37*
G36*
G01Y439234D02*
X1076131Y439284D01*
Y439684D01*
X1076881Y439734D01*
X1077081D01*
Y439234D01*
X1076881D01*
G37*
G36*
G01Y436634D02*
X1076131Y436684D01*
Y437084D01*
X1076881Y437134D01*
X1077081D01*
Y436634D01*
X1076881D01*
G37*
G36*
G01Y434034D02*
X1076131Y434084D01*
Y434484D01*
X1076881Y434534D01*
X1077081D01*
Y434034D01*
X1076881D01*
G37*
G36*
G01X1090073Y416011D02*
X1089289Y415721D01*
X1088652Y416358D01*
X1088942Y417142D01*
X1089066Y417266D01*
X1090197Y416135D01*
X1090073Y416011D01*
G37*
G36*
G01X1090757Y411584D02*
X1089997Y411934D01*
Y412834D01*
X1090757Y413184D01*
X1090932D01*
Y411584D01*
X1090757D01*
G37*
G36*
G01X1089882Y407881D02*
X1089399Y408565D01*
X1089849Y409344D01*
X1090682Y409267D01*
X1090834Y409179D01*
X1090033Y407794D01*
X1089882Y407881D01*
G37*
G36*
G01X1088131Y422834D02*
X1088881Y422784D01*
Y422384D01*
X1088131Y422334D01*
X1087931D01*
Y422834D01*
X1088131D01*
G37*
G36*
G01Y425434D02*
X1088881Y425384D01*
Y424984D01*
X1088131Y424934D01*
X1087931D01*
Y425434D01*
X1088131D01*
G37*
G36*
G01Y428034D02*
X1088881Y427984D01*
Y427584D01*
X1088131Y427534D01*
X1087931D01*
Y428034D01*
X1088131D01*
G37*
G36*
G01Y430634D02*
X1088881Y430584D01*
Y430184D01*
X1088131Y430134D01*
X1087931D01*
Y430634D01*
X1088131D01*
G37*
G36*
G01Y433234D02*
X1088881Y433184D01*
Y432784D01*
X1088131Y432734D01*
X1087931D01*
Y433234D01*
X1088131D01*
G37*
G36*
G01Y438434D02*
X1088881Y438384D01*
Y437984D01*
X1088131Y437934D01*
X1087931D01*
Y438434D01*
X1088131D01*
G37*
G36*
G01Y435834D02*
X1088881Y435784D01*
Y435384D01*
X1088131Y435334D01*
X1087931D01*
Y435834D01*
X1088131D01*
G37*
G36*
G01X1087731Y421034D02*
X1086981Y421084D01*
Y421484D01*
X1087731Y421534D01*
X1087931D01*
Y421034D01*
X1087731D01*
G37*
G36*
G01Y423634D02*
X1086981Y423684D01*
Y424084D01*
X1087731Y424134D01*
X1087931D01*
Y423634D01*
X1087731D01*
G37*
G36*
G01Y426234D02*
X1086981Y426284D01*
Y426684D01*
X1087731Y426734D01*
X1087931D01*
Y426234D01*
X1087731D01*
G37*
G36*
G01Y428834D02*
X1086981Y428884D01*
Y429284D01*
X1087731Y429334D01*
X1087931D01*
Y428834D01*
X1087731D01*
G37*
G36*
G01Y431434D02*
X1086981Y431484D01*
Y431884D01*
X1087731Y431934D01*
X1087931D01*
Y431434D01*
X1087731D01*
G37*
G36*
G01Y439234D02*
X1086981Y439284D01*
Y439684D01*
X1087731Y439734D01*
X1087931D01*
Y439234D01*
X1087731D01*
G37*
G36*
G01Y436634D02*
X1086981Y436684D01*
Y437084D01*
X1087731Y437134D01*
X1087931D01*
Y436634D01*
X1087731D01*
G37*
G36*
G01Y434034D02*
X1086981Y434084D01*
Y434484D01*
X1087731Y434534D01*
X1087931D01*
Y434034D01*
X1087731D01*
G37*
G36*
G01X1089774Y417974D02*
X1090558Y418264D01*
X1091195Y417627D01*
X1090905Y416843D01*
X1090781Y416719D01*
X1089650Y417850D01*
X1089774Y417974D01*
G37*
G36*
G01X1091857Y413184D02*
X1092617Y412834D01*
Y411934D01*
X1091857Y411584D01*
X1091682D01*
Y413184D01*
X1091857D01*
G37*
G36*
G01X1091634Y408717D02*
X1092116Y408034D01*
X1091666Y407254D01*
X1090833Y407332D01*
X1090681Y407419D01*
X1091482Y408805D01*
X1091634Y408717D01*
G37*
G36*
G01X1089281Y421034D02*
X1088531Y421084D01*
Y421484D01*
X1089281Y421534D01*
X1089481D01*
Y421034D01*
X1089281D01*
G37*
G36*
G01Y423634D02*
X1088531Y423684D01*
Y424084D01*
X1089281Y424134D01*
X1089481D01*
Y423634D01*
X1089281D01*
G37*
G36*
G01Y426234D02*
X1088531Y426284D01*
Y426684D01*
X1089281Y426734D01*
X1089481D01*
Y426234D01*
X1089281D01*
G37*
G36*
G01Y428834D02*
X1088531Y428884D01*
Y429284D01*
X1089281Y429334D01*
X1089481D01*
Y428834D01*
X1089281D01*
G37*
G36*
G01Y431434D02*
X1088531Y431484D01*
Y431884D01*
X1089281Y431934D01*
X1089481D01*
Y431434D01*
X1089281D01*
G37*
G36*
G01Y436634D02*
X1088531Y436684D01*
Y437084D01*
X1089281Y437134D01*
X1089481D01*
Y436634D01*
X1089281D01*
G37*
G36*
G01Y434034D02*
X1088531Y434084D01*
Y434484D01*
X1089281Y434534D01*
X1089481D01*
Y434034D01*
X1089281D01*
G37*
G36*
G01X1089681Y422834D02*
X1090431Y422784D01*
Y422384D01*
X1089681Y422334D01*
X1089481D01*
Y422834D01*
X1089681D01*
G37*
G36*
G01Y425434D02*
X1090431Y425384D01*
Y424984D01*
X1089681Y424934D01*
X1089481D01*
Y425434D01*
X1089681D01*
G37*
G36*
G01Y428034D02*
X1090431Y427984D01*
Y427584D01*
X1089681Y427534D01*
X1089481D01*
Y428034D01*
X1089681D01*
G37*
G36*
G01Y430634D02*
X1090431Y430584D01*
Y430184D01*
X1089681Y430134D01*
X1089481D01*
Y430634D01*
X1089681D01*
G37*
G36*
G01Y433234D02*
X1090431Y433184D01*
Y432784D01*
X1089681Y432734D01*
X1089481D01*
Y433234D01*
X1089681D01*
G37*
G36*
G01Y438434D02*
X1090431Y438384D01*
Y437984D01*
X1089681Y437934D01*
X1089481D01*
Y438434D01*
X1089681D01*
G37*
G36*
G01Y435834D02*
X1090431Y435784D01*
Y435384D01*
X1089681Y435334D01*
X1089481D01*
Y435834D01*
X1089681D01*
G37*
G36*
G01X1089281Y439234D02*
X1088531Y439284D01*
Y439684D01*
X1089281Y439734D01*
X1089481D01*
Y439234D01*
X1089281D01*
G37*
G36*
G01X1072656Y410296D02*
X1071896Y410646D01*
Y411546D01*
X1072656Y411896D01*
X1072831D01*
Y410296D01*
X1072656D01*
G37*
G36*
G01Y414196D02*
X1071896Y414546D01*
Y415446D01*
X1072656Y415796D01*
X1072831D01*
Y414196D01*
X1072656D01*
G37*
G36*
G01X1074142Y405635D02*
X1073357Y405345D01*
X1072721Y405981D01*
X1073011Y406766D01*
X1073134Y406890D01*
X1074266Y405758D01*
X1074142Y405635D01*
G37*
G36*
G01X1072631Y422834D02*
X1073381Y422784D01*
Y422384D01*
X1072631Y422334D01*
X1072431D01*
Y422834D01*
X1072631D01*
G37*
G36*
G01Y425434D02*
X1073381Y425384D01*
Y424984D01*
X1072631Y424934D01*
X1072431D01*
Y425434D01*
X1072631D01*
G37*
G36*
G01Y428034D02*
X1073381Y427984D01*
Y427584D01*
X1072631Y427534D01*
X1072431D01*
Y428034D01*
X1072631D01*
G37*
G36*
G01Y430634D02*
X1073381Y430584D01*
Y430184D01*
X1072631Y430134D01*
X1072431D01*
Y430634D01*
X1072631D01*
G37*
G36*
G01Y433234D02*
X1073381Y433184D01*
Y432784D01*
X1072631Y432734D01*
X1072431D01*
Y433234D01*
X1072631D01*
G37*
G36*
G01Y438434D02*
X1073381Y438384D01*
Y437984D01*
X1072631Y437934D01*
X1072431D01*
Y438434D01*
X1072631D01*
G37*
G36*
G01Y435834D02*
X1073381Y435784D01*
Y435384D01*
X1072631Y435334D01*
X1072431D01*
Y435834D01*
X1072631D01*
G37*
G36*
G01X1072231Y421034D02*
X1071481Y421084D01*
Y421484D01*
X1072231Y421534D01*
X1072431D01*
Y421034D01*
X1072231D01*
G37*
G36*
G01Y423634D02*
X1071481Y423684D01*
Y424084D01*
X1072231Y424134D01*
X1072431D01*
Y423634D01*
X1072231D01*
G37*
G36*
G01Y426234D02*
X1071481Y426284D01*
Y426684D01*
X1072231Y426734D01*
X1072431D01*
Y426234D01*
X1072231D01*
G37*
G36*
G01Y428834D02*
X1071481Y428884D01*
Y429284D01*
X1072231Y429334D01*
X1072431D01*
Y428834D01*
X1072231D01*
G37*
G36*
G01Y431434D02*
X1071481Y431484D01*
Y431884D01*
X1072231Y431934D01*
X1072431D01*
Y431434D01*
X1072231D01*
G37*
G36*
G01Y434034D02*
X1071481Y434084D01*
Y434484D01*
X1072231Y434534D01*
X1072431D01*
Y434034D01*
X1072231D01*
G37*
G36*
G01Y439234D02*
X1071481Y439284D01*
Y439684D01*
X1072231Y439734D01*
X1072431D01*
Y439234D01*
X1072231D01*
G37*
G36*
G01Y436634D02*
X1071481Y436684D01*
Y437084D01*
X1072231Y437134D01*
X1072431D01*
Y436634D01*
X1072231D01*
G37*
G36*
G01X1073756Y411896D02*
X1074516Y411546D01*
Y410646D01*
X1073756Y410296D01*
X1073581D01*
Y411896D01*
X1073756D01*
G37*
G36*
G01Y415796D02*
X1074516Y415446D01*
Y414546D01*
X1073756Y414196D01*
X1073581D01*
Y415796D01*
X1073756D01*
G37*
G36*
G01X1073800Y407555D02*
X1074585Y407845D01*
X1075221Y407209D01*
X1074931Y406424D01*
X1074808Y406300D01*
X1073676Y407432D01*
X1073800Y407555D01*
G37*
G36*
G01X1074181Y438434D02*
X1074931Y438384D01*
Y437984D01*
X1074181Y437934D01*
X1073981D01*
Y438434D01*
X1074181D01*
G37*
G36*
G01Y435834D02*
X1074931Y435784D01*
Y435384D01*
X1074181Y435334D01*
X1073981D01*
Y435834D01*
X1074181D01*
G37*
G36*
G01Y433234D02*
X1074931Y433184D01*
Y432784D01*
X1074181Y432734D01*
X1073981D01*
Y433234D01*
X1074181D01*
G37*
G36*
G01Y422834D02*
X1074931Y422784D01*
Y422384D01*
X1074181Y422334D01*
X1073981D01*
Y422834D01*
X1074181D01*
G37*
G36*
G01Y425434D02*
X1074931Y425384D01*
Y424984D01*
X1074181Y424934D01*
X1073981D01*
Y425434D01*
X1074181D01*
G37*
G36*
G01Y428034D02*
X1074931Y427984D01*
Y427584D01*
X1074181Y427534D01*
X1073981D01*
Y428034D01*
X1074181D01*
G37*
G36*
G01Y430634D02*
X1074931Y430584D01*
Y430184D01*
X1074181Y430134D01*
X1073981D01*
Y430634D01*
X1074181D01*
G37*
G36*
G01X1073781Y439234D02*
X1073031Y439284D01*
Y439684D01*
X1073781Y439734D01*
X1073981D01*
Y439234D01*
X1073781D01*
G37*
G36*
G01Y436634D02*
X1073031Y436684D01*
Y437084D01*
X1073781Y437134D01*
X1073981D01*
Y436634D01*
X1073781D01*
G37*
G36*
G01Y434034D02*
X1073031Y434084D01*
Y434484D01*
X1073781Y434534D01*
X1073981D01*
Y434034D01*
X1073781D01*
G37*
G36*
G01Y431434D02*
X1073031Y431484D01*
Y431884D01*
X1073781Y431934D01*
X1073981D01*
Y431434D01*
X1073781D01*
G37*
G36*
G01Y421034D02*
X1073031Y421084D01*
Y421484D01*
X1073781Y421534D01*
X1073981D01*
Y421034D01*
X1073781D01*
G37*
G36*
G01Y423634D02*
X1073031Y423684D01*
Y424084D01*
X1073781Y424134D01*
X1073981D01*
Y423634D01*
X1073781D01*
G37*
G36*
G01Y426234D02*
X1073031Y426284D01*
Y426684D01*
X1073781Y426734D01*
X1073981D01*
Y426234D01*
X1073781D01*
G37*
G36*
G01Y428834D02*
X1073031Y428884D01*
Y429284D01*
X1073781Y429334D01*
X1073981D01*
Y428834D01*
X1073781D01*
G37*
G36*
G01X1087636Y410246D02*
X1086876Y410596D01*
Y411496D01*
X1087636Y411846D01*
X1087811D01*
Y410246D01*
X1087636D01*
G37*
G36*
G01X1085031Y422834D02*
X1085781Y422784D01*
Y422384D01*
X1085031Y422334D01*
X1084831D01*
Y422834D01*
X1085031D01*
G37*
G36*
G01Y425434D02*
X1085781Y425384D01*
Y424984D01*
X1085031Y424934D01*
X1084831D01*
Y425434D01*
X1085031D01*
G37*
G36*
G01Y428034D02*
X1085781Y427984D01*
Y427584D01*
X1085031Y427534D01*
X1084831D01*
Y428034D01*
X1085031D01*
G37*
G36*
G01Y430634D02*
X1085781Y430584D01*
Y430184D01*
X1085031Y430134D01*
X1084831D01*
Y430634D01*
X1085031D01*
G37*
G36*
G01Y433234D02*
X1085781Y433184D01*
Y432784D01*
X1085031Y432734D01*
X1084831D01*
Y433234D01*
X1085031D01*
G37*
G36*
G01Y438434D02*
X1085781Y438384D01*
Y437984D01*
X1085031Y437934D01*
X1084831D01*
Y438434D01*
X1085031D01*
G37*
G36*
G01Y435834D02*
X1085781Y435784D01*
Y435384D01*
X1085031Y435334D01*
X1084831D01*
Y435834D01*
X1085031D01*
G37*
G36*
G01X1084631Y421034D02*
X1083881Y421084D01*
Y421484D01*
X1084631Y421534D01*
X1084831D01*
Y421034D01*
X1084631D01*
G37*
G36*
G01Y423634D02*
X1083881Y423684D01*
Y424084D01*
X1084631Y424134D01*
X1084831D01*
Y423634D01*
X1084631D01*
G37*
G36*
G01Y426234D02*
X1083881Y426284D01*
Y426684D01*
X1084631Y426734D01*
X1084831D01*
Y426234D01*
X1084631D01*
G37*
G36*
G01Y428834D02*
X1083881Y428884D01*
Y429284D01*
X1084631Y429334D01*
X1084831D01*
Y428834D01*
X1084631D01*
G37*
G36*
G01Y431434D02*
X1083881Y431484D01*
Y431884D01*
X1084631Y431934D01*
X1084831D01*
Y431434D01*
X1084631D01*
G37*
G36*
G01Y439234D02*
X1083881Y439284D01*
Y439684D01*
X1084631Y439734D01*
X1084831D01*
Y439234D01*
X1084631D01*
G37*
G36*
G01Y436634D02*
X1083881Y436684D01*
Y437084D01*
X1084631Y437134D01*
X1084831D01*
Y436634D01*
X1084631D01*
G37*
G36*
G01Y434034D02*
X1083881Y434084D01*
Y434484D01*
X1084631Y434534D01*
X1084831D01*
Y434034D01*
X1084631D01*
G37*
G36*
G01X1086829Y416618D02*
X1087614Y416908D01*
X1088250Y416272D01*
X1087960Y415487D01*
X1087837Y415363D01*
X1086705Y416495D01*
X1086829Y416618D01*
G37*
G36*
G01X1088136Y408346D02*
X1088896Y407996D01*
Y407096D01*
X1088136Y406746D01*
X1087961D01*
Y408346D01*
X1088136D01*
G37*
G36*
G01X1088736Y411846D02*
X1089496Y411496D01*
Y410596D01*
X1088736Y410246D01*
X1088561D01*
Y411846D01*
X1088736D01*
G37*
G36*
G01X1086581Y422834D02*
X1087331Y422784D01*
Y422384D01*
X1086581Y422334D01*
X1086381D01*
Y422834D01*
X1086581D01*
G37*
G36*
G01Y425434D02*
X1087331Y425384D01*
Y424984D01*
X1086581Y424934D01*
X1086381D01*
Y425434D01*
X1086581D01*
G37*
G36*
G01Y428034D02*
X1087331Y427984D01*
Y427584D01*
X1086581Y427534D01*
X1086381D01*
Y428034D01*
X1086581D01*
G37*
G36*
G01Y430634D02*
X1087331Y430584D01*
Y430184D01*
X1086581Y430134D01*
X1086381D01*
Y430634D01*
X1086581D01*
G37*
G36*
G01Y433234D02*
X1087331Y433184D01*
Y432784D01*
X1086581Y432734D01*
X1086381D01*
Y433234D01*
X1086581D01*
G37*
G36*
G01Y438434D02*
X1087331Y438384D01*
Y437984D01*
X1086581Y437934D01*
X1086381D01*
Y438434D01*
X1086581D01*
G37*
G36*
G01Y435834D02*
X1087331Y435784D01*
Y435384D01*
X1086581Y435334D01*
X1086381D01*
Y435834D01*
X1086581D01*
G37*
G36*
G01X1086181Y421034D02*
X1085431Y421084D01*
Y421484D01*
X1086181Y421534D01*
X1086381D01*
Y421034D01*
X1086181D01*
G37*
G36*
G01Y423634D02*
X1085431Y423684D01*
Y424084D01*
X1086181Y424134D01*
X1086381D01*
Y423634D01*
X1086181D01*
G37*
G36*
G01Y426234D02*
X1085431Y426284D01*
Y426684D01*
X1086181Y426734D01*
X1086381D01*
Y426234D01*
X1086181D01*
G37*
G36*
G01Y428834D02*
X1085431Y428884D01*
Y429284D01*
X1086181Y429334D01*
X1086381D01*
Y428834D01*
X1086181D01*
G37*
G36*
G01Y431434D02*
X1085431Y431484D01*
Y431884D01*
X1086181Y431934D01*
X1086381D01*
Y431434D01*
X1086181D01*
G37*
G36*
G01Y439234D02*
X1085431Y439284D01*
Y439684D01*
X1086181Y439734D01*
X1086381D01*
Y439234D01*
X1086181D01*
G37*
G36*
G01Y436634D02*
X1085431Y436684D01*
Y437084D01*
X1086181Y437134D01*
X1086381D01*
Y436634D01*
X1086181D01*
G37*
G36*
G01Y434034D02*
X1085431Y434084D01*
Y434484D01*
X1086181Y434534D01*
X1086381D01*
Y434034D01*
X1086181D01*
G37*
G36*
G01X1079956Y417530D02*
X1080716Y417180D01*
Y416280D01*
X1079956Y415930D01*
X1079781D01*
Y417530D01*
X1079956D01*
G37*
G36*
G01X1080972Y413335D02*
X1081756Y413625D01*
X1082393Y412988D01*
X1082103Y412204D01*
X1081979Y412080D01*
X1080848Y413211D01*
X1080972Y413335D01*
G37*
G36*
G01X1083221Y410621D02*
X1083981Y410271D01*
Y409371D01*
X1083221Y409021D01*
X1083046D01*
Y410621D01*
X1083221D01*
G37*
G36*
G01X1080381Y422834D02*
X1081131Y422784D01*
Y422384D01*
X1080381Y422334D01*
X1080181D01*
Y422834D01*
X1080381D01*
G37*
G36*
G01Y425434D02*
X1081131Y425384D01*
Y424984D01*
X1080381Y424934D01*
X1080181D01*
Y425434D01*
X1080381D01*
G37*
G36*
G01Y428034D02*
X1081131Y427984D01*
Y427584D01*
X1080381Y427534D01*
X1080181D01*
Y428034D01*
X1080381D01*
G37*
G36*
G01Y430634D02*
X1081131Y430584D01*
Y430184D01*
X1080381Y430134D01*
X1080181D01*
Y430634D01*
X1080381D01*
G37*
G36*
G01Y433234D02*
X1081131Y433184D01*
Y432784D01*
X1080381Y432734D01*
X1080181D01*
Y433234D01*
X1080381D01*
G37*
G36*
G01Y438434D02*
X1081131Y438384D01*
Y437984D01*
X1080381Y437934D01*
X1080181D01*
Y438434D01*
X1080381D01*
G37*
G36*
G01Y435834D02*
X1081131Y435784D01*
Y435384D01*
X1080381Y435334D01*
X1080181D01*
Y435834D01*
X1080381D01*
G37*
G36*
G01X1079981Y421034D02*
X1079231Y421084D01*
Y421484D01*
X1079981Y421534D01*
X1080181D01*
Y421034D01*
X1079981D01*
G37*
G36*
G01Y423634D02*
X1079231Y423684D01*
Y424084D01*
X1079981Y424134D01*
X1080181D01*
Y423634D01*
X1079981D01*
G37*
G36*
G01Y426234D02*
X1079231Y426284D01*
Y426684D01*
X1079981Y426734D01*
X1080181D01*
Y426234D01*
X1079981D01*
G37*
G36*
G01Y428834D02*
X1079231Y428884D01*
Y429284D01*
X1079981Y429334D01*
X1080181D01*
Y428834D01*
X1079981D01*
G37*
G36*
G01Y431434D02*
X1079231Y431484D01*
Y431884D01*
X1079981Y431934D01*
X1080181D01*
Y431434D01*
X1079981D01*
G37*
G36*
G01Y439234D02*
X1079231Y439284D01*
Y439684D01*
X1079981Y439734D01*
X1080181D01*
Y439234D01*
X1079981D01*
G37*
G36*
G01Y436634D02*
X1079231Y436684D01*
Y437084D01*
X1079981Y437134D01*
X1080181D01*
Y436634D01*
X1079981D01*
G37*
G36*
G01Y434034D02*
X1079231Y434084D01*
Y434484D01*
X1079981Y434534D01*
X1080181D01*
Y434034D01*
X1079981D01*
G37*
G36*
G01X1083886Y413167D02*
X1083101Y412877D01*
X1082465Y413513D01*
X1082755Y414298D01*
X1082878Y414422D01*
X1084010Y413290D01*
X1083886Y413167D01*
G37*
G36*
G01X1081956Y416530D02*
X1081196Y416880D01*
Y417780D01*
X1081956Y418130D01*
X1082131D01*
Y416530D01*
X1081956D01*
G37*
G36*
G01X1084581Y407281D02*
X1083821Y407631D01*
Y408531D01*
X1084581Y408881D01*
X1084756D01*
Y407281D01*
X1084581D01*
G37*
G36*
G01X1081931Y422834D02*
X1082681Y422784D01*
Y422384D01*
X1081931Y422334D01*
X1081731D01*
Y422834D01*
X1081931D01*
G37*
G36*
G01Y425434D02*
X1082681Y425384D01*
Y424984D01*
X1081931Y424934D01*
X1081731D01*
Y425434D01*
X1081931D01*
G37*
G36*
G01Y428034D02*
X1082681Y427984D01*
Y427584D01*
X1081931Y427534D01*
X1081731D01*
Y428034D01*
X1081931D01*
G37*
G36*
G01Y430634D02*
X1082681Y430584D01*
Y430184D01*
X1081931Y430134D01*
X1081731D01*
Y430634D01*
X1081931D01*
G37*
G36*
G01Y433234D02*
X1082681Y433184D01*
Y432784D01*
X1081931Y432734D01*
X1081731D01*
Y433234D01*
X1081931D01*
G37*
G36*
G01Y438434D02*
X1082681Y438384D01*
Y437984D01*
X1081931Y437934D01*
X1081731D01*
Y438434D01*
X1081931D01*
G37*
G36*
G01Y435834D02*
X1082681Y435784D01*
Y435384D01*
X1081931Y435334D01*
X1081731D01*
Y435834D01*
X1081931D01*
G37*
G36*
G01X1081531Y421034D02*
X1080781Y421084D01*
Y421484D01*
X1081531Y421534D01*
X1081731D01*
Y421034D01*
X1081531D01*
G37*
G36*
G01Y423634D02*
X1080781Y423684D01*
Y424084D01*
X1081531Y424134D01*
X1081731D01*
Y423634D01*
X1081531D01*
G37*
G36*
G01Y426234D02*
X1080781Y426284D01*
Y426684D01*
X1081531Y426734D01*
X1081731D01*
Y426234D01*
X1081531D01*
G37*
G36*
G01Y428834D02*
X1080781Y428884D01*
Y429284D01*
X1081531Y429334D01*
X1081731D01*
Y428834D01*
X1081531D01*
G37*
G36*
G01Y431434D02*
X1080781Y431484D01*
Y431884D01*
X1081531Y431934D01*
X1081731D01*
Y431434D01*
X1081531D01*
G37*
G36*
G01Y439234D02*
X1080781Y439284D01*
Y439684D01*
X1081531Y439734D01*
X1081731D01*
Y439234D01*
X1081531D01*
G37*
G36*
G01Y436634D02*
X1080781Y436684D01*
Y437084D01*
X1081531Y437134D01*
X1081731D01*
Y436634D01*
X1081531D01*
G37*
G36*
G01Y434034D02*
X1080781Y434084D01*
Y434484D01*
X1081531Y434534D01*
X1081731D01*
Y434034D01*
X1081531D01*
G37*
G36*
G01X1078856Y415930D02*
X1078096Y416280D01*
Y417180D01*
X1078856Y417530D01*
X1079031D01*
Y415930D01*
X1078856D01*
G37*
G36*
G01X1081325Y411426D02*
X1080540Y411136D01*
X1079904Y411772D01*
X1080194Y412557D01*
X1080317Y412681D01*
X1081449Y411549D01*
X1081325Y411426D01*
G37*
G36*
G01X1082121Y407321D02*
X1081361Y407671D01*
Y408571D01*
X1082121Y408921D01*
X1082296D01*
Y407321D01*
X1082121D01*
G37*
G36*
G01X1078831Y422834D02*
X1079581Y422784D01*
Y422384D01*
X1078831Y422334D01*
X1078631D01*
Y422834D01*
X1078831D01*
G37*
G36*
G01Y425434D02*
X1079581Y425384D01*
Y424984D01*
X1078831Y424934D01*
X1078631D01*
Y425434D01*
X1078831D01*
G37*
G36*
G01Y428034D02*
X1079581Y427984D01*
Y427584D01*
X1078831Y427534D01*
X1078631D01*
Y428034D01*
X1078831D01*
G37*
G36*
G01Y430634D02*
X1079581Y430584D01*
Y430184D01*
X1078831Y430134D01*
X1078631D01*
Y430634D01*
X1078831D01*
G37*
G36*
G01Y433234D02*
X1079581Y433184D01*
Y432784D01*
X1078831Y432734D01*
X1078631D01*
Y433234D01*
X1078831D01*
G37*
G36*
G01Y438434D02*
X1079581Y438384D01*
Y437984D01*
X1078831Y437934D01*
X1078631D01*
Y438434D01*
X1078831D01*
G37*
G36*
G01Y435834D02*
X1079581Y435784D01*
Y435384D01*
X1078831Y435334D01*
X1078631D01*
Y435834D01*
X1078831D01*
G37*
G36*
G01X1078431Y421034D02*
X1077681Y421084D01*
Y421484D01*
X1078431Y421534D01*
X1078631D01*
Y421034D01*
X1078431D01*
G37*
G36*
G01Y423634D02*
X1077681Y423684D01*
Y424084D01*
X1078431Y424134D01*
X1078631D01*
Y423634D01*
X1078431D01*
G37*
G36*
G01Y426234D02*
X1077681Y426284D01*
Y426684D01*
X1078431Y426734D01*
X1078631D01*
Y426234D01*
X1078431D01*
G37*
G36*
G01Y428834D02*
X1077681Y428884D01*
Y429284D01*
X1078431Y429334D01*
X1078631D01*
Y428834D01*
X1078431D01*
G37*
G36*
G01Y431434D02*
X1077681Y431484D01*
Y431884D01*
X1078431Y431934D01*
X1078631D01*
Y431434D01*
X1078431D01*
G37*
G36*
G01Y439234D02*
X1077681Y439284D01*
Y439684D01*
X1078431Y439734D01*
X1078631D01*
Y439234D01*
X1078431D01*
G37*
G36*
G01Y436634D02*
X1077681Y436684D01*
Y437084D01*
X1078431Y437134D01*
X1078631D01*
Y436634D01*
X1078431D01*
G37*
G36*
G01Y434034D02*
X1077681Y434084D01*
Y434484D01*
X1078431Y434534D01*
X1078631D01*
Y434034D01*
X1078431D01*
G37*
G36*
G01X1083056Y418130D02*
X1083816Y417780D01*
Y416880D01*
X1083056Y416530D01*
X1082881D01*
Y418130D01*
X1083056D01*
G37*
G36*
G01X1083752Y414857D02*
X1084536Y415147D01*
X1085173Y414510D01*
X1084883Y413726D01*
X1084759Y413602D01*
X1083628Y414733D01*
X1083752Y414857D01*
G37*
G36*
G01X1085681Y408881D02*
X1086441Y408531D01*
Y407631D01*
X1085681Y407281D01*
X1085506D01*
Y408881D01*
X1085681D01*
G37*
G36*
G01X1083481Y422834D02*
X1084231Y422784D01*
Y422384D01*
X1083481Y422334D01*
X1083281D01*
Y422834D01*
X1083481D01*
G37*
G36*
G01Y425434D02*
X1084231Y425384D01*
Y424984D01*
X1083481Y424934D01*
X1083281D01*
Y425434D01*
X1083481D01*
G37*
G36*
G01Y428034D02*
X1084231Y427984D01*
Y427584D01*
X1083481Y427534D01*
X1083281D01*
Y428034D01*
X1083481D01*
G37*
G36*
G01Y430634D02*
X1084231Y430584D01*
Y430184D01*
X1083481Y430134D01*
X1083281D01*
Y430634D01*
X1083481D01*
G37*
G36*
G01Y433234D02*
X1084231Y433184D01*
Y432784D01*
X1083481Y432734D01*
X1083281D01*
Y433234D01*
X1083481D01*
G37*
G36*
G01Y438434D02*
X1084231Y438384D01*
Y437984D01*
X1083481Y437934D01*
X1083281D01*
Y438434D01*
X1083481D01*
G37*
G36*
G01Y435834D02*
X1084231Y435784D01*
Y435384D01*
X1083481Y435334D01*
X1083281D01*
Y435834D01*
X1083481D01*
G37*
G36*
G01X1083081Y421034D02*
X1082331Y421084D01*
Y421484D01*
X1083081Y421534D01*
X1083281D01*
Y421034D01*
X1083081D01*
G37*
G36*
G01Y423634D02*
X1082331Y423684D01*
Y424084D01*
X1083081Y424134D01*
X1083281D01*
Y423634D01*
X1083081D01*
G37*
G36*
G01Y426234D02*
X1082331Y426284D01*
Y426684D01*
X1083081Y426734D01*
X1083281D01*
Y426234D01*
X1083081D01*
G37*
G36*
G01Y428834D02*
X1082331Y428884D01*
Y429284D01*
X1083081Y429334D01*
X1083281D01*
Y428834D01*
X1083081D01*
G37*
G36*
G01Y431434D02*
X1082331Y431484D01*
Y431884D01*
X1083081Y431934D01*
X1083281D01*
Y431434D01*
X1083081D01*
G37*
G36*
G01Y439234D02*
X1082331Y439284D01*
Y439684D01*
X1083081Y439734D01*
X1083281D01*
Y439234D01*
X1083081D01*
G37*
G36*
G01Y436634D02*
X1082331Y436684D01*
Y437084D01*
X1083081Y437134D01*
X1083281D01*
Y436634D01*
X1083081D01*
G37*
G36*
G01Y434034D02*
X1082331Y434084D01*
Y434484D01*
X1083081Y434534D01*
X1083281D01*
Y434034D01*
X1083081D01*
G37*
G36*
G01X1095480Y420376D02*
X1094730Y420426D01*
Y420826D01*
X1095480Y420876D01*
X1095680D01*
Y420376D01*
X1095480D01*
G37*
G36*
G01Y417776D02*
X1094730Y417826D01*
Y418226D01*
X1095480Y418276D01*
X1095680D01*
Y417776D01*
X1095480D01*
G37*
G36*
G01Y425576D02*
X1094730Y425626D01*
Y426026D01*
X1095480Y426076D01*
X1095680D01*
Y425576D01*
X1095480D01*
G37*
G36*
G01Y428176D02*
X1094730Y428226D01*
Y428626D01*
X1095480Y428676D01*
X1095680D01*
Y428176D01*
X1095480D01*
G37*
G36*
G01Y430776D02*
X1094730Y430826D01*
Y431226D01*
X1095480Y431276D01*
X1095680D01*
Y430776D01*
X1095480D01*
G37*
G36*
G01Y422976D02*
X1094730Y423026D01*
Y423426D01*
X1095480Y423476D01*
X1095680D01*
Y422976D01*
X1095480D01*
G37*
G36*
G01X1102608Y536500D02*
X1101608Y535500D01*
Y531700D01*
X1099208Y529300D01*
Y528256D01*
X1093000D01*
Y529756D01*
X1092000Y530756D01*
X1071600D01*
X1070600Y531756D01*
X1056408D01*
Y535256D01*
X1095500D01*
X1096500Y536256D01*
Y537092D01*
X1097309Y537901D01*
X1102307D01*
X1102608Y537600D01*
Y536500D01*
G37*
G36*
G01X1059460Y575640D02*
Y574757D01*
G03X1062580Y574597I1564J0D01*
G02X1062978Y574599I199J-20D01*
G03X1063034Y574334I1393J156D01*
G01X1063044Y574305D01*
Y574209D01*
X1063111Y574141D01*
X1063126Y574113D01*
G03X1065706Y575185I1245J645D01*
G01X1065696Y575215D01*
Y575640D01*
X1076428D01*
Y575206D01*
X1076419Y575177D01*
G03Y574337I1338J-420D01*
G01X1076428Y574308D01*
Y574210D01*
X1076497Y574141D01*
X1076512Y574113D01*
G03X1079091Y575188I1245J645D01*
G01X1079082Y575218D01*
Y575640D01*
X1083122D01*
Y575206D01*
X1083112Y575177D01*
G03Y574337I1338J-420D01*
G01X1083122Y574308D01*
Y574210D01*
X1083190Y574141D01*
X1083205Y574113D01*
G03X1085784Y575188I1245J645D01*
G01X1085774Y575218D01*
Y575640D01*
X1086061D01*
G02X1086446Y575133I0J-400D01*
G03X1089148I1351J-376D01*
G02X1089533Y575640I385J107D01*
G01X1092030D01*
X1092634Y575036D01*
Y566265D01*
X1092160Y565790D01*
X1089122D01*
Y566361D01*
X1089131Y566391D01*
G03X1086552Y567466I-1334J430D01*
G01X1086537Y567438D01*
X1086468Y567369D01*
Y567271D01*
X1086459Y567242D01*
G03Y566402I1338J-420D01*
G01X1086468Y566373D01*
Y565790D01*
X1082428D01*
Y566101D01*
X1082449Y566143D01*
G03X1079755I-1347J664D01*
G01X1079776Y566101D01*
Y565790D01*
X1075736D01*
Y566101D01*
X1075756Y566143D01*
G03X1073062I-1347J664D01*
G01X1073082Y566101D01*
Y565790D01*
X1072390D01*
Y566364D01*
X1072399Y566394D01*
G03X1069819Y567466I-1335J427D01*
G01X1069804Y567438D01*
X1069736Y567370D01*
Y567274D01*
X1069727Y567245D01*
G03Y566399I1337J-423D01*
G01X1069736Y566370D01*
Y565790D01*
X1065696D01*
Y566364D01*
X1065706Y566394D01*
G03X1063126Y567466I-1335J427D01*
G01X1063111Y567438D01*
X1063044Y567370D01*
Y567274D01*
X1063034Y567245D01*
G03Y566399I1337J-423D01*
G01X1063044Y566370D01*
Y565790D01*
X1059004D01*
Y566101D01*
X1059024Y566143D01*
G03X1056330I-1347J664D01*
G01X1056350Y566101D01*
Y565790D01*
X1055656D01*
Y566364D01*
X1055666Y566394D01*
G03X1053086Y567466I-1335J427D01*
G01X1053071Y567438D01*
X1053004Y567370D01*
Y567274D01*
X1052994Y567245D01*
G03Y566399I1337J-423D01*
G01X1053004Y566370D01*
Y565790D01*
X1048964D01*
Y566101D01*
X1048984Y566143D01*
G03X1046642Y567932I-1347J664D01*
G02X1045977Y568232I-265J300D01*
G01Y574648D01*
X1046969Y575640D01*
X1049658D01*
Y575209D01*
X1049648Y575180D01*
G03Y574334I1337J-423D01*
G01X1049658Y574305D01*
Y574209D01*
X1049725Y574141D01*
X1049740Y574113D01*
G03X1052320Y575185I1245J645D01*
G01X1052310Y575215D01*
Y575640D01*
X1053004D01*
Y575209D01*
X1052994Y575180D01*
G03X1055666Y575185I1337J-423D01*
G01X1055656Y575215D01*
Y575640D01*
X1059460D01*
G37*
G36*
G01X1065425Y584798D02*
G03X1065398Y586676I-1054J924D01*
G02X1065691Y587348I293J272D01*
G01X1069010D01*
Y588398D01*
X1069862D01*
X1069886Y588392D01*
G03Y591208I356J1408D01*
G01X1069862Y591202D01*
X1069010D01*
Y592252D01*
X1065866D01*
G02X1065534Y592875I0J400D01*
G03X1065740Y593957I-1163J782D01*
G02X1066131Y594443I391J86D01*
G01X1069304D01*
G02X1069695Y593957I0J-400D01*
G03X1072369Y594170I1369J-300D01*
G01X1072355Y594205D01*
Y594443D01*
X1073017D01*
Y594207D01*
X1073004Y594172D01*
G03X1075877Y593959I1405J-530D01*
G02X1076268Y594443I391J84D01*
G01X1079345D01*
G02X1079735Y593954I0J-400D01*
G03X1079931Y592871I1367J-312D01*
G02X1079597Y592252I-334J-219D01*
G01X1077506D01*
Y591752D01*
X1076006D01*
Y587848D01*
X1077506D01*
Y587110D01*
X1077363Y587067D01*
G03X1076703Y584798I394J-1345D01*
G02X1076402Y584134I-301J-264D01*
G01X1071780D01*
Y584512D01*
X1071865Y584571D01*
G03X1070265Y584570I-801J1151D01*
G01X1070350Y584511D01*
Y584134D01*
X1065726D01*
G02X1065425Y584798I0J400D01*
G37*
G36*
G01X1078811D02*
G03X1078784Y586676I-1054J924D01*
G02X1079077Y587348I293J272D01*
G01X1082010D01*
Y588398D01*
X1082728D01*
X1082752Y588392D01*
G03Y591208I356J1408D01*
G01X1082728Y591202D01*
X1082010D01*
Y592573D01*
G03X1082469Y593954I-908J1069D01*
G02X1082859Y594443I390J89D01*
G01X1086034D01*
G02X1086425Y593958I0J-400D01*
G03X1089165I1370J-299D01*
G02X1089556Y594443I391J85D01*
G01X1091837D01*
X1092634Y593646D01*
Y592252D01*
X1089864D01*
Y591752D01*
X1088364D01*
Y587848D01*
X1089864D01*
Y587348D01*
X1092634D01*
Y584875D01*
X1091893Y584134D01*
X1089152D01*
G02X1088851Y584798I0J400D01*
G03X1086743I-1054J924D01*
G02X1086442Y584134I-301J-264D01*
G01X1085805D01*
G02X1085504Y584798I0J400D01*
G03X1083396I-1054J924D01*
G02X1083095Y584134I-301J-264D01*
G01X1079112D01*
G02X1078811Y584798I0J400D01*
G37*
G36*
G01X1046966Y584134D02*
X1045977Y585123D01*
Y592354D01*
G02X1046657Y592640I400J0D01*
G03X1049004Y593954I980J1002D01*
G02X1049394Y594443I390J89D01*
G01X1052571D01*
G02X1052962Y593957I0J-400D01*
G03X1053168Y592875I1369J-300D01*
G02X1052836Y592252I-332J-223D01*
G01X1052056D01*
Y591752D01*
X1050556D01*
Y587848D01*
X1052056D01*
Y587348D01*
X1053011D01*
G02X1053304Y586676I0J-400D01*
G03X1053277Y584798I1027J-954D01*
G02X1052976Y584134I-301J-264D01*
G01X1052340D01*
G02X1052039Y584798I0J400D01*
G03X1049931I-1054J924D01*
G02X1049630Y584134I-301J-264D01*
G01X1046966D01*
G37*
G36*
G01X1055385Y584798D02*
G03X1055358Y586676I-1054J924D01*
G02X1055651Y587348I293J272D01*
G01X1056560D01*
Y588398D01*
X1057412D01*
X1057436Y588392D01*
G03Y591208I356J1408D01*
G01X1057412Y591202D01*
X1056560D01*
Y591989D01*
G02X1057119Y592356I400J0D01*
G03X1059044Y593954I558J1286D01*
G02X1059434Y594443I390J89D01*
G01X1062611D01*
G02X1063002Y593957I0J-400D01*
G03X1064315Y592256I1369J-300D01*
G02X1064506Y592056I-9J-200D01*
G01Y591752D01*
X1063006D01*
Y587848D01*
X1064506D01*
Y587323D01*
G02X1064315Y587123I-200J0D01*
G03X1063317Y584798I56J-1401D01*
G02X1063016Y584134I-301J-264D01*
G01X1062379D01*
G02X1062078Y584798I0J400D01*
G03X1059970I-1054J924D01*
G02X1059669Y584134I-301J-264D01*
G01X1055686D01*
G02X1055385Y584798I0J400D01*
G37*
G36*
G01X1065425Y546998D02*
G03X1065398Y548876I-1054J924D01*
G02X1065691Y549548I293J272D01*
G01X1069010D01*
Y550598D01*
X1070596D01*
X1070620Y550592D01*
G03Y553408I356J1408D01*
G01X1070596Y553402D01*
X1069010D01*
Y554452D01*
X1065866D01*
G02X1065534Y555075I0J400D01*
G03X1065740Y556157I-1163J782D01*
G02X1066131Y556643I391J86D01*
G01X1069304D01*
G02X1069695Y556157I0J-400D01*
G03X1072433I1369J-300D01*
G02X1072824Y556643I391J86D01*
G01X1073124D01*
Y556404D01*
X1073109Y556368D01*
G03X1075776Y556154I1300J-526D01*
G02X1076166Y556643I390J89D01*
G01X1079345D01*
G02X1079735Y556154I0J-400D01*
G03X1079931Y555071I1367J-312D01*
G02X1079597Y554452I-334J-219D01*
G01X1077506D01*
Y553952D01*
X1076006D01*
Y550048D01*
X1077506D01*
Y549310D01*
X1077363Y549267D01*
G03X1076703Y546998I394J-1345D01*
G02X1076402Y546334I-301J-264D01*
G01X1071780D01*
Y546712D01*
X1071865Y546771D01*
G03X1070265Y546770I-801J1151D01*
G01X1070350Y546711D01*
Y546334D01*
X1065726D01*
G02X1065425Y546998I0J400D01*
G37*
G36*
G01X1078811D02*
G03X1078784Y548876I-1054J924D01*
G02X1079077Y549548I293J272D01*
G01X1082010D01*
Y550598D01*
X1082736D01*
X1082760Y550592D01*
G03Y553408I356J1408D01*
G01X1082736Y553402D01*
X1082010D01*
Y554773D01*
G03X1082469Y556154I-908J1069D01*
G02X1082859Y556643I390J89D01*
G01X1086034D01*
G02X1086425Y556158I0J-400D01*
G03X1089165I1370J-299D01*
G02X1089556Y556643I391J85D01*
G01X1091837D01*
X1092634Y555846D01*
Y554452D01*
X1089864D01*
Y553952D01*
X1088364D01*
Y550048D01*
X1089864D01*
Y549548D01*
X1092634D01*
Y547075D01*
X1091893Y546334D01*
X1089152D01*
G02X1088851Y546998I0J400D01*
G03X1086743I-1054J924D01*
G02X1086442Y546334I-301J-264D01*
G01X1085805D01*
G02X1085504Y546998I0J400D01*
G03X1083396I-1054J924D01*
G02X1083095Y546334I-301J-264D01*
G01X1079112D01*
G02X1078811Y546998I0J400D01*
G37*
G36*
G01X1046966Y546334D02*
X1045977Y547323D01*
Y554554D01*
G02X1046657Y554840I400J0D01*
G03X1049004Y556154I980J1002D01*
G02X1049394Y556643I390J89D01*
G01X1052571D01*
G02X1052962Y556157I0J-400D01*
G03X1053168Y555075I1369J-300D01*
G02X1052836Y554452I-332J-223D01*
G01X1052056D01*
Y553952D01*
X1050556D01*
Y550048D01*
X1052056D01*
Y549548D01*
X1053011D01*
G02X1053304Y548876I0J-400D01*
G03X1053277Y546998I1027J-954D01*
G02X1052976Y546334I-301J-264D01*
G01X1052339D01*
G02X1052038Y546998I0J400D01*
G03X1049930I-1054J924D01*
G02X1049629Y546334I-301J-264D01*
G01X1046966D01*
G37*
G36*
G01X1055385Y546998D02*
G03X1055358Y548876I-1054J924D01*
G02X1055651Y549548I293J272D01*
G01X1056560D01*
Y550598D01*
X1057412D01*
X1057436Y550592D01*
G03Y553408I356J1408D01*
G01X1057412Y553402D01*
X1056560D01*
Y554189D01*
G02X1057119Y554556I400J0D01*
G03X1059044Y556154I558J1286D01*
G02X1059434Y556643I390J89D01*
G01X1062611D01*
G02X1063002Y556157I0J-400D01*
G03X1064315Y554456I1369J-300D01*
G02X1064506Y554256I-9J-200D01*
G01Y553952D01*
X1063006D01*
Y550048D01*
X1064506D01*
Y549523D01*
G02X1064315Y549323I-200J0D01*
G03X1063317Y546998I56J-1401D01*
G02X1063016Y546334I-301J-264D01*
G01X1062379D01*
G02X1062078Y546998I0J400D01*
G03X1059970I-1054J924D01*
G02X1059669Y546334I-301J-264D01*
G01X1055686D01*
G02X1055385Y546998I0J400D01*
G37*
G36*
G01X1059459Y613525D02*
Y609864D01*
G03X1062587I1564J0D01*
G01X1062588D01*
Y611349D01*
G02X1063278Y611624I400J0D01*
G03X1065825Y613027I1091J1033D01*
G02X1066212Y613525I388J98D01*
G01X1069298D01*
G02X1069679Y613003I0J-400D01*
G03X1072445I1383J-443D01*
G02X1072826Y613525I381J122D01*
G01X1075912D01*
G02X1076299Y613027I-1J-400D01*
G03X1079211I1456J-370D01*
G02X1079598Y613525I388J98D01*
G01X1082605D01*
G02X1082992Y613027I-1J-400D01*
G03X1085829Y613247I1456J-370D01*
G01X1085813Y613284D01*
Y613525D01*
X1086468D01*
Y610570D01*
X1086448Y610528D01*
G03X1089142I1347J-664D01*
G01X1089122Y610570D01*
Y613525D01*
X1091945D01*
X1092634Y612836D01*
Y604065D01*
X1092159Y603590D01*
X1089122D01*
Y603908D01*
X1089142Y603950D01*
G03X1086448I-1347J664D01*
G01X1086468Y603908D01*
Y603590D01*
X1082935D01*
G02X1082549Y604097I-1J400D01*
G03X1079655I-1447J402D01*
G02X1079269Y603590I-385J-107D01*
G01X1075736D01*
Y603908D01*
X1075756Y603950D01*
G03X1073062I-1347J664D01*
G01X1073082Y603908D01*
Y603590D01*
X1072390D01*
Y606588D01*
X1072410Y606630D01*
G03X1069716Y606626I-1348J662D01*
G01X1069736Y606584D01*
Y603590D01*
X1065696D01*
Y606588D01*
X1065717Y606630D01*
G03X1063023Y606626I-1348J662D01*
G01X1063044Y606584D01*
Y603590D01*
X1059004D01*
Y606588D01*
X1059024Y606630D01*
G03X1056330Y606626I-1348J662D01*
G01X1056350Y606584D01*
Y603590D01*
X1055677D01*
Y603834D01*
X1055695Y603873D01*
G03X1052883Y604097I-1365J626D01*
G02X1052497Y603590I-385J-107D01*
G01X1049470D01*
G02X1049084Y604097I-1J400D01*
G03X1046642Y605624I-1447J402D01*
G02X1045977Y605924I-265J300D01*
G01Y612448D01*
X1047054Y613525D01*
X1049140D01*
G02X1049528Y613027I0J-400D01*
G03X1052366Y613247I1456J-369D01*
G01X1052350Y613284D01*
Y613525D01*
X1053004D01*
Y610570D01*
X1052983Y610528D01*
G03X1055677I1347J-664D01*
G01X1055656Y610570D01*
Y613525D01*
X1059459D01*
G37*
G36*
G01X1102700Y13290D02*
Y8991D01*
X1101030Y7320D01*
X1099487D01*
X1099183Y7624D01*
Y10366D01*
X1099328Y10511D01*
Y11685D01*
X1098446Y12567D01*
X1097221D01*
X1096376Y11722D01*
Y10493D01*
X1096496Y10373D01*
Y9779D01*
X1096351Y9634D01*
X1095972D01*
X1095697Y9909D01*
Y16330D01*
X1098213Y18847D01*
X1100053D01*
X1100117Y18783D01*
G02Y18218I-283J-283D01*
G03X1102435Y16331I1064J-1060D01*
G01X1104769D01*
X1105700Y15400D01*
Y14200D01*
X1105121Y13621D01*
X1103031D01*
X1102700Y13290D01*
G37*
G36*
G01X1101164Y45257D02*
X1097907D01*
X1095828Y47336D01*
X1095813Y47379D01*
G03X1095792Y47437I-1328J-448D01*
G01X1095778Y47472D01*
Y54213D01*
X1098208Y56643D01*
X1099429D01*
X1099640Y56432D01*
Y54201D01*
X1100470Y53371D01*
X1102037D01*
X1102880Y54214D01*
X1104486D01*
X1105200Y53500D01*
Y51500D01*
X1105100Y51400D01*
X1103800D01*
X1103700Y51300D01*
Y51238D01*
X1102962Y50500D01*
Y50376D01*
X1102934Y50329D01*
G03X1102962Y48754I1293J-765D01*
G01Y47055D01*
X1101164Y45257D01*
G37*
G36*
G01X1098144Y180302D02*
X1098709Y180797D01*
X1098992Y180514D01*
X1098497Y179949D01*
X1098356Y179807D01*
X1098002Y180161D01*
X1098144Y180302D01*
G37*
G36*
G01X1096305Y182141D02*
X1096871Y182636D01*
X1097154Y182353D01*
X1096659Y181787D01*
X1096517Y181646D01*
X1096164Y181999D01*
X1096305Y182141D01*
G37*
G36*
G01X1099982Y178464D02*
X1100548Y178959D01*
X1100831Y178676D01*
X1100336Y178110D01*
X1100194Y177969D01*
X1099841Y178322D01*
X1099982Y178464D01*
G37*
G36*
G01X1101820Y176625D02*
X1102386Y177120D01*
X1102669Y176838D01*
X1102174Y176272D01*
X1102033Y176130D01*
X1101679Y176484D01*
X1101820Y176625D01*
G37*
G36*
G01X1103659Y174787D02*
X1104225Y175282D01*
X1104507Y174999D01*
X1104013Y174433D01*
X1103871Y174292D01*
X1103518Y174645D01*
X1103659Y174787D01*
G37*
G36*
G01X1105497Y172948D02*
X1106063Y173443D01*
X1106346Y173161D01*
X1105851Y172595D01*
X1105710Y172453D01*
X1105356Y172807D01*
X1105497Y172948D01*
G37*
G36*
G01X1099133Y178747D02*
X1098568Y178252D01*
X1098285Y178535D01*
X1098780Y179100D01*
X1098921Y179242D01*
X1099275Y178888D01*
X1099133Y178747D01*
G37*
G36*
G01X1097295Y180585D02*
X1096729Y180090D01*
X1096446Y180373D01*
X1096941Y180939D01*
X1097083Y181080D01*
X1097436Y180727D01*
X1097295Y180585D01*
G37*
G36*
G01X1100972Y176908D02*
X1100406Y176413D01*
X1100123Y176696D01*
X1100618Y177262D01*
X1100760Y177403D01*
X1101113Y177050D01*
X1100972Y176908D01*
G37*
G36*
G01X1102810Y175070D02*
X1102245Y174575D01*
X1101962Y174858D01*
X1102457Y175423D01*
X1102598Y175565D01*
X1102952Y175211D01*
X1102810Y175070D01*
G37*
G36*
G01X1104649Y173231D02*
X1104083Y172736D01*
X1103800Y173019D01*
X1104295Y173585D01*
X1104437Y173726D01*
X1104790Y173373D01*
X1104649Y173231D01*
G37*
G36*
G01X1106487Y171393D02*
X1105922Y170898D01*
X1105639Y171181D01*
X1106134Y171746D01*
X1106275Y171888D01*
X1106629Y171534D01*
X1106487Y171393D01*
G37*
G36*
G01X1107850Y168878D02*
X1108600Y168828D01*
Y168428D01*
X1107850Y168378D01*
X1107650D01*
Y168878D01*
X1107850D01*
G37*
G36*
G01Y166278D02*
X1108600Y166228D01*
Y165828D01*
X1107850Y165778D01*
X1107650D01*
Y166278D01*
X1107850D01*
G37*
G36*
G01X1107450Y167078D02*
X1106700Y167128D01*
Y167528D01*
X1107450Y167578D01*
X1107650D01*
Y167078D01*
X1107450D01*
G37*
G36*
G01Y164478D02*
X1106700Y164528D01*
Y164928D01*
X1107450Y164978D01*
X1107650D01*
Y164478D01*
X1107450D01*
G37*
G36*
G01X1095563Y185076D02*
X1096129Y185571D01*
X1096412Y185288D01*
X1095917Y184722D01*
X1095775Y184581D01*
X1095422Y184934D01*
X1095563Y185076D01*
G37*
G36*
G01X1104755Y175883D02*
X1105321Y176378D01*
X1105604Y176096D01*
X1105109Y175530D01*
X1104968Y175388D01*
X1104614Y175742D01*
X1104755Y175883D01*
G37*
G36*
G01X1106594Y174045D02*
X1107160Y174540D01*
X1107442Y174257D01*
X1106947Y173691D01*
X1106806Y173550D01*
X1106453Y173903D01*
X1106594Y174045D01*
G37*
G36*
G01X1102917Y177722D02*
X1103483Y178217D01*
X1103766Y177934D01*
X1103271Y177368D01*
X1103129Y177227D01*
X1102776Y177580D01*
X1102917Y177722D01*
G37*
G36*
G01X1101078Y179560D02*
X1101644Y180055D01*
X1101927Y179772D01*
X1101432Y179207D01*
X1101291Y179065D01*
X1100937Y179419D01*
X1101078Y179560D01*
G37*
G36*
G01X1099240Y181399D02*
X1099806Y181894D01*
X1100089Y181611D01*
X1099594Y181045D01*
X1099452Y180904D01*
X1099099Y181257D01*
X1099240Y181399D01*
G37*
G36*
G01X1097402Y183237D02*
X1097967Y183732D01*
X1098250Y183449D01*
X1097755Y182884D01*
X1097614Y182742D01*
X1097260Y183096D01*
X1097402Y183237D01*
G37*
G36*
G01X1103907Y176166D02*
X1103341Y175671D01*
X1103058Y175954D01*
X1103553Y176520D01*
X1103695Y176661D01*
X1104048Y176308D01*
X1103907Y176166D01*
G37*
G36*
G01X1105745Y174328D02*
X1105180Y173833D01*
X1104897Y174116D01*
X1105392Y174681D01*
X1105533Y174823D01*
X1105887Y174469D01*
X1105745Y174328D01*
G37*
G36*
G01X1102068Y178005D02*
X1101503Y177510D01*
X1101220Y177793D01*
X1101715Y178358D01*
X1101856Y178500D01*
X1102210Y178146D01*
X1102068Y178005D01*
G37*
G36*
G01X1100230Y179843D02*
X1099664Y179348D01*
X1099381Y179631D01*
X1099876Y180197D01*
X1100018Y180338D01*
X1100371Y179985D01*
X1100230Y179843D01*
G37*
G36*
G01X1098391Y181682D02*
X1097826Y181187D01*
X1097543Y181470D01*
X1098038Y182035D01*
X1098179Y182177D01*
X1098533Y181823D01*
X1098391Y181682D01*
G37*
G36*
G01X1096553Y183520D02*
X1095987Y183025D01*
X1095704Y183308D01*
X1096199Y183874D01*
X1096341Y184015D01*
X1096694Y183662D01*
X1096553Y183520D01*
G37*
G36*
G01X1108432Y172206D02*
X1108998Y172701D01*
X1109281Y172419D01*
X1108786Y171853D01*
X1108645Y171711D01*
X1108291Y172065D01*
X1108432Y172206D01*
G37*
G36*
G01X1107584Y172489D02*
X1107018Y171994D01*
X1106735Y172277D01*
X1107230Y172843D01*
X1107372Y172984D01*
X1107725Y172631D01*
X1107584Y172489D01*
G37*
G36*
G01X1109400Y166278D02*
X1110150Y166228D01*
Y165828D01*
X1109400Y165778D01*
X1109200D01*
Y166278D01*
X1109400D01*
G37*
G36*
G01Y168878D02*
X1110150Y168828D01*
Y168428D01*
X1109400Y168378D01*
X1109200D01*
Y168878D01*
X1109400D01*
G37*
G36*
G01X1109000Y164478D02*
X1108250Y164528D01*
Y164928D01*
X1109000Y164978D01*
X1109200D01*
Y164478D01*
X1109000D01*
G37*
G36*
G01Y167078D02*
X1108250Y167128D01*
Y167528D01*
X1109000Y167578D01*
X1109200D01*
Y167078D01*
X1109000D01*
G37*
G36*
G01Y169678D02*
X1108250Y169728D01*
Y170128D01*
X1109000Y170178D01*
X1109200D01*
Y169678D01*
X1109000D01*
G37*
G36*
G01X1106067Y189357D02*
X1105501Y188862D01*
X1105218Y189145D01*
X1105713Y189711D01*
X1105855Y189852D01*
X1106208Y189499D01*
X1106067Y189357D01*
G37*
G36*
G01X1105606Y191652D02*
X1106356Y191602D01*
Y191202D01*
X1105606Y191152D01*
X1105406D01*
Y191652D01*
X1105606D01*
G37*
G36*
G01X1105206Y192452D02*
X1104456Y192502D01*
Y192902D01*
X1105206Y192952D01*
X1105406D01*
Y192452D01*
X1105206D01*
G37*
G36*
G01X1105758Y203957D02*
X1105004Y204012D01*
X1104659Y204810D01*
X1105135Y205398D01*
X1105295Y205467D01*
X1105919Y204027D01*
X1105758Y203957D01*
G37*
G36*
G01X1114269Y181720D02*
X1114835Y182215D01*
X1115118Y181933D01*
X1114623Y181367D01*
X1114482Y181225D01*
X1114128Y181579D01*
X1114269Y181720D01*
G37*
G36*
G01X1112431Y183559D02*
X1112997Y184054D01*
X1113279Y183771D01*
X1112785Y183205D01*
X1112643Y183064D01*
X1112290Y183417D01*
X1112431Y183559D01*
G37*
G36*
G01X1110592Y185397D02*
X1111158Y185892D01*
X1111441Y185610D01*
X1110946Y185044D01*
X1110805Y184902D01*
X1110451Y185256D01*
X1110592Y185397D01*
G37*
G36*
G01X1108754Y187236D02*
X1109320Y187731D01*
X1109603Y187448D01*
X1109108Y186882D01*
X1108966Y186741D01*
X1108613Y187094D01*
X1108754Y187236D01*
G37*
G36*
G01X1106916Y189074D02*
X1107481Y189569D01*
X1107764Y189286D01*
X1107269Y188721D01*
X1107128Y188579D01*
X1106774Y188933D01*
X1106916Y189074D01*
G37*
G36*
G01X1116108Y179882D02*
X1116674Y180377D01*
X1116956Y180094D01*
X1116461Y179528D01*
X1116320Y179387D01*
X1115966Y179741D01*
X1116108Y179882D01*
G37*
G36*
G01X1117946Y178043D02*
X1118512Y178538D01*
X1118795Y178256D01*
X1118300Y177690D01*
X1118159Y177548D01*
X1117805Y177902D01*
X1117946Y178043D01*
G37*
G36*
G01X1119785Y176205D02*
X1120351Y176700D01*
X1120633Y176417D01*
X1120138Y175851D01*
X1119997Y175710D01*
X1119643Y176064D01*
X1119785Y176205D01*
G37*
G36*
G01X1121623Y174367D02*
X1122189Y174861D01*
X1122472Y174579D01*
X1121977Y174013D01*
X1121835Y173872D01*
X1121482Y174225D01*
X1121623Y174367D01*
G37*
G36*
G01X1115259Y180165D02*
X1114694Y179670D01*
X1114411Y179953D01*
X1114906Y180518D01*
X1115047Y180660D01*
X1115401Y180306D01*
X1115259Y180165D01*
G37*
G36*
G01X1113421Y182003D02*
X1112855Y181508D01*
X1112572Y181791D01*
X1113067Y182357D01*
X1113209Y182498D01*
X1113562Y182145D01*
X1113421Y182003D01*
G37*
G36*
G01X1111582Y183842D02*
X1111017Y183347D01*
X1110734Y183630D01*
X1111229Y184195D01*
X1111370Y184337D01*
X1111724Y183983D01*
X1111582Y183842D01*
G37*
G36*
G01X1109744Y185680D02*
X1109178Y185185D01*
X1108895Y185468D01*
X1109390Y186034D01*
X1109532Y186175D01*
X1109885Y185822D01*
X1109744Y185680D01*
G37*
G36*
G01X1107905Y187519D02*
X1107340Y187024D01*
X1107057Y187307D01*
X1107552Y187872D01*
X1107693Y188014D01*
X1108047Y187660D01*
X1107905Y187519D01*
G37*
G36*
G01X1117098Y178326D02*
X1116532Y177831D01*
X1116249Y178114D01*
X1116744Y178680D01*
X1116886Y178821D01*
X1117239Y178468D01*
X1117098Y178326D01*
G37*
G36*
G01X1118936Y176488D02*
X1118371Y175993D01*
X1118088Y176276D01*
X1118583Y176841D01*
X1118724Y176983D01*
X1119078Y176629D01*
X1118936Y176488D01*
G37*
G36*
G01X1120775Y174649D02*
X1120209Y174154D01*
X1119926Y174437D01*
X1120421Y175003D01*
X1120563Y175144D01*
X1120916Y174791D01*
X1120775Y174649D01*
G37*
G36*
G01X1123462Y172528D02*
X1124028Y173023D01*
X1124310Y172740D01*
X1123815Y172174D01*
X1123674Y172033D01*
X1123320Y172387D01*
X1123462Y172528D01*
G37*
G36*
G01X1125300Y170690D02*
X1125866Y171185D01*
X1126149Y170902D01*
X1125654Y170336D01*
X1125512Y170195D01*
X1125159Y170548D01*
X1125300Y170690D01*
G37*
G36*
G01X1122613Y172811D02*
X1122048Y172316D01*
X1121765Y172599D01*
X1122260Y173164D01*
X1122401Y173306D01*
X1122755Y172952D01*
X1122613Y172811D01*
G37*
G36*
G01X1124452Y170972D02*
X1123886Y170477D01*
X1123603Y170760D01*
X1124098Y171326D01*
X1124240Y171467D01*
X1124593Y171114D01*
X1124452Y170972D01*
G37*
G36*
G01X1126290Y169134D02*
X1125725Y168639D01*
X1125442Y168922D01*
X1125937Y169487D01*
X1126078Y169629D01*
X1126432Y169275D01*
X1126290Y169134D01*
G37*
G36*
G01X1127139Y168851D02*
X1127704Y169346D01*
X1127987Y169063D01*
X1127492Y168498D01*
X1127351Y168356D01*
X1126997Y168710D01*
X1127139Y168851D01*
G37*
G36*
G01X1128129Y167296D02*
X1127564Y166801D01*
X1127281Y167084D01*
X1127776Y167649D01*
X1127917Y167791D01*
X1128271Y167437D01*
X1128129Y167296D01*
G37*
G36*
G01X1128978Y167013D02*
X1129543Y167508D01*
X1129826Y167225D01*
X1129331Y166660D01*
X1129190Y166518D01*
X1128836Y166872D01*
X1128978Y167013D01*
G37*
G36*
G01X1108012Y190171D02*
X1108578Y190666D01*
X1108861Y190383D01*
X1108366Y189817D01*
X1108224Y189676D01*
X1107871Y190029D01*
X1108012Y190171D01*
G37*
G36*
G01X1106756Y192452D02*
X1106006Y192502D01*
Y192902D01*
X1106756Y192952D01*
X1106956D01*
Y192452D01*
X1106756D01*
G37*
G36*
G01X1105519Y209291D02*
X1106273Y209236D01*
X1106619Y208438D01*
X1106144Y207850D01*
X1105983Y207781D01*
X1105359Y209221D01*
X1105519Y209291D01*
G37*
G36*
G01X1119043Y179140D02*
X1119609Y179635D01*
X1119891Y179352D01*
X1119396Y178786D01*
X1119255Y178645D01*
X1118901Y178999D01*
X1119043Y179140D01*
G37*
G36*
G01X1120881Y177301D02*
X1121447Y177796D01*
X1121730Y177514D01*
X1121235Y176948D01*
X1121093Y176807D01*
X1120740Y177160D01*
X1120881Y177301D01*
G37*
G36*
G01X1122720Y175463D02*
X1123286Y175958D01*
X1123568Y175675D01*
X1123073Y175109D01*
X1122932Y174968D01*
X1122578Y175322D01*
X1122720Y175463D01*
G37*
G36*
G01X1124558Y173625D02*
X1125124Y174120D01*
X1125407Y173837D01*
X1124912Y173271D01*
X1124770Y173130D01*
X1124417Y173483D01*
X1124558Y173625D01*
G37*
G36*
G01X1117204Y180978D02*
X1117770Y181473D01*
X1118053Y181191D01*
X1117558Y180625D01*
X1117417Y180483D01*
X1117063Y180837D01*
X1117204Y180978D01*
G37*
G36*
G01X1115366Y182817D02*
X1115932Y183312D01*
X1116214Y183029D01*
X1115719Y182463D01*
X1115578Y182322D01*
X1115225Y182675D01*
X1115366Y182817D01*
G37*
G36*
G01X1113527Y184655D02*
X1114093Y185150D01*
X1114376Y184868D01*
X1113881Y184302D01*
X1113740Y184160D01*
X1113386Y184514D01*
X1113527Y184655D01*
G37*
G36*
G01X1111689Y186494D02*
X1112255Y186989D01*
X1112538Y186706D01*
X1112043Y186140D01*
X1111901Y185999D01*
X1111548Y186352D01*
X1111689Y186494D01*
G37*
G36*
G01X1109850Y188332D02*
X1110416Y188827D01*
X1110699Y188544D01*
X1110204Y187979D01*
X1110063Y187837D01*
X1109709Y188191D01*
X1109850Y188332D01*
G37*
G36*
G01X1120033Y177584D02*
X1119467Y177089D01*
X1119184Y177372D01*
X1119679Y177938D01*
X1119821Y178079D01*
X1120174Y177726D01*
X1120033Y177584D01*
G37*
G36*
G01X1121871Y175746D02*
X1121306Y175251D01*
X1121023Y175534D01*
X1121518Y176099D01*
X1121659Y176241D01*
X1122013Y175887D01*
X1121871Y175746D01*
G37*
G36*
G01X1123710Y173907D02*
X1123144Y173412D01*
X1122861Y173695D01*
X1123356Y174261D01*
X1123498Y174402D01*
X1123851Y174049D01*
X1123710Y173907D01*
G37*
G36*
G01X1118194Y179423D02*
X1117629Y178928D01*
X1117346Y179211D01*
X1117841Y179776D01*
X1117982Y179918D01*
X1118336Y179564D01*
X1118194Y179423D01*
G37*
G36*
G01X1116356Y181261D02*
X1115790Y180766D01*
X1115507Y181049D01*
X1116002Y181615D01*
X1116144Y181756D01*
X1116497Y181403D01*
X1116356Y181261D01*
G37*
G36*
G01X1114517Y183100D02*
X1113952Y182605D01*
X1113669Y182888D01*
X1114164Y183453D01*
X1114305Y183595D01*
X1114659Y183241D01*
X1114517Y183100D01*
G37*
G36*
G01X1112679Y184938D02*
X1112113Y184443D01*
X1111830Y184726D01*
X1112325Y185292D01*
X1112467Y185433D01*
X1112820Y185080D01*
X1112679Y184938D01*
G37*
G36*
G01X1110840Y186777D02*
X1110275Y186282D01*
X1109992Y186565D01*
X1110487Y187130D01*
X1110628Y187272D01*
X1110982Y186918D01*
X1110840Y186777D01*
G37*
G36*
G01X1109002Y188615D02*
X1108436Y188120D01*
X1108153Y188403D01*
X1108648Y188969D01*
X1108790Y189110D01*
X1109143Y188757D01*
X1109002Y188615D01*
G37*
G36*
G01X1126397Y171786D02*
X1126962Y172281D01*
X1127245Y171998D01*
X1126750Y171432D01*
X1126609Y171291D01*
X1126255Y171645D01*
X1126397Y171786D01*
G37*
G36*
G01X1125548Y172069D02*
X1124983Y171574D01*
X1124700Y171857D01*
X1125195Y172422D01*
X1125336Y172564D01*
X1125690Y172210D01*
X1125548Y172069D01*
G37*
G36*
G01X1128235Y169948D02*
X1128801Y170443D01*
X1129084Y170160D01*
X1128589Y169594D01*
X1128447Y169453D01*
X1128094Y169806D01*
X1128235Y169948D01*
G37*
G36*
G01X1127387Y170230D02*
X1126821Y169735D01*
X1126538Y170018D01*
X1127033Y170584D01*
X1127175Y170725D01*
X1127528Y170372D01*
X1127387Y170230D01*
G37*
G36*
G01X1130074Y168110D02*
X1130640Y168605D01*
X1130923Y168322D01*
X1130428Y167756D01*
X1130286Y167615D01*
X1129933Y167968D01*
X1130074Y168110D01*
G37*
G36*
G01X1129226Y168392D02*
X1128660Y167897D01*
X1128377Y168180D01*
X1128872Y168746D01*
X1129014Y168887D01*
X1129367Y168534D01*
X1129226Y168392D01*
G37*
G36*
G01X1096940Y176554D02*
X1096375Y176059D01*
X1096092Y176342D01*
X1096587Y176907D01*
X1096728Y177049D01*
X1097082Y176695D01*
X1096940Y176554D01*
G37*
G36*
G01X1098779Y174715D02*
X1098213Y174220D01*
X1097930Y174503D01*
X1098425Y175069D01*
X1098567Y175210D01*
X1098920Y174857D01*
X1098779Y174715D01*
G37*
G36*
G01X1095951Y178109D02*
X1096516Y178604D01*
X1096799Y178321D01*
X1096304Y177756D01*
X1096163Y177614D01*
X1095809Y177968D01*
X1095951Y178109D01*
G37*
G36*
G01X1097789Y176271D02*
X1098355Y176766D01*
X1098638Y176483D01*
X1098143Y175917D01*
X1098001Y175776D01*
X1097648Y176129D01*
X1097789Y176271D01*
G37*
G36*
G01X1099627Y174432D02*
X1100193Y174927D01*
X1100476Y174645D01*
X1099981Y174079D01*
X1099840Y173937D01*
X1099486Y174291D01*
X1099627Y174432D01*
G37*
G36*
G01X1100617Y172877D02*
X1100052Y172382D01*
X1099769Y172665D01*
X1100264Y173230D01*
X1100405Y173372D01*
X1100759Y173018D01*
X1100617Y172877D01*
G37*
G36*
G01X1102456Y171038D02*
X1101890Y170543D01*
X1101607Y170826D01*
X1102102Y171392D01*
X1102244Y171533D01*
X1102597Y171180D01*
X1102456Y171038D01*
G37*
G36*
G01X1101466Y172594D02*
X1102032Y173089D01*
X1102314Y172806D01*
X1101820Y172240D01*
X1101678Y172099D01*
X1101325Y172452D01*
X1101466Y172594D01*
G37*
G36*
G01X1103304Y170755D02*
X1103870Y171250D01*
X1104153Y170968D01*
X1103658Y170402D01*
X1103517Y170260D01*
X1103163Y170614D01*
X1103304Y170755D01*
G37*
G36*
G01X1104350Y167078D02*
X1103600Y167128D01*
Y167528D01*
X1104350Y167578D01*
X1104550D01*
Y167078D01*
X1104350D01*
G37*
G36*
G01Y164478D02*
X1103600Y164528D01*
Y164928D01*
X1104350Y164978D01*
X1104550D01*
Y164478D01*
X1104350D01*
G37*
G36*
G01X1104750Y168878D02*
X1105500Y168828D01*
Y168428D01*
X1104750Y168378D01*
X1104550D01*
Y168878D01*
X1104750D01*
G37*
G36*
G01Y166278D02*
X1105500Y166228D01*
Y165828D01*
X1104750Y165778D01*
X1104550D01*
Y166278D01*
X1104750D01*
G37*
G36*
G01X1095209Y181044D02*
X1095774Y181539D01*
X1096057Y181256D01*
X1095562Y180691D01*
X1095421Y180549D01*
X1095067Y180903D01*
X1095209Y181044D01*
G37*
G36*
G01X1096198Y179489D02*
X1095633Y178994D01*
X1095350Y179277D01*
X1095845Y179842D01*
X1095986Y179984D01*
X1096340Y179630D01*
X1096198Y179489D01*
G37*
G36*
G01X1100724Y175529D02*
X1101290Y176024D01*
X1101573Y175741D01*
X1101078Y175175D01*
X1100936Y175034D01*
X1100583Y175387D01*
X1100724Y175529D01*
G37*
G36*
G01X1102562Y173690D02*
X1103128Y174185D01*
X1103411Y173903D01*
X1102916Y173337D01*
X1102775Y173195D01*
X1102421Y173549D01*
X1102562Y173690D01*
G37*
G36*
G01X1098885Y177367D02*
X1099451Y177862D01*
X1099734Y177579D01*
X1099239Y177014D01*
X1099098Y176872D01*
X1098744Y177226D01*
X1098885Y177367D01*
G37*
G36*
G01X1097047Y179206D02*
X1097613Y179701D01*
X1097896Y179418D01*
X1097401Y178852D01*
X1097259Y178711D01*
X1096906Y179064D01*
X1097047Y179206D01*
G37*
G36*
G01X1101714Y173973D02*
X1101148Y173478D01*
X1100865Y173761D01*
X1101360Y174327D01*
X1101502Y174468D01*
X1101855Y174115D01*
X1101714Y173973D01*
G37*
G36*
G01X1099875Y175812D02*
X1099310Y175317D01*
X1099027Y175600D01*
X1099522Y176165D01*
X1099663Y176307D01*
X1100017Y175953D01*
X1099875Y175812D01*
G37*
G36*
G01X1098037Y177650D02*
X1097471Y177155D01*
X1097188Y177438D01*
X1097683Y178004D01*
X1097825Y178145D01*
X1098178Y177792D01*
X1098037Y177650D01*
G37*
G36*
G01X1104401Y171852D02*
X1104967Y172347D01*
X1105249Y172064D01*
X1104754Y171498D01*
X1104613Y171357D01*
X1104260Y171710D01*
X1104401Y171852D01*
G37*
G36*
G01X1103552Y172135D02*
X1102987Y171640D01*
X1102704Y171923D01*
X1103199Y172488D01*
X1103340Y172630D01*
X1103694Y172276D01*
X1103552Y172135D01*
G37*
G36*
G01X1105391Y170296D02*
X1104825Y169801D01*
X1104542Y170084D01*
X1105037Y170650D01*
X1105179Y170791D01*
X1105532Y170438D01*
X1105391Y170296D01*
G37*
G36*
G01X1106300Y163678D02*
X1107050Y163628D01*
Y163228D01*
X1106300Y163178D01*
X1106100D01*
Y163678D01*
X1106300D01*
G37*
G36*
G01Y166278D02*
X1107050Y166228D01*
Y165828D01*
X1106300Y165778D01*
X1106100D01*
Y166278D01*
X1106300D01*
G37*
G36*
G01Y168878D02*
X1107050Y168828D01*
Y168428D01*
X1106300Y168378D01*
X1106100D01*
Y168878D01*
X1106300D01*
G37*
G36*
G01X1105900Y164478D02*
X1105150Y164528D01*
Y164928D01*
X1105900Y164978D01*
X1106100D01*
Y164478D01*
X1105900D01*
G37*
G36*
G01Y167078D02*
X1105150Y167128D01*
Y167528D01*
X1105900Y167578D01*
X1106100D01*
Y167078D01*
X1105900D01*
G37*
G36*
G01X1102506Y191652D02*
X1103256Y191602D01*
Y191202D01*
X1102506Y191152D01*
X1102306D01*
Y191652D01*
X1102506D01*
G37*
G36*
G01Y194252D02*
X1103256Y194202D01*
Y193802D01*
X1102506Y193752D01*
X1102306D01*
Y194252D01*
X1102506D01*
G37*
G36*
G01X1102106Y189852D02*
X1101356Y189902D01*
Y190302D01*
X1102106Y190352D01*
X1102306D01*
Y189852D01*
X1102106D01*
G37*
G36*
G01Y192452D02*
X1101356Y192502D01*
Y192902D01*
X1102106Y192952D01*
X1102306D01*
Y192452D01*
X1102106D01*
G37*
G36*
G01X1101831Y201259D02*
X1101161Y201609D01*
Y202479D01*
X1101831Y202829D01*
X1102006D01*
Y201259D01*
X1101831D01*
G37*
G36*
G01Y197359D02*
X1101161Y197709D01*
Y198579D01*
X1101831Y198929D01*
X1102006D01*
Y197359D01*
X1101831D01*
G37*
G36*
G01X1115753Y175850D02*
X1116319Y176345D01*
X1116602Y176063D01*
X1116107Y175497D01*
X1115966Y175355D01*
X1115612Y175709D01*
X1115753Y175850D01*
G37*
G36*
G01X1117592Y174012D02*
X1118158Y174507D01*
X1118440Y174224D01*
X1117945Y173658D01*
X1117804Y173517D01*
X1117450Y173871D01*
X1117592Y174012D01*
G37*
G36*
G01X1113915Y177689D02*
X1114481Y178184D01*
X1114763Y177901D01*
X1114268Y177335D01*
X1114127Y177194D01*
X1113773Y177548D01*
X1113915Y177689D01*
G37*
G36*
G01X1112076Y179527D02*
X1112642Y180022D01*
X1112925Y179740D01*
X1112430Y179174D01*
X1112289Y179032D01*
X1111935Y179386D01*
X1112076Y179527D01*
G37*
G36*
G01X1110238Y181366D02*
X1110804Y181861D01*
X1111086Y181578D01*
X1110592Y181012D01*
X1110450Y180871D01*
X1110097Y181224D01*
X1110238Y181366D01*
G37*
G36*
G01X1108399Y183204D02*
X1108965Y183699D01*
X1109248Y183417D01*
X1108753Y182851D01*
X1108612Y182709D01*
X1108258Y183063D01*
X1108399Y183204D01*
G37*
G36*
G01X1106561Y185043D02*
X1107127Y185538D01*
X1107410Y185255D01*
X1106915Y184689D01*
X1106773Y184548D01*
X1106420Y184901D01*
X1106561Y185043D01*
G37*
G36*
G01X1104723Y186881D02*
X1105288Y187376D01*
X1105571Y187093D01*
X1105076Y186528D01*
X1104935Y186386D01*
X1104581Y186740D01*
X1104723Y186881D01*
G37*
G36*
G01X1102884Y188720D02*
X1103450Y189215D01*
X1103733Y188932D01*
X1103238Y188366D01*
X1103096Y188225D01*
X1102743Y188578D01*
X1102884Y188720D01*
G37*
G36*
G01X1114905Y176133D02*
X1114339Y175638D01*
X1114056Y175921D01*
X1114551Y176487D01*
X1114693Y176628D01*
X1115046Y176275D01*
X1114905Y176133D01*
G37*
G36*
G01X1116743Y174295D02*
X1116178Y173800D01*
X1115895Y174083D01*
X1116390Y174648D01*
X1116531Y174790D01*
X1116885Y174436D01*
X1116743Y174295D01*
G37*
G36*
G01X1113066Y177972D02*
X1112501Y177477D01*
X1112218Y177760D01*
X1112713Y178325D01*
X1112854Y178467D01*
X1113208Y178113D01*
X1113066Y177972D01*
G37*
G36*
G01X1111228Y179810D02*
X1110662Y179315D01*
X1110379Y179598D01*
X1110874Y180164D01*
X1111016Y180305D01*
X1111369Y179952D01*
X1111228Y179810D01*
G37*
G36*
G01X1109389Y181649D02*
X1108824Y181154D01*
X1108541Y181437D01*
X1109036Y182002D01*
X1109177Y182144D01*
X1109531Y181790D01*
X1109389Y181649D01*
G37*
G36*
G01X1107551Y183487D02*
X1106985Y182992D01*
X1106702Y183275D01*
X1107197Y183841D01*
X1107339Y183982D01*
X1107692Y183629D01*
X1107551Y183487D01*
G37*
G36*
G01X1105712Y185326D02*
X1105147Y184831D01*
X1104864Y185114D01*
X1105359Y185679D01*
X1105500Y185821D01*
X1105854Y185467D01*
X1105712Y185326D01*
G37*
G36*
G01X1103874Y187164D02*
X1103308Y186669D01*
X1103025Y186952D01*
X1103520Y187518D01*
X1103662Y187659D01*
X1104015Y187306D01*
X1103874Y187164D01*
G37*
G36*
G01X1119430Y172174D02*
X1119996Y172668D01*
X1120279Y172386D01*
X1119784Y171820D01*
X1119642Y171679D01*
X1119289Y172032D01*
X1119430Y172174D01*
G37*
G36*
G01X1121269Y170335D02*
X1121835Y170830D01*
X1122117Y170547D01*
X1121622Y169981D01*
X1121481Y169840D01*
X1121127Y170194D01*
X1121269Y170335D01*
G37*
G36*
G01X1123107Y168497D02*
X1123673Y168992D01*
X1123956Y168709D01*
X1123461Y168143D01*
X1123319Y168002D01*
X1122966Y168355D01*
X1123107Y168497D01*
G37*
G36*
G01X1118582Y172456D02*
X1118016Y171961D01*
X1117733Y172244D01*
X1118228Y172810D01*
X1118370Y172951D01*
X1118723Y172598D01*
X1118582Y172456D01*
G37*
G36*
G01X1120420Y170618D02*
X1119855Y170123D01*
X1119572Y170406D01*
X1120067Y170971D01*
X1120208Y171113D01*
X1120562Y170759D01*
X1120420Y170618D01*
G37*
G36*
G01X1124945Y166658D02*
X1125511Y167153D01*
X1125794Y166870D01*
X1125299Y166304D01*
X1125157Y166163D01*
X1124804Y166516D01*
X1124945Y166658D01*
G37*
G36*
G01X1104056Y194252D02*
X1104806Y194202D01*
Y193802D01*
X1104056Y193752D01*
X1103856D01*
Y194252D01*
X1104056D01*
G37*
G36*
G01Y191652D02*
X1104806Y191602D01*
Y191202D01*
X1104056Y191152D01*
X1103856D01*
Y191652D01*
X1104056D01*
G37*
G36*
G01X1103656Y192452D02*
X1102906Y192502D01*
Y192902D01*
X1103656Y192952D01*
X1103856D01*
Y192452D01*
X1103656D01*
G37*
G36*
G01X1102931Y201140D02*
X1103601Y200790D01*
Y199920D01*
X1102931Y199570D01*
X1102756D01*
Y201140D01*
X1102931D01*
G37*
G36*
G01X1103242Y205301D02*
X1103912Y204951D01*
Y204081D01*
X1103242Y203731D01*
X1103067D01*
Y205301D01*
X1103242D01*
G37*
G36*
G01Y209182D02*
X1103912Y208832D01*
Y207962D01*
X1103242Y207612D01*
X1103067D01*
Y209182D01*
X1103242D01*
G37*
G36*
G01X1113173Y180624D02*
X1113739Y181119D01*
X1114021Y180836D01*
X1113526Y180270D01*
X1113385Y180129D01*
X1113032Y180482D01*
X1113173Y180624D01*
G37*
G36*
G01X1111334Y182462D02*
X1111900Y182957D01*
X1112183Y182675D01*
X1111688Y182109D01*
X1111547Y181967D01*
X1111193Y182321D01*
X1111334Y182462D01*
G37*
G36*
G01X1109496Y184301D02*
X1110062Y184796D01*
X1110345Y184513D01*
X1109850Y183947D01*
X1109708Y183806D01*
X1109355Y184159D01*
X1109496Y184301D01*
G37*
G36*
G01X1107657Y186139D02*
X1108223Y186634D01*
X1108506Y186351D01*
X1108011Y185786D01*
X1107870Y185644D01*
X1107516Y185998D01*
X1107657Y186139D01*
G37*
G36*
G01X1105819Y187978D02*
X1106385Y188473D01*
X1106668Y188190D01*
X1106173Y187624D01*
X1106031Y187483D01*
X1105678Y187836D01*
X1105819Y187978D01*
G37*
G36*
G01X1115011Y178785D02*
X1115577Y179280D01*
X1115860Y178998D01*
X1115365Y178432D01*
X1115224Y178290D01*
X1114870Y178644D01*
X1115011Y178785D01*
G37*
G36*
G01X1116850Y176947D02*
X1117416Y177442D01*
X1117698Y177159D01*
X1117203Y176593D01*
X1117062Y176452D01*
X1116708Y176806D01*
X1116850Y176947D01*
G37*
G36*
G01X1118688Y175108D02*
X1119254Y175603D01*
X1119537Y175321D01*
X1119042Y174755D01*
X1118900Y174614D01*
X1118547Y174967D01*
X1118688Y175108D01*
G37*
G36*
G01X1120527Y173270D02*
X1121093Y173765D01*
X1121375Y173482D01*
X1120880Y172916D01*
X1120739Y172775D01*
X1120385Y173129D01*
X1120527Y173270D01*
G37*
G36*
G01X1114163Y179068D02*
X1113597Y178573D01*
X1113314Y178856D01*
X1113809Y179422D01*
X1113951Y179563D01*
X1114304Y179210D01*
X1114163Y179068D01*
G37*
G36*
G01X1112324Y180907D02*
X1111759Y180412D01*
X1111476Y180695D01*
X1111971Y181260D01*
X1112112Y181402D01*
X1112466Y181048D01*
X1112324Y180907D01*
G37*
G36*
G01X1110486Y182745D02*
X1109920Y182250D01*
X1109637Y182533D01*
X1110132Y183099D01*
X1110274Y183240D01*
X1110627Y182887D01*
X1110486Y182745D01*
G37*
G36*
G01X1108647Y184584D02*
X1108082Y184089D01*
X1107799Y184372D01*
X1108294Y184937D01*
X1108435Y185079D01*
X1108789Y184725D01*
X1108647Y184584D01*
G37*
G36*
G01X1106809Y186422D02*
X1106243Y185927D01*
X1105960Y186210D01*
X1106455Y186776D01*
X1106597Y186917D01*
X1106950Y186564D01*
X1106809Y186422D01*
G37*
G36*
G01X1104970Y188261D02*
X1104405Y187766D01*
X1104122Y188049D01*
X1104617Y188614D01*
X1104758Y188756D01*
X1105112Y188402D01*
X1104970Y188261D01*
G37*
G36*
G01X1116001Y177230D02*
X1115436Y176735D01*
X1115153Y177018D01*
X1115648Y177583D01*
X1115789Y177725D01*
X1116143Y177371D01*
X1116001Y177230D01*
G37*
G36*
G01X1117840Y175391D02*
X1117274Y174896D01*
X1116991Y175179D01*
X1117486Y175745D01*
X1117628Y175886D01*
X1117981Y175533D01*
X1117840Y175391D01*
G37*
G36*
G01X1119678Y173553D02*
X1119113Y173058D01*
X1118830Y173341D01*
X1119325Y173906D01*
X1119466Y174048D01*
X1119820Y173694D01*
X1119678Y173553D01*
G37*
G36*
G01X1122365Y171432D02*
X1122931Y171927D01*
X1123214Y171644D01*
X1122719Y171078D01*
X1122577Y170937D01*
X1122224Y171290D01*
X1122365Y171432D01*
G37*
G36*
G01X1124204Y169593D02*
X1124769Y170088D01*
X1125052Y169805D01*
X1124557Y169239D01*
X1124416Y169098D01*
X1124062Y169452D01*
X1124204Y169593D01*
G37*
G36*
G01X1121517Y171714D02*
X1120951Y171219D01*
X1120668Y171502D01*
X1121163Y172068D01*
X1121305Y172209D01*
X1121658Y171856D01*
X1121517Y171714D01*
G37*
G36*
G01X1123355Y169876D02*
X1122790Y169381D01*
X1122507Y169664D01*
X1123002Y170229D01*
X1123143Y170371D01*
X1123497Y170017D01*
X1123355Y169876D01*
G37*
G36*
G01X1125194Y168037D02*
X1124628Y167542D01*
X1124345Y167825D01*
X1124840Y168391D01*
X1124982Y168532D01*
X1125335Y168179D01*
X1125194Y168037D01*
G37*
G36*
G01X1126042Y167754D02*
X1126607Y168249D01*
X1126890Y167966D01*
X1126395Y167400D01*
X1126254Y167259D01*
X1125900Y167613D01*
X1126042Y167754D01*
G37*
G36*
G01X1118503Y190209D02*
X1119069Y190704D01*
X1119352Y190422D01*
X1118857Y189856D01*
X1118716Y189714D01*
X1118362Y190068D01*
X1118503Y190209D01*
G37*
G36*
G01X1116665Y192048D02*
X1117231Y192543D01*
X1117514Y192260D01*
X1117019Y191694D01*
X1116877Y191553D01*
X1116524Y191906D01*
X1116665Y192048D01*
G37*
G36*
G01X1114826Y193886D02*
X1115392Y194381D01*
X1115675Y194098D01*
X1115180Y193533D01*
X1115039Y193391D01*
X1114685Y193745D01*
X1114826Y193886D01*
G37*
G36*
G01X1117655Y190492D02*
X1117089Y189997D01*
X1116806Y190280D01*
X1117301Y190846D01*
X1117443Y190987D01*
X1117796Y190634D01*
X1117655Y190492D01*
G37*
G36*
G01X1115816Y192331D02*
X1115251Y191836D01*
X1114968Y192119D01*
X1115463Y192684D01*
X1115604Y192826D01*
X1115958Y192472D01*
X1115816Y192331D01*
G37*
G36*
G01X1113681Y196108D02*
X1113011Y196458D01*
Y197328D01*
X1113681Y197678D01*
X1113856D01*
Y196108D01*
X1113681D01*
G37*
G36*
G01Y200008D02*
X1113011Y200358D01*
Y201228D01*
X1113681Y201578D01*
X1113856D01*
Y200008D01*
X1113681D01*
G37*
G36*
G01X1124019Y184694D02*
X1124585Y185189D01*
X1124867Y184906D01*
X1124372Y184340D01*
X1124231Y184199D01*
X1123877Y184553D01*
X1124019Y184694D01*
G37*
G36*
G01X1125857Y182855D02*
X1126423Y183350D01*
X1126706Y183068D01*
X1126211Y182502D01*
X1126069Y182361D01*
X1125716Y182714D01*
X1125857Y182855D01*
G37*
G36*
G01X1122180Y186532D02*
X1122746Y187027D01*
X1123029Y186745D01*
X1122534Y186179D01*
X1122393Y186037D01*
X1122039Y186391D01*
X1122180Y186532D01*
G37*
G36*
G01X1120342Y188371D02*
X1120908Y188866D01*
X1121190Y188583D01*
X1120695Y188017D01*
X1120554Y187876D01*
X1120201Y188229D01*
X1120342Y188371D01*
G37*
G36*
G01X1125009Y183138D02*
X1124443Y182643D01*
X1124160Y182926D01*
X1124655Y183492D01*
X1124797Y183633D01*
X1125150Y183280D01*
X1125009Y183138D01*
G37*
G36*
G01X1126847Y181300D02*
X1126282Y180805D01*
X1125999Y181088D01*
X1126494Y181653D01*
X1126635Y181795D01*
X1126989Y181441D01*
X1126847Y181300D01*
G37*
G36*
G01X1123170Y184977D02*
X1122605Y184482D01*
X1122322Y184765D01*
X1122817Y185330D01*
X1122958Y185472D01*
X1123312Y185118D01*
X1123170Y184977D01*
G37*
G36*
G01X1121332Y186815D02*
X1120766Y186320D01*
X1120483Y186603D01*
X1120978Y187169D01*
X1121120Y187310D01*
X1121473Y186957D01*
X1121332Y186815D01*
G37*
G36*
G01X1119493Y188654D02*
X1118928Y188159D01*
X1118645Y188442D01*
X1119140Y189007D01*
X1119281Y189149D01*
X1119635Y188795D01*
X1119493Y188654D01*
G37*
G36*
G01X1127696Y181017D02*
X1128262Y181512D01*
X1128544Y181229D01*
X1128049Y180663D01*
X1127908Y180522D01*
X1127554Y180876D01*
X1127696Y181017D01*
G37*
G36*
G01X1129534Y179179D02*
X1130100Y179674D01*
X1130383Y179391D01*
X1129888Y178825D01*
X1129746Y178684D01*
X1129393Y179037D01*
X1129534Y179179D01*
G37*
G36*
G01X1128686Y179461D02*
X1128120Y178966D01*
X1127837Y179249D01*
X1128332Y179815D01*
X1128474Y179956D01*
X1128827Y179603D01*
X1128686Y179461D01*
G37*
G36*
G01X1146843Y177706D02*
X1146793Y176956D01*
X1146393D01*
X1146343Y177706D01*
Y177906D01*
X1146843D01*
Y177706D01*
G37*
G36*
G01X1149443D02*
X1149393Y176956D01*
X1148993D01*
X1148943Y177706D01*
Y177906D01*
X1149443D01*
Y177706D01*
G37*
G36*
G01X1152043D02*
X1151993Y176956D01*
X1151593D01*
X1151543Y177706D01*
Y177906D01*
X1152043D01*
Y177706D01*
G37*
G36*
G01X1144243D02*
X1144193Y176956D01*
X1143793D01*
X1143743Y177706D01*
Y177906D01*
X1144243D01*
Y177706D01*
G37*
G36*
G01X1141643D02*
X1141593Y176956D01*
X1141193D01*
X1141143Y177706D01*
Y177906D01*
X1141643D01*
Y177706D01*
G37*
G36*
G01X1139043D02*
X1138993Y176956D01*
X1138593D01*
X1138543Y177706D01*
Y177906D01*
X1139043D01*
Y177706D01*
G37*
G36*
G01X1136443D02*
X1136393Y176956D01*
X1135993D01*
X1135943Y177706D01*
Y177906D01*
X1136443D01*
Y177706D01*
G37*
G36*
G01X1133843D02*
X1133793Y176956D01*
X1133393D01*
X1133343Y177706D01*
Y177906D01*
X1133843D01*
Y177706D01*
G37*
G36*
G01X1145043Y178106D02*
X1145093Y178856D01*
X1145493D01*
X1145543Y178106D01*
Y177906D01*
X1145043D01*
Y178106D01*
G37*
G36*
G01X1147643D02*
X1147693Y178856D01*
X1148093D01*
X1148143Y178106D01*
Y177906D01*
X1147643D01*
Y178106D01*
G37*
G36*
G01X1150243D02*
X1150293Y178856D01*
X1150693D01*
X1150743Y178106D01*
Y177906D01*
X1150243D01*
Y178106D01*
G37*
G36*
G01X1142443D02*
X1142493Y178856D01*
X1142893D01*
X1142943Y178106D01*
Y177906D01*
X1142443D01*
Y178106D01*
G37*
G36*
G01X1139843D02*
X1139893Y178856D01*
X1140293D01*
X1140343Y178106D01*
Y177906D01*
X1139843D01*
Y178106D01*
G37*
G36*
G01X1137243D02*
X1137293Y178856D01*
X1137693D01*
X1137743Y178106D01*
Y177906D01*
X1137243D01*
Y178106D01*
G37*
G36*
G01X1132043D02*
X1132093Y178856D01*
X1132493D01*
X1132543Y178106D01*
Y177906D01*
X1132043D01*
Y178106D01*
G37*
G36*
G01X1154643Y177706D02*
X1154593Y176956D01*
X1154193D01*
X1154143Y177706D01*
Y177906D01*
X1154643D01*
Y177706D01*
G37*
G36*
G01X1152843Y178106D02*
X1152893Y178856D01*
X1153293D01*
X1153343Y178106D01*
Y177906D01*
X1152843D01*
Y178106D01*
G37*
G36*
G01X1155443D02*
X1155493Y178856D01*
X1155893D01*
X1155943Y178106D01*
Y177906D01*
X1155443D01*
Y178106D01*
G37*
G36*
G01X1134643D02*
X1134693Y178856D01*
X1135093D01*
X1135143Y178106D01*
Y177906D01*
X1134643D01*
Y178106D01*
G37*
G36*
G01X1121438Y189467D02*
X1122004Y189962D01*
X1122287Y189680D01*
X1121792Y189114D01*
X1121651Y188972D01*
X1121297Y189326D01*
X1121438Y189467D01*
G37*
G36*
G01X1119600Y191306D02*
X1120166Y191801D01*
X1120448Y191518D01*
X1119954Y190952D01*
X1119812Y190811D01*
X1119459Y191164D01*
X1119600Y191306D01*
G37*
G36*
G01X1120590Y189750D02*
X1120024Y189255D01*
X1119741Y189538D01*
X1120236Y190104D01*
X1120378Y190245D01*
X1120731Y189892D01*
X1120590Y189750D01*
G37*
G36*
G01X1118751Y191589D02*
X1118186Y191094D01*
X1117903Y191377D01*
X1118398Y191942D01*
X1118539Y192084D01*
X1118893Y191730D01*
X1118751Y191589D01*
G37*
G36*
G01X1116913Y193427D02*
X1116347Y192932D01*
X1116064Y193215D01*
X1116559Y193781D01*
X1116701Y193922D01*
X1117054Y193569D01*
X1116913Y193427D01*
G37*
G36*
G01X1114781Y201578D02*
X1115451Y201228D01*
Y200358D01*
X1114781Y200008D01*
X1114606D01*
Y201578D01*
X1114781D01*
G37*
G36*
G01Y197678D02*
X1115451Y197328D01*
Y196458D01*
X1114781Y196108D01*
X1114606D01*
Y197678D01*
X1114781D01*
G37*
G36*
G01X1125115Y185790D02*
X1125681Y186285D01*
X1125964Y186003D01*
X1125469Y185437D01*
X1125328Y185295D01*
X1124974Y185649D01*
X1125115Y185790D01*
G37*
G36*
G01X1123277Y187629D02*
X1123843Y188124D01*
X1124125Y187841D01*
X1123630Y187275D01*
X1123489Y187134D01*
X1123135Y187488D01*
X1123277Y187629D01*
G37*
G36*
G01X1126105Y184235D02*
X1125540Y183740D01*
X1125257Y184023D01*
X1125752Y184588D01*
X1125893Y184730D01*
X1126247Y184376D01*
X1126105Y184235D01*
G37*
G36*
G01X1124267Y186073D02*
X1123701Y185578D01*
X1123418Y185861D01*
X1123913Y186427D01*
X1124055Y186568D01*
X1124408Y186215D01*
X1124267Y186073D01*
G37*
G36*
G01X1122428Y187912D02*
X1121863Y187417D01*
X1121580Y187700D01*
X1122075Y188265D01*
X1122216Y188407D01*
X1122570Y188053D01*
X1122428Y187912D01*
G37*
G36*
G01X1126954Y183952D02*
X1127520Y184447D01*
X1127802Y184164D01*
X1127307Y183598D01*
X1127166Y183457D01*
X1126812Y183811D01*
X1126954Y183952D01*
G37*
G36*
G01X1128792Y182114D02*
X1129358Y182608D01*
X1129641Y182326D01*
X1129146Y181760D01*
X1129004Y181619D01*
X1128651Y181972D01*
X1128792Y182114D01*
G37*
G36*
G01X1130631Y180275D02*
X1131197Y180770D01*
X1131479Y180487D01*
X1130984Y179921D01*
X1130843Y179780D01*
X1130489Y180134D01*
X1130631Y180275D01*
G37*
G36*
G01X1127944Y182396D02*
X1127378Y181901D01*
X1127095Y182184D01*
X1127590Y182750D01*
X1127732Y182891D01*
X1128085Y182538D01*
X1127944Y182396D01*
G37*
G36*
G01X1129782Y180558D02*
X1129217Y180063D01*
X1128934Y180346D01*
X1129429Y180911D01*
X1129570Y181053D01*
X1129924Y180699D01*
X1129782Y180558D01*
G37*
G36*
G01X1146843Y179256D02*
X1146793Y178506D01*
X1146393D01*
X1146343Y179256D01*
Y179456D01*
X1146843D01*
Y179256D01*
G37*
G36*
G01X1149443D02*
X1149393Y178506D01*
X1148993D01*
X1148943Y179256D01*
Y179456D01*
X1149443D01*
Y179256D01*
G37*
G36*
G01X1152043D02*
X1151993Y178506D01*
X1151593D01*
X1151543Y179256D01*
Y179456D01*
X1152043D01*
Y179256D01*
G37*
G36*
G01X1144243D02*
X1144193Y178506D01*
X1143793D01*
X1143743Y179256D01*
Y179456D01*
X1144243D01*
Y179256D01*
G37*
G36*
G01X1141643D02*
X1141593Y178506D01*
X1141193D01*
X1141143Y179256D01*
Y179456D01*
X1141643D01*
Y179256D01*
G37*
G36*
G01X1139043D02*
X1138993Y178506D01*
X1138593D01*
X1138543Y179256D01*
Y179456D01*
X1139043D01*
Y179256D01*
G37*
G36*
G01X1136443D02*
X1136393Y178506D01*
X1135993D01*
X1135943Y179256D01*
Y179456D01*
X1136443D01*
Y179256D01*
G37*
G36*
G01X1133843D02*
X1133793Y178506D01*
X1133393D01*
X1133343Y179256D01*
Y179456D01*
X1133843D01*
Y179256D01*
G37*
G36*
G01X1145043Y179656D02*
X1145093Y180406D01*
X1145493D01*
X1145543Y179656D01*
Y179456D01*
X1145043D01*
Y179656D01*
G37*
G36*
G01X1147643D02*
X1147693Y180406D01*
X1148093D01*
X1148143Y179656D01*
Y179456D01*
X1147643D01*
Y179656D01*
G37*
G36*
G01X1150243D02*
X1150293Y180406D01*
X1150693D01*
X1150743Y179656D01*
Y179456D01*
X1150243D01*
Y179656D01*
G37*
G36*
G01X1142443D02*
X1142493Y180406D01*
X1142893D01*
X1142943Y179656D01*
Y179456D01*
X1142443D01*
Y179656D01*
G37*
G36*
G01X1139843D02*
X1139893Y180406D01*
X1140293D01*
X1140343Y179656D01*
Y179456D01*
X1139843D01*
Y179656D01*
G37*
G36*
G01X1137243D02*
X1137293Y180406D01*
X1137693D01*
X1137743Y179656D01*
Y179456D01*
X1137243D01*
Y179656D01*
G37*
G36*
G01X1132043D02*
X1132093Y180406D01*
X1132493D01*
X1132543Y179656D01*
Y179456D01*
X1132043D01*
Y179656D01*
G37*
G36*
G01X1154643Y179256D02*
X1154593Y178506D01*
X1154193D01*
X1154143Y179256D01*
Y179456D01*
X1154643D01*
Y179256D01*
G37*
G36*
G01X1152843Y179656D02*
X1152893Y180406D01*
X1153293D01*
X1153343Y179656D01*
Y179456D01*
X1152843D01*
Y179656D01*
G37*
G36*
G01X1155443D02*
X1155493Y180406D01*
X1155893D01*
X1155943Y179656D01*
Y179456D01*
X1155443D01*
Y179656D01*
G37*
G36*
G01X1134643D02*
X1134693Y180406D01*
X1135093D01*
X1135143Y179656D01*
Y179456D01*
X1134643D01*
Y179656D01*
G37*
G36*
G01X1132791Y193466D02*
X1133357Y193961D01*
X1133639Y193678D01*
X1133144Y193112D01*
X1133003Y192971D01*
X1132649Y193325D01*
X1132791Y193466D01*
G37*
G36*
G01X1130952Y195304D02*
X1131518Y195799D01*
X1131801Y195517D01*
X1131306Y194951D01*
X1131165Y194809D01*
X1130811Y195163D01*
X1130952Y195304D01*
G37*
G36*
G01X1129114Y197143D02*
X1129680Y197638D01*
X1129962Y197355D01*
X1129467Y196789D01*
X1129326Y196648D01*
X1128973Y197001D01*
X1129114Y197143D01*
G37*
G36*
G01X1133781Y191910D02*
X1133215Y191415D01*
X1132932Y191698D01*
X1133427Y192264D01*
X1133569Y192405D01*
X1133922Y192052D01*
X1133781Y191910D01*
G37*
G36*
G01X1131942Y193749D02*
X1131377Y193254D01*
X1131094Y193537D01*
X1131589Y194102D01*
X1131730Y194244D01*
X1132084Y193890D01*
X1131942Y193749D01*
G37*
G36*
G01X1130104Y195587D02*
X1129538Y195092D01*
X1129255Y195375D01*
X1129750Y195941D01*
X1129892Y196082D01*
X1130245Y195729D01*
X1130104Y195587D01*
G37*
G36*
G01X1136443Y190106D02*
X1136393Y189356D01*
X1135993D01*
X1135943Y190106D01*
Y190306D01*
X1136443D01*
Y190106D01*
G37*
G36*
G01X1137243Y190506D02*
X1137293Y191256D01*
X1137693D01*
X1137743Y190506D01*
Y190306D01*
X1137243D01*
Y190506D01*
G37*
G36*
G01X1127677Y198729D02*
X1127007Y199079D01*
Y199949D01*
X1127677Y200299D01*
X1127852D01*
Y198729D01*
X1127677D01*
G37*
G36*
G01X1152043Y190106D02*
X1151993Y189356D01*
X1151593D01*
X1151543Y190106D01*
Y190306D01*
X1152043D01*
Y190106D01*
G37*
G36*
G01X1149443D02*
X1149393Y189356D01*
X1148993D01*
X1148943Y190106D01*
Y190306D01*
X1149443D01*
Y190106D01*
G37*
G36*
G01X1146843D02*
X1146793Y189356D01*
X1146393D01*
X1146343Y190106D01*
Y190306D01*
X1146843D01*
Y190106D01*
G37*
G36*
G01X1144243D02*
X1144193Y189356D01*
X1143793D01*
X1143743Y190106D01*
Y190306D01*
X1144243D01*
Y190106D01*
G37*
G36*
G01X1141643D02*
X1141593Y189356D01*
X1141193D01*
X1141143Y190106D01*
Y190306D01*
X1141643D01*
Y190106D01*
G37*
G36*
G01X1139043D02*
X1138993Y189356D01*
X1138593D01*
X1138543Y190106D01*
Y190306D01*
X1139043D01*
Y190106D01*
G37*
G36*
G01X1150243Y190506D02*
X1150293Y191256D01*
X1150693D01*
X1150743Y190506D01*
Y190306D01*
X1150243D01*
Y190506D01*
G37*
G36*
G01X1147643D02*
X1147693Y191256D01*
X1148093D01*
X1148143Y190506D01*
Y190306D01*
X1147643D01*
Y190506D01*
G37*
G36*
G01X1145043D02*
X1145093Y191256D01*
X1145493D01*
X1145543Y190506D01*
Y190306D01*
X1145043D01*
Y190506D01*
G37*
G36*
G01X1142443D02*
X1142493Y191256D01*
X1142893D01*
X1142943Y190506D01*
Y190306D01*
X1142443D01*
Y190506D01*
G37*
G36*
G01X1139843D02*
X1139893Y191256D01*
X1140293D01*
X1140343Y190506D01*
Y190306D01*
X1139843D01*
Y190506D01*
G37*
G36*
G01X1154643Y190106D02*
X1154593Y189356D01*
X1154193D01*
X1154143Y190106D01*
Y190306D01*
X1154643D01*
Y190106D01*
G37*
G36*
G01X1152843Y190506D02*
X1152893Y191256D01*
X1153293D01*
X1153343Y190506D01*
Y190306D01*
X1152843D01*
Y190506D01*
G37*
G36*
G01X1155443D02*
X1155493Y191256D01*
X1155893D01*
X1155943Y190506D01*
Y190306D01*
X1155443D01*
Y190506D01*
G37*
G36*
G01X1134629Y191627D02*
X1135195Y192122D01*
X1135478Y191840D01*
X1134983Y191274D01*
X1134841Y191133D01*
X1134488Y191486D01*
X1134629Y191627D01*
G37*
G36*
G01X1132049Y196401D02*
X1132615Y196896D01*
X1132897Y196613D01*
X1132402Y196047D01*
X1132261Y195906D01*
X1131907Y196260D01*
X1132049Y196401D01*
G37*
G36*
G01X1133887Y194562D02*
X1134453Y195057D01*
X1134736Y194775D01*
X1134241Y194209D01*
X1134100Y194067D01*
X1133746Y194421D01*
X1133887Y194562D01*
G37*
G36*
G01X1135726Y192724D02*
X1136292Y193219D01*
X1136574Y192936D01*
X1136079Y192370D01*
X1135938Y192229D01*
X1135584Y192583D01*
X1135726Y192724D01*
G37*
G36*
G01X1131200Y196684D02*
X1130635Y196189D01*
X1130352Y196472D01*
X1130847Y197037D01*
X1130988Y197179D01*
X1131342Y196825D01*
X1131200Y196684D01*
G37*
G36*
G01X1133039Y194845D02*
X1132473Y194350D01*
X1132190Y194633D01*
X1132685Y195199D01*
X1132827Y195340D01*
X1133180Y194987D01*
X1133039Y194845D01*
G37*
G36*
G01X1137243Y192056D02*
X1137293Y192806D01*
X1137693D01*
X1137743Y192056D01*
Y191856D01*
X1137243D01*
Y192056D01*
G37*
G36*
G01X1128777Y201173D02*
X1129447Y200823D01*
Y199953D01*
X1128777Y199603D01*
X1128602D01*
Y201173D01*
X1128777D01*
G37*
G36*
G01X1130210Y198239D02*
X1130776Y198734D01*
X1131059Y198452D01*
X1130564Y197886D01*
X1130423Y197744D01*
X1130069Y198098D01*
X1130210Y198239D01*
G37*
G36*
G01X1126900Y207211D02*
X1127570Y206861D01*
Y205991D01*
X1126900Y205641D01*
X1126726D01*
X1126725Y207212D01*
X1126900Y207211D01*
G37*
G36*
G01X1145043Y192056D02*
X1145093Y192806D01*
X1145493D01*
X1145543Y192056D01*
Y191856D01*
X1145043D01*
Y192056D01*
G37*
G36*
G01X1142443D02*
X1142493Y192806D01*
X1142893D01*
X1142943Y192056D01*
Y191856D01*
X1142443D01*
Y192056D01*
G37*
G36*
G01X1139843D02*
X1139893Y192806D01*
X1140293D01*
X1140343Y192056D01*
Y191856D01*
X1139843D01*
Y192056D01*
G37*
G36*
G01X1147643D02*
X1147693Y192806D01*
X1148093D01*
X1148143Y192056D01*
Y191856D01*
X1147643D01*
Y192056D01*
G37*
G36*
G01X1150243D02*
X1150293Y192806D01*
X1150693D01*
X1150743Y192056D01*
Y191856D01*
X1150243D01*
Y192056D01*
G37*
G36*
G01X1146843Y191656D02*
X1146793Y190906D01*
X1146393D01*
X1146343Y191656D01*
Y191856D01*
X1146843D01*
Y191656D01*
G37*
G36*
G01X1144243D02*
X1144193Y190906D01*
X1143793D01*
X1143743Y191656D01*
Y191856D01*
X1144243D01*
Y191656D01*
G37*
G36*
G01X1141643D02*
X1141593Y190906D01*
X1141193D01*
X1141143Y191656D01*
Y191856D01*
X1141643D01*
Y191656D01*
G37*
G36*
G01X1139043D02*
X1138993Y190906D01*
X1138593D01*
X1138543Y191656D01*
Y191856D01*
X1139043D01*
Y191656D01*
G37*
G36*
G01X1149443D02*
X1149393Y190906D01*
X1148993D01*
X1148943Y191656D01*
Y191856D01*
X1149443D01*
Y191656D01*
G37*
G36*
G01X1152043D02*
X1151993Y190906D01*
X1151593D01*
X1151543Y191656D01*
Y191856D01*
X1152043D01*
Y191656D01*
G37*
G36*
G01X1152843Y192056D02*
X1152893Y192806D01*
X1153293D01*
X1153343Y192056D01*
Y191856D01*
X1152843D01*
Y192056D01*
G37*
G36*
G01X1155443D02*
X1155493Y192806D01*
X1155893D01*
X1155943Y192056D01*
Y191856D01*
X1155443D01*
Y192056D01*
G37*
G36*
G01X1154643Y191656D02*
X1154593Y190906D01*
X1154193D01*
X1154143Y191656D01*
Y191856D01*
X1154643D01*
Y191656D01*
G37*
G36*
G01X1134877Y193007D02*
X1134312Y192512D01*
X1134029Y192795D01*
X1134524Y193360D01*
X1134665Y193502D01*
X1135019Y193148D01*
X1134877Y193007D01*
G37*
G36*
G01X1113623Y190138D02*
X1113058Y189643D01*
X1112775Y189926D01*
X1113270Y190491D01*
X1113411Y190633D01*
X1113765Y190279D01*
X1113623Y190138D01*
G37*
G36*
G01X1114472Y189855D02*
X1115038Y190350D01*
X1115321Y190067D01*
X1114826Y189501D01*
X1114684Y189360D01*
X1114331Y189713D01*
X1114472Y189855D01*
G37*
G36*
G01X1112633Y191693D02*
X1113199Y192188D01*
X1113482Y191905D01*
X1112987Y191340D01*
X1112846Y191198D01*
X1112492Y191552D01*
X1112633Y191693D01*
G37*
G36*
G01X1110629Y195120D02*
X1109908Y194894D01*
X1109293Y195509D01*
X1109519Y196230D01*
X1109643Y196354D01*
X1110753Y195244D01*
X1110629Y195120D01*
G37*
G36*
G01X1119139Y184622D02*
X1118573Y184127D01*
X1118290Y184410D01*
X1118785Y184976D01*
X1118927Y185117D01*
X1119280Y184764D01*
X1119139Y184622D01*
G37*
G36*
G01X1117300Y186461D02*
X1116735Y185966D01*
X1116452Y186249D01*
X1116947Y186814D01*
X1117088Y186956D01*
X1117442Y186602D01*
X1117300Y186461D01*
G37*
G36*
G01X1115462Y188299D02*
X1114896Y187804D01*
X1114613Y188087D01*
X1115108Y188653D01*
X1115250Y188794D01*
X1115603Y188441D01*
X1115462Y188299D01*
G37*
G36*
G01X1120977Y182784D02*
X1120412Y182289D01*
X1120129Y182572D01*
X1120624Y183137D01*
X1120765Y183279D01*
X1121119Y182925D01*
X1120977Y182784D01*
G37*
G36*
G01X1122816Y180945D02*
X1122250Y180450D01*
X1121967Y180733D01*
X1122462Y181299D01*
X1122604Y181440D01*
X1122957Y181087D01*
X1122816Y180945D01*
G37*
G36*
G01X1124654Y179107D02*
X1124089Y178612D01*
X1123806Y178895D01*
X1124301Y179460D01*
X1124442Y179602D01*
X1124796Y179248D01*
X1124654Y179107D01*
G37*
G36*
G01X1126493Y177268D02*
X1125927Y176773D01*
X1125644Y177056D01*
X1126139Y177622D01*
X1126281Y177763D01*
X1126634Y177410D01*
X1126493Y177268D01*
G37*
G36*
G01X1118149Y186178D02*
X1118715Y186673D01*
X1118997Y186390D01*
X1118502Y185824D01*
X1118361Y185683D01*
X1118008Y186036D01*
X1118149Y186178D01*
G37*
G36*
G01X1116310Y188016D02*
X1116876Y188511D01*
X1117159Y188229D01*
X1116664Y187663D01*
X1116523Y187521D01*
X1116169Y187875D01*
X1116310Y188016D01*
G37*
G36*
G01X1119987Y184339D02*
X1120553Y184834D01*
X1120836Y184552D01*
X1120341Y183986D01*
X1120200Y183844D01*
X1119846Y184198D01*
X1119987Y184339D01*
G37*
G36*
G01X1121826Y182501D02*
X1122392Y182996D01*
X1122674Y182713D01*
X1122179Y182147D01*
X1122038Y182006D01*
X1121684Y182360D01*
X1121826Y182501D01*
G37*
G36*
G01X1123664Y180662D02*
X1124230Y181157D01*
X1124513Y180875D01*
X1124018Y180309D01*
X1123876Y180168D01*
X1123523Y180521D01*
X1123664Y180662D01*
G37*
G36*
G01X1125503Y178824D02*
X1126069Y179319D01*
X1126351Y179036D01*
X1125856Y178470D01*
X1125715Y178329D01*
X1125361Y178683D01*
X1125503Y178824D01*
G37*
G36*
G01X1128331Y175430D02*
X1127766Y174935D01*
X1127483Y175218D01*
X1127978Y175783D01*
X1128119Y175925D01*
X1128473Y175571D01*
X1128331Y175430D01*
G37*
G36*
G01X1127341Y176986D02*
X1127907Y177481D01*
X1128190Y177198D01*
X1127695Y176632D01*
X1127553Y176491D01*
X1127200Y176844D01*
X1127341Y176986D01*
G37*
G36*
G01X1141643Y174606D02*
X1141593Y173856D01*
X1141193D01*
X1141143Y174606D01*
Y174806D01*
X1141643D01*
Y174606D01*
G37*
G36*
G01X1139043D02*
X1138993Y173856D01*
X1138593D01*
X1138543Y174606D01*
Y174806D01*
X1139043D01*
Y174606D01*
G37*
G36*
G01X1136443D02*
X1136393Y173856D01*
X1135993D01*
X1135943Y174606D01*
Y174806D01*
X1136443D01*
Y174606D01*
G37*
G36*
G01X1133843D02*
X1133793Y173856D01*
X1133393D01*
X1133343Y174606D01*
Y174806D01*
X1133843D01*
Y174606D01*
G37*
G36*
G01X1131243D02*
X1131193Y173856D01*
X1130793D01*
X1130743Y174606D01*
Y174806D01*
X1131243D01*
Y174606D01*
G37*
G36*
G01X1144243D02*
X1144193Y173856D01*
X1143793D01*
X1143743Y174606D01*
Y174806D01*
X1144243D01*
Y174606D01*
G37*
G36*
G01X1146843D02*
X1146793Y173856D01*
X1146393D01*
X1146343Y174606D01*
Y174806D01*
X1146843D01*
Y174606D01*
G37*
G36*
G01X1149443D02*
X1149393Y173856D01*
X1148993D01*
X1148943Y174606D01*
Y174806D01*
X1149443D01*
Y174606D01*
G37*
G36*
G01X1152043D02*
X1151993Y173856D01*
X1151593D01*
X1151543Y174606D01*
Y174806D01*
X1152043D01*
Y174606D01*
G37*
G36*
G01X1139843Y175006D02*
X1139893Y175756D01*
X1140293D01*
X1140343Y175006D01*
Y174806D01*
X1139843D01*
Y175006D01*
G37*
G36*
G01X1137243D02*
X1137293Y175756D01*
X1137693D01*
X1137743Y175006D01*
Y174806D01*
X1137243D01*
Y175006D01*
G37*
G36*
G01X1132043D02*
X1132093Y175756D01*
X1132493D01*
X1132543Y175006D01*
Y174806D01*
X1132043D01*
Y175006D01*
G37*
G36*
G01X1142443D02*
X1142493Y175756D01*
X1142893D01*
X1142943Y175006D01*
Y174806D01*
X1142443D01*
Y175006D01*
G37*
G36*
G01X1145043D02*
X1145093Y175756D01*
X1145493D01*
X1145543Y175006D01*
Y174806D01*
X1145043D01*
Y175006D01*
G37*
G36*
G01X1147643D02*
X1147693Y175756D01*
X1148093D01*
X1148143Y175006D01*
Y174806D01*
X1147643D01*
Y175006D01*
G37*
G36*
G01X1150243D02*
X1150293Y175756D01*
X1150693D01*
X1150743Y175006D01*
Y174806D01*
X1150243D01*
Y175006D01*
G37*
G36*
G01X1129443D02*
X1129493Y175756D01*
X1129893D01*
X1129943Y175006D01*
Y174806D01*
X1129443D01*
Y175006D01*
G37*
G36*
G01X1154643Y174606D02*
X1154593Y173856D01*
X1154193D01*
X1154143Y174606D01*
Y174806D01*
X1154643D01*
Y174606D01*
G37*
G36*
G01X1152843Y175006D02*
X1152893Y175756D01*
X1153293D01*
X1153343Y175006D01*
Y174806D01*
X1152843D01*
Y175006D01*
G37*
G36*
G01X1155443D02*
X1155493Y175756D01*
X1155893D01*
X1155943Y175006D01*
Y174806D01*
X1155443D01*
Y175006D01*
G37*
G36*
G01X1134643D02*
X1134693Y175756D01*
X1135093D01*
X1135143Y175006D01*
Y174806D01*
X1134643D01*
Y175006D01*
G37*
G36*
G01X1115568Y190951D02*
X1116134Y191446D01*
X1116417Y191164D01*
X1115922Y190598D01*
X1115781Y190456D01*
X1115427Y190810D01*
X1115568Y190951D01*
G37*
G36*
G01X1113730Y192790D02*
X1114296Y193285D01*
X1114579Y193002D01*
X1114084Y192436D01*
X1113942Y192295D01*
X1113589Y192648D01*
X1113730Y192790D01*
G37*
G36*
G01X1116558Y189396D02*
X1115993Y188901D01*
X1115710Y189184D01*
X1116205Y189749D01*
X1116346Y189891D01*
X1116700Y189537D01*
X1116558Y189396D01*
G37*
G36*
G01X1114720Y191234D02*
X1114154Y190739D01*
X1113871Y191022D01*
X1114366Y191588D01*
X1114508Y191729D01*
X1114861Y191376D01*
X1114720Y191234D01*
G37*
G36*
G01X1110768Y196538D02*
X1111490Y196764D01*
X1112105Y196149D01*
X1111879Y195428D01*
X1111755Y195304D01*
X1110645Y196414D01*
X1110768Y196538D01*
G37*
G36*
G01X1113592Y208591D02*
X1113624Y207836D01*
X1112871Y207401D01*
X1112233Y207806D01*
X1112145Y207957D01*
X1113505Y208743D01*
X1113592Y208591D01*
G37*
G36*
G01X1119245Y187274D02*
X1119811Y187769D01*
X1120094Y187487D01*
X1119599Y186921D01*
X1119458Y186779D01*
X1119104Y187133D01*
X1119245Y187274D01*
G37*
G36*
G01X1117407Y189113D02*
X1117973Y189608D01*
X1118255Y189325D01*
X1117761Y188759D01*
X1117619Y188618D01*
X1117266Y188971D01*
X1117407Y189113D01*
G37*
G36*
G01X1121084Y185436D02*
X1121650Y185931D01*
X1121932Y185648D01*
X1121437Y185082D01*
X1121296Y184941D01*
X1120942Y185295D01*
X1121084Y185436D01*
G37*
G36*
G01X1122922Y183597D02*
X1123488Y184092D01*
X1123771Y183810D01*
X1123276Y183244D01*
X1123135Y183102D01*
X1122781Y183456D01*
X1122922Y183597D01*
G37*
G36*
G01X1124761Y181759D02*
X1125327Y182254D01*
X1125609Y181971D01*
X1125114Y181405D01*
X1124973Y181264D01*
X1124619Y181618D01*
X1124761Y181759D01*
G37*
G36*
G01X1120235Y185719D02*
X1119670Y185224D01*
X1119387Y185507D01*
X1119882Y186072D01*
X1120023Y186214D01*
X1120377Y185860D01*
X1120235Y185719D01*
G37*
G36*
G01X1118397Y187557D02*
X1117831Y187062D01*
X1117548Y187345D01*
X1118043Y187911D01*
X1118185Y188052D01*
X1118538Y187699D01*
X1118397Y187557D01*
G37*
G36*
G01X1122074Y183880D02*
X1121508Y183385D01*
X1121225Y183668D01*
X1121720Y184234D01*
X1121862Y184375D01*
X1122215Y184022D01*
X1122074Y183880D01*
G37*
G36*
G01X1123912Y182042D02*
X1123347Y181547D01*
X1123064Y181830D01*
X1123559Y182395D01*
X1123700Y182537D01*
X1124054Y182183D01*
X1123912Y182042D01*
G37*
G36*
G01X1125751Y180203D02*
X1125185Y179708D01*
X1124902Y179991D01*
X1125397Y180557D01*
X1125539Y180698D01*
X1125892Y180345D01*
X1125751Y180203D01*
G37*
G36*
G01X1126599Y179921D02*
X1127165Y180415D01*
X1127448Y180133D01*
X1126953Y179567D01*
X1126811Y179426D01*
X1126458Y179779D01*
X1126599Y179921D01*
G37*
G36*
G01X1128438Y178082D02*
X1129004Y178577D01*
X1129286Y178294D01*
X1128791Y177728D01*
X1128650Y177587D01*
X1128296Y177941D01*
X1128438Y178082D01*
G37*
G36*
G01X1127589Y178365D02*
X1127024Y177870D01*
X1126741Y178153D01*
X1127236Y178718D01*
X1127377Y178860D01*
X1127731Y178506D01*
X1127589Y178365D01*
G37*
G36*
G01X1129428Y176526D02*
X1128862Y176031D01*
X1128579Y176314D01*
X1129074Y176880D01*
X1129216Y177021D01*
X1129569Y176668D01*
X1129428Y176526D01*
G37*
G36*
G01X1141643Y176156D02*
X1141593Y175406D01*
X1141193D01*
X1141143Y176156D01*
Y176356D01*
X1141643D01*
Y176156D01*
G37*
G36*
G01X1139043D02*
X1138993Y175406D01*
X1138593D01*
X1138543Y176156D01*
Y176356D01*
X1139043D01*
Y176156D01*
G37*
G36*
G01X1136443D02*
X1136393Y175406D01*
X1135993D01*
X1135943Y176156D01*
Y176356D01*
X1136443D01*
Y176156D01*
G37*
G36*
G01X1133843D02*
X1133793Y175406D01*
X1133393D01*
X1133343Y176156D01*
Y176356D01*
X1133843D01*
Y176156D01*
G37*
G36*
G01X1131243D02*
X1131193Y175406D01*
X1130793D01*
X1130743Y176156D01*
Y176356D01*
X1131243D01*
Y176156D01*
G37*
G36*
G01X1144243D02*
X1144193Y175406D01*
X1143793D01*
X1143743Y176156D01*
Y176356D01*
X1144243D01*
Y176156D01*
G37*
G36*
G01X1146843D02*
X1146793Y175406D01*
X1146393D01*
X1146343Y176156D01*
Y176356D01*
X1146843D01*
Y176156D01*
G37*
G36*
G01X1149443D02*
X1149393Y175406D01*
X1148993D01*
X1148943Y176156D01*
Y176356D01*
X1149443D01*
Y176156D01*
G37*
G36*
G01X1152043D02*
X1151993Y175406D01*
X1151593D01*
X1151543Y176156D01*
Y176356D01*
X1152043D01*
Y176156D01*
G37*
G36*
G01X1139843Y176556D02*
X1139893Y177306D01*
X1140293D01*
X1140343Y176556D01*
Y176356D01*
X1139843D01*
Y176556D01*
G37*
G36*
G01X1137243D02*
X1137293Y177306D01*
X1137693D01*
X1137743Y176556D01*
Y176356D01*
X1137243D01*
Y176556D01*
G37*
G36*
G01X1132043D02*
X1132093Y177306D01*
X1132493D01*
X1132543Y176556D01*
Y176356D01*
X1132043D01*
Y176556D01*
G37*
G36*
G01X1142443D02*
X1142493Y177306D01*
X1142893D01*
X1142943Y176556D01*
Y176356D01*
X1142443D01*
Y176556D01*
G37*
G36*
G01X1145043D02*
X1145093Y177306D01*
X1145493D01*
X1145543Y176556D01*
Y176356D01*
X1145043D01*
Y176556D01*
G37*
G36*
G01X1147643D02*
X1147693Y177306D01*
X1148093D01*
X1148143Y176556D01*
Y176356D01*
X1147643D01*
Y176556D01*
G37*
G36*
G01X1150243D02*
X1150293Y177306D01*
X1150693D01*
X1150743Y176556D01*
Y176356D01*
X1150243D01*
Y176556D01*
G37*
G36*
G01X1154643Y176156D02*
X1154593Y175406D01*
X1154193D01*
X1154143Y176156D01*
Y176356D01*
X1154643D01*
Y176156D01*
G37*
G36*
G01X1152843Y176556D02*
X1152893Y177306D01*
X1153293D01*
X1153343Y176556D01*
Y176356D01*
X1152843D01*
Y176556D01*
G37*
G36*
G01X1155443D02*
X1155493Y177306D01*
X1155893D01*
X1155943Y176556D01*
Y176356D01*
X1155443D01*
Y176556D01*
G37*
G36*
G01X1157354Y175510D02*
X1156788Y175015D01*
X1156505Y175298D01*
X1157000Y175864D01*
X1157142Y176005D01*
X1157495Y175652D01*
X1157354Y175510D01*
G37*
G36*
G01X1110753Y205278D02*
X1111423Y204928D01*
Y204058D01*
X1110753Y203708D01*
X1110578D01*
Y205278D01*
X1110753D01*
G37*
G36*
G01X1134643Y176556D02*
X1134693Y177306D01*
X1135093D01*
X1135143Y176556D01*
Y176356D01*
X1134643D01*
Y176556D01*
G37*
G36*
G01X1126072Y195233D02*
X1125507Y194738D01*
X1125224Y195021D01*
X1125719Y195586D01*
X1125860Y195728D01*
X1126214Y195374D01*
X1126072Y195233D01*
G37*
G36*
G01X1123740Y197039D02*
X1123019Y196813D01*
X1122404Y197428D01*
X1122630Y198149D01*
X1122754Y198273D01*
X1123864Y197163D01*
X1123740Y197039D01*
G37*
G36*
G01X1122321Y199847D02*
X1121651Y200197D01*
Y201067D01*
X1122321Y201417D01*
X1122496D01*
Y199847D01*
X1122321D01*
G37*
G36*
G01X1128759Y193111D02*
X1129325Y193606D01*
X1129608Y193324D01*
X1129113Y192758D01*
X1128972Y192616D01*
X1128618Y192970D01*
X1128759Y193111D01*
G37*
G36*
G01X1126921Y194950D02*
X1127487Y195445D01*
X1127769Y195162D01*
X1127274Y194596D01*
X1127133Y194455D01*
X1126780Y194808D01*
X1126921Y194950D01*
G37*
G36*
G01X1130598Y191273D02*
X1131164Y191768D01*
X1131446Y191485D01*
X1130951Y190919D01*
X1130810Y190778D01*
X1130456Y191132D01*
X1130598Y191273D01*
G37*
G36*
G01X1132436Y189434D02*
X1133002Y189929D01*
X1133285Y189647D01*
X1132790Y189081D01*
X1132648Y188940D01*
X1132295Y189293D01*
X1132436Y189434D01*
G37*
G36*
G01X1127911Y193394D02*
X1127345Y192899D01*
X1127062Y193182D01*
X1127557Y193748D01*
X1127699Y193889D01*
X1128052Y193536D01*
X1127911Y193394D01*
G37*
G36*
G01X1129749Y191556D02*
X1129184Y191061D01*
X1128901Y191344D01*
X1129396Y191909D01*
X1129537Y192051D01*
X1129891Y191697D01*
X1129749Y191556D01*
G37*
G36*
G01X1131588Y189717D02*
X1131022Y189222D01*
X1130739Y189505D01*
X1131234Y190071D01*
X1131376Y190212D01*
X1131729Y189859D01*
X1131588Y189717D01*
G37*
G36*
G01X1133426Y187879D02*
X1132861Y187384D01*
X1132578Y187667D01*
X1133073Y188232D01*
X1133214Y188374D01*
X1133568Y188020D01*
X1133426Y187879D01*
G37*
G36*
G01X1144243Y187006D02*
X1144193Y186256D01*
X1143793D01*
X1143743Y187006D01*
Y187206D01*
X1144243D01*
Y187006D01*
G37*
G36*
G01X1141643D02*
X1141593Y186256D01*
X1141193D01*
X1141143Y187006D01*
Y187206D01*
X1141643D01*
Y187006D01*
G37*
G36*
G01X1139043D02*
X1138993Y186256D01*
X1138593D01*
X1138543Y187006D01*
Y187206D01*
X1139043D01*
Y187006D01*
G37*
G36*
G01X1136443D02*
X1136393Y186256D01*
X1135993D01*
X1135943Y187006D01*
Y187206D01*
X1136443D01*
Y187006D01*
G37*
G36*
G01X1146843D02*
X1146793Y186256D01*
X1146393D01*
X1146343Y187006D01*
Y187206D01*
X1146843D01*
Y187006D01*
G37*
G36*
G01X1149443D02*
X1149393Y186256D01*
X1148993D01*
X1148943Y187006D01*
Y187206D01*
X1149443D01*
Y187006D01*
G37*
G36*
G01X1152043D02*
X1151993Y186256D01*
X1151593D01*
X1151543Y187006D01*
Y187206D01*
X1152043D01*
Y187006D01*
G37*
G36*
G01X1145043Y187406D02*
X1145093Y188156D01*
X1145493D01*
X1145543Y187406D01*
Y187206D01*
X1145043D01*
Y187406D01*
G37*
G36*
G01X1142443D02*
X1142493Y188156D01*
X1142893D01*
X1142943Y187406D01*
Y187206D01*
X1142443D01*
Y187406D01*
G37*
G36*
G01X1139843D02*
X1139893Y188156D01*
X1140293D01*
X1140343Y187406D01*
Y187206D01*
X1139843D01*
Y187406D01*
G37*
G36*
G01X1137243D02*
X1137293Y188156D01*
X1137693D01*
X1137743Y187406D01*
Y187206D01*
X1137243D01*
Y187406D01*
G37*
G36*
G01X1147643D02*
X1147693Y188156D01*
X1148093D01*
X1148143Y187406D01*
Y187206D01*
X1147643D01*
Y187406D01*
G37*
G36*
G01X1150243D02*
X1150293Y188156D01*
X1150693D01*
X1150743Y187406D01*
Y187206D01*
X1150243D01*
Y187406D01*
G37*
G36*
G01X1154643Y187006D02*
X1154593Y186256D01*
X1154193D01*
X1154143Y187006D01*
Y187206D01*
X1154643D01*
Y187006D01*
G37*
G36*
G01X1152843Y187406D02*
X1152893Y188156D01*
X1153293D01*
X1153343Y187406D01*
Y187206D01*
X1152843D01*
Y187406D01*
G37*
G36*
G01X1155443D02*
X1155493Y188156D01*
X1155893D01*
X1155943Y187406D01*
Y187206D01*
X1155443D01*
Y187406D01*
G37*
G36*
G01X1123421Y205217D02*
X1124091Y204867D01*
Y203997D01*
X1123421Y203647D01*
X1123246D01*
Y205217D01*
X1123421D01*
G37*
G36*
G01Y209117D02*
X1124091Y208767D01*
Y207897D01*
X1123421Y207547D01*
X1123246D01*
Y209117D01*
X1123421D01*
G37*
G36*
G01X1128017Y196046D02*
X1128583Y196541D01*
X1128866Y196259D01*
X1128371Y195693D01*
X1128230Y195551D01*
X1127876Y195905D01*
X1128017Y196046D01*
G37*
G36*
G01X1129856Y194208D02*
X1130422Y194703D01*
X1130704Y194420D01*
X1130209Y193854D01*
X1130068Y193713D01*
X1129714Y194067D01*
X1129856Y194208D01*
G37*
G36*
G01X1131694Y192369D02*
X1132260Y192864D01*
X1132543Y192582D01*
X1132048Y192016D01*
X1131907Y191874D01*
X1131553Y192228D01*
X1131694Y192369D01*
G37*
G36*
G01X1133533Y190531D02*
X1134099Y191026D01*
X1134381Y190743D01*
X1133886Y190177D01*
X1133745Y190036D01*
X1133391Y190390D01*
X1133533Y190531D01*
G37*
G36*
G01X1129007Y194491D02*
X1128442Y193996D01*
X1128159Y194279D01*
X1128654Y194844D01*
X1128795Y194986D01*
X1129149Y194632D01*
X1129007Y194491D01*
G37*
G36*
G01X1130846Y192652D02*
X1130280Y192157D01*
X1129997Y192440D01*
X1130492Y193006D01*
X1130634Y193147D01*
X1130987Y192794D01*
X1130846Y192652D01*
G37*
G36*
G01X1132684Y190814D02*
X1132119Y190319D01*
X1131836Y190602D01*
X1132331Y191167D01*
X1132472Y191309D01*
X1132826Y190955D01*
X1132684Y190814D01*
G37*
G36*
G01X1134523Y188975D02*
X1133957Y188480D01*
X1133674Y188763D01*
X1134169Y189329D01*
X1134311Y189470D01*
X1134664Y189117D01*
X1134523Y188975D01*
G37*
G36*
G01X1146843Y188556D02*
X1146793Y187806D01*
X1146393D01*
X1146343Y188556D01*
Y188756D01*
X1146843D01*
Y188556D01*
G37*
G36*
G01X1144243D02*
X1144193Y187806D01*
X1143793D01*
X1143743Y188556D01*
Y188756D01*
X1144243D01*
Y188556D01*
G37*
G36*
G01X1141643D02*
X1141593Y187806D01*
X1141193D01*
X1141143Y188556D01*
Y188756D01*
X1141643D01*
Y188556D01*
G37*
G36*
G01X1139043D02*
X1138993Y187806D01*
X1138593D01*
X1138543Y188556D01*
Y188756D01*
X1139043D01*
Y188556D01*
G37*
G36*
G01X1136443D02*
X1136393Y187806D01*
X1135993D01*
X1135943Y188556D01*
Y188756D01*
X1136443D01*
Y188556D01*
G37*
G36*
G01X1149443D02*
X1149393Y187806D01*
X1148993D01*
X1148943Y188556D01*
Y188756D01*
X1149443D01*
Y188556D01*
G37*
G36*
G01X1152043D02*
X1151993Y187806D01*
X1151593D01*
X1151543Y188556D01*
Y188756D01*
X1152043D01*
Y188556D01*
G37*
G36*
G01X1145043Y188956D02*
X1145093Y189706D01*
X1145493D01*
X1145543Y188956D01*
Y188756D01*
X1145043D01*
Y188956D01*
G37*
G36*
G01X1142443D02*
X1142493Y189706D01*
X1142893D01*
X1142943Y188956D01*
Y188756D01*
X1142443D01*
Y188956D01*
G37*
G36*
G01X1139843D02*
X1139893Y189706D01*
X1140293D01*
X1140343Y188956D01*
Y188756D01*
X1139843D01*
Y188956D01*
G37*
G36*
G01X1137243D02*
X1137293Y189706D01*
X1137693D01*
X1137743Y188956D01*
Y188756D01*
X1137243D01*
Y188956D01*
G37*
G36*
G01X1147643D02*
X1147693Y189706D01*
X1148093D01*
X1148143Y188956D01*
Y188756D01*
X1147643D01*
Y188956D01*
G37*
G36*
G01X1150243D02*
X1150293Y189706D01*
X1150693D01*
X1150743Y188956D01*
Y188756D01*
X1150243D01*
Y188956D01*
G37*
G36*
G01X1154643Y188556D02*
X1154593Y187806D01*
X1154193D01*
X1154143Y188556D01*
Y188756D01*
X1154643D01*
Y188556D01*
G37*
G36*
G01X1152843Y188956D02*
X1152893Y189706D01*
X1153293D01*
X1153343Y188956D01*
Y188756D01*
X1152843D01*
Y188956D01*
G37*
G36*
G01X1155443D02*
X1155493Y189706D01*
X1155893D01*
X1155943Y188956D01*
Y188756D01*
X1155443D01*
Y188956D01*
G37*
G36*
G01X1097856Y194252D02*
X1098606Y194202D01*
Y193802D01*
X1097856Y193752D01*
X1097656D01*
Y194252D01*
X1097856D01*
G37*
G36*
G01Y191652D02*
X1098606Y191602D01*
Y191202D01*
X1097856Y191152D01*
X1097656D01*
Y191652D01*
X1097856D01*
G37*
G36*
G01X1097456Y192452D02*
X1096706Y192502D01*
Y192902D01*
X1097456Y192952D01*
X1097656D01*
Y192452D01*
X1097456D01*
G37*
G36*
G01Y189852D02*
X1096706Y189902D01*
Y190302D01*
X1097456Y190352D01*
X1097656D01*
Y189852D01*
X1097456D01*
G37*
G36*
G01X1097425Y199888D02*
X1098095Y199538D01*
Y198668D01*
X1097425Y198318D01*
X1097250D01*
Y199888D01*
X1097425D01*
G37*
G36*
G01X1105110Y179915D02*
X1105676Y180410D01*
X1105959Y180127D01*
X1105464Y179561D01*
X1105322Y179420D01*
X1104969Y179773D01*
X1105110Y179915D01*
G37*
G36*
G01X1103271Y181753D02*
X1103837Y182248D01*
X1104120Y181965D01*
X1103625Y181400D01*
X1103484Y181258D01*
X1103130Y181612D01*
X1103271Y181753D01*
G37*
G36*
G01X1101433Y183592D02*
X1101999Y184087D01*
X1102282Y183804D01*
X1101787Y183238D01*
X1101645Y183097D01*
X1101292Y183450D01*
X1101433Y183592D01*
G37*
G36*
G01X1099595Y185430D02*
X1100160Y185925D01*
X1100443Y185642D01*
X1099948Y185077D01*
X1099807Y184935D01*
X1099453Y185289D01*
X1099595Y185430D01*
G37*
G36*
G01X1106948Y178076D02*
X1107514Y178571D01*
X1107797Y178289D01*
X1107302Y177723D01*
X1107161Y177581D01*
X1106807Y177935D01*
X1106948Y178076D01*
G37*
G36*
G01X1108787Y176238D02*
X1109353Y176733D01*
X1109635Y176450D01*
X1109140Y175884D01*
X1108999Y175743D01*
X1108646Y176096D01*
X1108787Y176238D01*
G37*
G36*
G01X1110625Y174399D02*
X1111191Y174894D01*
X1111474Y174612D01*
X1110979Y174046D01*
X1110838Y173904D01*
X1110484Y174258D01*
X1110625Y174399D01*
G37*
G36*
G01X1106100Y178359D02*
X1105534Y177864D01*
X1105251Y178147D01*
X1105746Y178713D01*
X1105888Y178854D01*
X1106241Y178501D01*
X1106100Y178359D01*
G37*
G36*
G01X1104261Y180198D02*
X1103696Y179703D01*
X1103413Y179986D01*
X1103908Y180551D01*
X1104049Y180693D01*
X1104403Y180339D01*
X1104261Y180198D01*
G37*
G36*
G01X1102423Y182036D02*
X1101857Y181541D01*
X1101574Y181824D01*
X1102069Y182390D01*
X1102211Y182531D01*
X1102564Y182178D01*
X1102423Y182036D01*
G37*
G36*
G01X1100584Y183875D02*
X1100019Y183380D01*
X1099736Y183663D01*
X1100231Y184228D01*
X1100372Y184370D01*
X1100726Y184016D01*
X1100584Y183875D01*
G37*
G36*
G01X1098746Y185713D02*
X1098180Y185218D01*
X1097897Y185501D01*
X1098392Y186067D01*
X1098534Y186208D01*
X1098887Y185855D01*
X1098746Y185713D01*
G37*
G36*
G01X1107938Y176521D02*
X1107373Y176026D01*
X1107090Y176309D01*
X1107585Y176874D01*
X1107726Y177016D01*
X1108080Y176662D01*
X1107938Y176521D01*
G37*
G36*
G01X1109777Y174682D02*
X1109211Y174187D01*
X1108928Y174470D01*
X1109423Y175036D01*
X1109565Y175177D01*
X1109918Y174824D01*
X1109777Y174682D01*
G37*
G36*
G01X1097856Y189052D02*
X1098606Y189002D01*
Y188602D01*
X1097856Y188552D01*
X1097656D01*
Y189052D01*
X1097856D01*
G37*
G36*
G01X1112464Y172561D02*
X1113030Y173056D01*
X1113312Y172773D01*
X1112817Y172207D01*
X1112676Y172066D01*
X1112322Y172420D01*
X1112464Y172561D01*
G37*
G36*
G01X1114302Y170722D02*
X1114868Y171217D01*
X1115151Y170935D01*
X1114656Y170369D01*
X1114514Y170228D01*
X1114161Y170581D01*
X1114302Y170722D01*
G37*
G36*
G01X1111615Y172844D02*
X1111050Y172349D01*
X1110767Y172632D01*
X1111262Y173197D01*
X1111403Y173339D01*
X1111757Y172985D01*
X1111615Y172844D01*
G37*
G36*
G01X1113454Y171005D02*
X1112888Y170510D01*
X1112605Y170793D01*
X1113100Y171359D01*
X1113242Y171500D01*
X1113595Y171147D01*
X1113454Y171005D01*
G37*
G36*
G01X1115562Y167564D02*
X1116312Y167514D01*
Y167114D01*
X1115562Y167064D01*
X1115362D01*
Y167564D01*
X1115562D01*
G37*
G36*
G01Y164964D02*
X1116312Y164914D01*
Y164514D01*
X1115562Y164464D01*
X1115362D01*
Y164964D01*
X1115562D01*
G37*
G36*
G01X1115162Y168364D02*
X1114412Y168414D01*
Y168814D01*
X1115162Y168864D01*
X1115362D01*
Y168364D01*
X1115162D01*
G37*
G36*
G01Y165764D02*
X1114412Y165814D01*
Y166214D01*
X1115162Y166264D01*
X1115362D01*
Y165764D01*
X1115162D01*
G37*
G36*
G01Y163164D02*
X1114412Y163214D01*
Y163614D01*
X1115162Y163664D01*
X1115362D01*
Y163164D01*
X1115162D01*
G37*
G36*
G01X1125470Y189822D02*
X1126036Y190317D01*
X1126318Y190034D01*
X1125823Y189468D01*
X1125682Y189327D01*
X1125328Y189681D01*
X1125470Y189822D01*
G37*
G36*
G01X1123631Y191660D02*
X1124197Y192155D01*
X1124480Y191873D01*
X1123985Y191307D01*
X1123844Y191165D01*
X1123490Y191519D01*
X1123631Y191660D01*
G37*
G36*
G01X1121793Y193499D02*
X1122359Y193994D01*
X1122641Y193711D01*
X1122147Y193145D01*
X1122005Y193004D01*
X1121652Y193357D01*
X1121793Y193499D01*
G37*
G36*
G01X1124621Y190105D02*
X1124056Y189610D01*
X1123773Y189893D01*
X1124268Y190458D01*
X1124409Y190600D01*
X1124763Y190246D01*
X1124621Y190105D01*
G37*
G36*
G01X1122784Y191943D02*
X1122218Y191448D01*
X1121935Y191731D01*
X1122430Y192297D01*
X1122572Y192438D01*
X1122925Y192085D01*
X1122784Y191943D01*
G37*
G36*
G01X1118623Y196028D02*
X1119344Y196255D01*
X1119960Y195639D01*
X1119733Y194918D01*
X1119610Y194794D01*
X1118499Y195905D01*
X1118623Y196028D01*
G37*
G36*
G01X1126461Y188266D02*
X1125895Y187771D01*
X1125612Y188054D01*
X1126107Y188620D01*
X1126249Y188761D01*
X1126602Y188408D01*
X1126461Y188266D01*
G37*
G36*
G01X1129147Y186145D02*
X1129713Y186640D01*
X1129995Y186357D01*
X1129500Y185791D01*
X1129359Y185650D01*
X1129005Y186004D01*
X1129147Y186145D01*
G37*
G36*
G01X1130985Y184307D02*
X1131551Y184801D01*
X1131834Y184519D01*
X1131339Y183953D01*
X1131197Y183812D01*
X1130844Y184165D01*
X1130985Y184307D01*
G37*
G36*
G01X1127308Y187983D02*
X1127874Y188478D01*
X1128157Y188196D01*
X1127662Y187630D01*
X1127521Y187488D01*
X1127167Y187842D01*
X1127308Y187983D01*
G37*
G36*
G01X1128298Y186428D02*
X1127733Y185933D01*
X1127450Y186216D01*
X1127945Y186781D01*
X1128086Y186923D01*
X1128440Y186569D01*
X1128298Y186428D01*
G37*
G36*
G01X1130138Y184589D02*
X1129572Y184094D01*
X1129289Y184377D01*
X1129784Y184943D01*
X1129926Y185084D01*
X1130279Y184731D01*
X1130138Y184589D01*
G37*
G36*
G01X1131975Y182751D02*
X1131410Y182256D01*
X1131127Y182539D01*
X1131622Y183104D01*
X1131763Y183246D01*
X1132117Y182892D01*
X1131975Y182751D01*
G37*
G36*
G01X1149443Y182356D02*
X1149393Y181606D01*
X1148993D01*
X1148943Y182356D01*
Y182556D01*
X1149443D01*
Y182356D01*
G37*
G36*
G01X1152043D02*
X1151993Y181606D01*
X1151593D01*
X1151543Y182356D01*
Y182556D01*
X1152043D01*
Y182356D01*
G37*
G36*
G01X1146843D02*
X1146793Y181606D01*
X1146393D01*
X1146343Y182356D01*
Y182556D01*
X1146843D01*
Y182356D01*
G37*
G36*
G01X1144243D02*
X1144193Y181606D01*
X1143793D01*
X1143743Y182356D01*
Y182556D01*
X1144243D01*
Y182356D01*
G37*
G36*
G01X1141643D02*
X1141593Y181606D01*
X1141193D01*
X1141143Y182356D01*
Y182556D01*
X1141643D01*
Y182356D01*
G37*
G36*
G01X1139043D02*
X1138993Y181606D01*
X1138593D01*
X1138543Y182356D01*
Y182556D01*
X1139043D01*
Y182356D01*
G37*
G36*
G01X1136443D02*
X1136393Y181606D01*
X1135993D01*
X1135943Y182356D01*
Y182556D01*
X1136443D01*
Y182356D01*
G37*
G36*
G01X1133843D02*
X1133793Y181606D01*
X1133393D01*
X1133343Y182356D01*
Y182556D01*
X1133843D01*
Y182356D01*
G37*
G36*
G01X1147643Y182756D02*
X1147693Y183506D01*
X1148093D01*
X1148143Y182756D01*
Y182556D01*
X1147643D01*
Y182756D01*
G37*
G36*
G01X1150243D02*
X1150293Y183506D01*
X1150693D01*
X1150743Y182756D01*
Y182556D01*
X1150243D01*
Y182756D01*
G37*
G36*
G01X1145043D02*
X1145093Y183506D01*
X1145493D01*
X1145543Y182756D01*
Y182556D01*
X1145043D01*
Y182756D01*
G37*
G36*
G01X1142443D02*
X1142493Y183506D01*
X1142893D01*
X1142943Y182756D01*
Y182556D01*
X1142443D01*
Y182756D01*
G37*
G36*
G01X1139843D02*
X1139893Y183506D01*
X1140293D01*
X1140343Y182756D01*
Y182556D01*
X1139843D01*
Y182756D01*
G37*
G36*
G01X1137243D02*
X1137293Y183506D01*
X1137693D01*
X1137743Y182756D01*
Y182556D01*
X1137243D01*
Y182756D01*
G37*
G36*
G01X1154643Y182356D02*
X1154593Y181606D01*
X1154193D01*
X1154143Y182356D01*
Y182556D01*
X1154643D01*
Y182356D01*
G37*
G36*
G01X1152843Y182756D02*
X1152893Y183506D01*
X1153293D01*
X1153343Y182756D01*
Y182556D01*
X1152843D01*
Y182756D01*
G37*
G36*
G01X1155443D02*
X1155493Y183506D01*
X1155893D01*
X1155943Y182756D01*
Y182556D01*
X1155443D01*
Y182756D01*
G37*
G36*
G01X1134643D02*
X1134693Y183506D01*
X1135093D01*
X1135143Y182756D01*
Y182556D01*
X1134643D01*
Y182756D01*
G37*
G36*
G01X1099406Y194252D02*
X1100156Y194202D01*
Y193802D01*
X1099406Y193752D01*
X1099206D01*
Y194252D01*
X1099406D01*
G37*
G36*
G01Y191652D02*
X1100156Y191602D01*
Y191202D01*
X1099406Y191152D01*
X1099206D01*
Y191652D01*
X1099406D01*
G37*
G36*
G01X1099006Y192452D02*
X1098256Y192502D01*
Y192902D01*
X1099006Y192952D01*
X1099206D01*
Y192452D01*
X1099006D01*
G37*
G36*
G01Y189852D02*
X1098256Y189902D01*
Y190302D01*
X1099006Y190352D01*
X1099206D01*
Y189852D01*
X1099006D01*
G37*
G36*
G01X1099421Y199306D02*
X1098751Y199656D01*
Y200526D01*
X1099421Y200876D01*
X1099596D01*
Y199306D01*
X1099421D01*
G37*
G36*
G01X1106206Y181011D02*
X1106772Y181506D01*
X1107055Y181224D01*
X1106560Y180658D01*
X1106419Y180516D01*
X1106065Y180870D01*
X1106206Y181011D01*
G37*
G36*
G01X1104368Y182850D02*
X1104934Y183345D01*
X1105217Y183062D01*
X1104722Y182496D01*
X1104580Y182355D01*
X1104227Y182708D01*
X1104368Y182850D01*
G37*
G36*
G01X1102530Y184688D02*
X1103095Y185183D01*
X1103378Y184900D01*
X1102883Y184335D01*
X1102742Y184193D01*
X1102388Y184547D01*
X1102530Y184688D01*
G37*
G36*
G01X1100691Y186527D02*
X1101257Y187022D01*
X1101540Y186739D01*
X1101045Y186173D01*
X1100903Y186032D01*
X1100550Y186385D01*
X1100691Y186527D01*
G37*
G36*
G01X1108045Y179173D02*
X1108611Y179668D01*
X1108893Y179385D01*
X1108399Y178819D01*
X1108257Y178678D01*
X1107904Y179031D01*
X1108045Y179173D01*
G37*
G36*
G01X1109883Y177334D02*
X1110449Y177829D01*
X1110732Y177547D01*
X1110237Y176981D01*
X1110096Y176839D01*
X1109742Y177193D01*
X1109883Y177334D01*
G37*
G36*
G01X1111722Y175496D02*
X1112288Y175991D01*
X1112570Y175708D01*
X1112075Y175142D01*
X1111934Y175001D01*
X1111580Y175355D01*
X1111722Y175496D01*
G37*
G36*
G01X1113560Y173657D02*
X1114126Y174152D01*
X1114409Y173870D01*
X1113914Y173304D01*
X1113773Y173162D01*
X1113419Y173516D01*
X1113560Y173657D01*
G37*
G36*
G01X1107196Y179456D02*
X1106631Y178961D01*
X1106348Y179244D01*
X1106843Y179809D01*
X1106984Y179951D01*
X1107338Y179597D01*
X1107196Y179456D01*
G37*
G36*
G01X1105358Y181294D02*
X1104792Y180799D01*
X1104509Y181082D01*
X1105004Y181648D01*
X1105146Y181789D01*
X1105499Y181436D01*
X1105358Y181294D01*
G37*
G36*
G01X1103519Y183133D02*
X1102954Y182638D01*
X1102671Y182921D01*
X1103166Y183486D01*
X1103307Y183628D01*
X1103661Y183274D01*
X1103519Y183133D01*
G37*
G36*
G01X1101681Y184971D02*
X1101115Y184476D01*
X1100832Y184759D01*
X1101327Y185325D01*
X1101469Y185466D01*
X1101822Y185113D01*
X1101681Y184971D01*
G37*
G36*
G01X1099843Y186810D02*
X1099277Y186315D01*
X1098994Y186598D01*
X1099489Y187163D01*
X1099630Y187305D01*
X1099984Y186951D01*
X1099843Y186810D01*
G37*
G36*
G01X1109035Y177617D02*
X1108469Y177122D01*
X1108186Y177405D01*
X1108681Y177971D01*
X1108823Y178112D01*
X1109176Y177759D01*
X1109035Y177617D01*
G37*
G36*
G01X1110873Y175779D02*
X1110308Y175284D01*
X1110025Y175567D01*
X1110520Y176132D01*
X1110661Y176274D01*
X1111015Y175920D01*
X1110873Y175779D01*
G37*
G36*
G01X1112712Y173940D02*
X1112146Y173445D01*
X1111863Y173728D01*
X1112358Y174294D01*
X1112500Y174435D01*
X1112853Y174082D01*
X1112712Y173940D01*
G37*
G36*
G01X1099406Y189052D02*
X1100156Y189002D01*
Y188602D01*
X1099406Y188552D01*
X1099206D01*
Y189052D01*
X1099406D01*
G37*
G36*
G01X1115399Y171819D02*
X1115965Y172314D01*
X1116247Y172031D01*
X1115752Y171465D01*
X1115611Y171324D01*
X1115257Y171678D01*
X1115399Y171819D01*
G37*
G36*
G01X1117237Y169981D02*
X1117803Y170475D01*
X1118086Y170193D01*
X1117591Y169627D01*
X1117449Y169486D01*
X1117096Y169839D01*
X1117237Y169981D01*
G37*
G36*
G01X1114550Y172102D02*
X1113985Y171607D01*
X1113702Y171890D01*
X1114197Y172455D01*
X1114338Y172597D01*
X1114692Y172243D01*
X1114550Y172102D01*
G37*
G36*
G01X1116389Y170263D02*
X1115823Y169768D01*
X1115540Y170051D01*
X1116035Y170617D01*
X1116177Y170758D01*
X1116530Y170405D01*
X1116389Y170263D01*
G37*
G36*
G01X1118312Y167564D02*
X1119062Y167514D01*
Y167114D01*
X1118312Y167064D01*
X1118112D01*
Y167564D01*
X1118312D01*
G37*
G36*
G01Y164964D02*
X1119062Y164914D01*
Y164514D01*
X1118312Y164464D01*
X1118112D01*
Y164964D01*
X1118312D01*
G37*
G36*
G01X1117912Y165764D02*
X1117162Y165814D01*
Y166214D01*
X1117912Y166264D01*
X1118112D01*
Y165764D01*
X1117912D01*
G37*
G36*
G01X1126566Y190918D02*
X1127132Y191413D01*
X1127415Y191131D01*
X1126920Y190565D01*
X1126779Y190423D01*
X1126425Y190777D01*
X1126566Y190918D01*
G37*
G36*
G01X1124728Y192757D02*
X1125294Y193252D01*
X1125576Y192969D01*
X1125081Y192403D01*
X1124940Y192262D01*
X1124587Y192615D01*
X1124728Y192757D01*
G37*
G36*
G01X1125718Y191201D02*
X1125152Y190706D01*
X1124869Y190989D01*
X1125364Y191555D01*
X1125506Y191696D01*
X1125859Y191343D01*
X1125718Y191201D01*
G37*
G36*
G01X1123879Y193040D02*
X1123314Y192545D01*
X1123031Y192828D01*
X1123526Y193393D01*
X1123667Y193535D01*
X1124021Y193181D01*
X1123879Y193040D01*
G37*
G36*
G01X1119238Y198480D02*
X1118568Y198830D01*
Y199700D01*
X1119238Y200050D01*
X1119413D01*
Y198480D01*
X1119238D01*
G37*
G36*
G01X1121824Y194823D02*
X1121103Y194597D01*
X1120488Y195212D01*
X1120714Y195933D01*
X1120838Y196057D01*
X1121948Y194947D01*
X1121824Y194823D01*
G37*
G36*
G01X1127556Y189363D02*
X1126991Y188868D01*
X1126708Y189151D01*
X1127203Y189716D01*
X1127344Y189858D01*
X1127698Y189504D01*
X1127556Y189363D01*
G37*
G36*
G01X1132082Y185403D02*
X1132648Y185898D01*
X1132930Y185615D01*
X1132435Y185049D01*
X1132294Y184908D01*
X1131940Y185262D01*
X1132082Y185403D01*
G37*
G36*
G01X1128405Y189080D02*
X1128971Y189575D01*
X1129253Y189292D01*
X1128758Y188726D01*
X1128617Y188585D01*
X1128263Y188939D01*
X1128405Y189080D01*
G37*
G36*
G01X1129395Y187524D02*
X1128829Y187029D01*
X1128546Y187312D01*
X1129041Y187878D01*
X1129183Y188019D01*
X1129536Y187666D01*
X1129395Y187524D01*
G37*
G36*
G01X1131233Y185686D02*
X1130668Y185191D01*
X1130385Y185474D01*
X1130880Y186039D01*
X1131021Y186181D01*
X1131375Y185827D01*
X1131233Y185686D01*
G37*
G36*
G01X1149443Y183906D02*
X1149393Y183156D01*
X1148993D01*
X1148943Y183906D01*
Y184106D01*
X1149443D01*
Y183906D01*
G37*
G36*
G01X1152043D02*
X1151993Y183156D01*
X1151593D01*
X1151543Y183906D01*
Y184106D01*
X1152043D01*
Y183906D01*
G37*
G36*
G01X1146843D02*
X1146793Y183156D01*
X1146393D01*
X1146343Y183906D01*
Y184106D01*
X1146843D01*
Y183906D01*
G37*
G36*
G01X1144243D02*
X1144193Y183156D01*
X1143793D01*
X1143743Y183906D01*
Y184106D01*
X1144243D01*
Y183906D01*
G37*
G36*
G01X1141643D02*
X1141593Y183156D01*
X1141193D01*
X1141143Y183906D01*
Y184106D01*
X1141643D01*
Y183906D01*
G37*
G36*
G01X1139043D02*
X1138993Y183156D01*
X1138593D01*
X1138543Y183906D01*
Y184106D01*
X1139043D01*
Y183906D01*
G37*
G36*
G01X1136443D02*
X1136393Y183156D01*
X1135993D01*
X1135943Y183906D01*
Y184106D01*
X1136443D01*
Y183906D01*
G37*
G36*
G01X1147643Y184306D02*
X1147693Y185056D01*
X1148093D01*
X1148143Y184306D01*
Y184106D01*
X1147643D01*
Y184306D01*
G37*
G36*
G01X1150243D02*
X1150293Y185056D01*
X1150693D01*
X1150743Y184306D01*
Y184106D01*
X1150243D01*
Y184306D01*
G37*
G36*
G01X1145043D02*
X1145093Y185056D01*
X1145493D01*
X1145543Y184306D01*
Y184106D01*
X1145043D01*
Y184306D01*
G37*
G36*
G01X1142443D02*
X1142493Y185056D01*
X1142893D01*
X1142943Y184306D01*
Y184106D01*
X1142443D01*
Y184306D01*
G37*
G36*
G01X1139843D02*
X1139893Y185056D01*
X1140293D01*
X1140343Y184306D01*
Y184106D01*
X1139843D01*
Y184306D01*
G37*
G36*
G01X1137243D02*
X1137293Y185056D01*
X1137693D01*
X1137743Y184306D01*
Y184106D01*
X1137243D01*
Y184306D01*
G37*
G36*
G01X1130243Y187241D02*
X1130809Y187736D01*
X1131092Y187454D01*
X1130597Y186888D01*
X1130455Y186747D01*
X1130102Y187100D01*
X1130243Y187241D01*
G37*
G36*
G01X1154643Y183906D02*
X1154593Y183156D01*
X1154193D01*
X1154143Y183906D01*
Y184106D01*
X1154643D01*
Y183906D01*
G37*
G36*
G01X1152843Y184306D02*
X1152893Y185056D01*
X1153293D01*
X1153343Y184306D01*
Y184106D01*
X1152843D01*
Y184306D01*
G37*
G36*
G01X1155443D02*
X1155493Y185056D01*
X1155893D01*
X1155943Y184306D01*
Y184106D01*
X1155443D01*
Y184306D01*
G37*
G36*
G01X1134643D02*
X1134693Y185056D01*
X1135093D01*
X1135143Y184306D01*
Y184106D01*
X1134643D01*
Y184306D01*
G37*
G36*
G01X1095906Y192452D02*
X1095156Y192502D01*
Y192902D01*
X1095906Y192952D01*
X1096106D01*
Y192452D01*
X1095906D01*
G37*
G36*
G01Y189852D02*
X1095156Y189902D01*
Y190302D01*
X1095906Y190352D01*
X1096106D01*
Y189852D01*
X1095906D01*
G37*
G36*
G01X1096306Y194252D02*
X1097056Y194202D01*
Y193802D01*
X1096306Y193752D01*
X1096106D01*
Y194252D01*
X1096306D01*
G37*
G36*
G01Y191652D02*
X1097056Y191602D01*
Y191202D01*
X1096306Y191152D01*
X1096106D01*
Y191652D01*
X1096306D01*
G37*
G36*
G01X1096325Y198264D02*
X1095655Y198614D01*
Y199484D01*
X1096325Y199834D01*
X1096500D01*
Y198264D01*
X1096325D01*
G37*
G36*
G01X1095906Y187252D02*
X1095156Y187302D01*
Y187702D01*
X1095906Y187752D01*
X1096106D01*
Y187252D01*
X1095906D01*
G37*
G36*
G01X1104013Y178818D02*
X1104579Y179313D01*
X1104862Y179031D01*
X1104367Y178465D01*
X1104226Y178323D01*
X1103872Y178677D01*
X1104013Y178818D01*
G37*
G36*
G01X1102175Y180657D02*
X1102741Y181152D01*
X1103024Y180869D01*
X1102529Y180303D01*
X1102387Y180162D01*
X1102034Y180515D01*
X1102175Y180657D01*
G37*
G36*
G01X1100337Y182495D02*
X1100902Y182990D01*
X1101185Y182707D01*
X1100690Y182142D01*
X1100549Y182000D01*
X1100195Y182354D01*
X1100337Y182495D01*
G37*
G36*
G01X1098498Y184334D02*
X1099064Y184829D01*
X1099347Y184546D01*
X1098852Y183980D01*
X1098710Y183839D01*
X1098357Y184192D01*
X1098498Y184334D01*
G37*
G36*
G01X1096660Y186172D02*
X1097225Y186667D01*
X1097508Y186384D01*
X1097013Y185819D01*
X1096872Y185677D01*
X1096518Y186031D01*
X1096660Y186172D01*
G37*
G36*
G01X1105852Y176980D02*
X1106418Y177475D01*
X1106700Y177192D01*
X1106206Y176626D01*
X1106064Y176485D01*
X1105711Y176838D01*
X1105852Y176980D01*
G37*
G36*
G01X1107690Y175141D02*
X1108256Y175636D01*
X1108539Y175354D01*
X1108044Y174788D01*
X1107903Y174646D01*
X1107549Y175000D01*
X1107690Y175141D01*
G37*
G36*
G01X1109529Y173303D02*
X1110095Y173798D01*
X1110377Y173515D01*
X1109882Y172949D01*
X1109741Y172808D01*
X1109387Y173162D01*
X1109529Y173303D01*
G37*
G36*
G01X1103165Y179101D02*
X1102599Y178606D01*
X1102316Y178889D01*
X1102811Y179455D01*
X1102953Y179596D01*
X1103306Y179243D01*
X1103165Y179101D01*
G37*
G36*
G01X1101326Y180940D02*
X1100761Y180445D01*
X1100478Y180728D01*
X1100973Y181293D01*
X1101114Y181435D01*
X1101468Y181081D01*
X1101326Y180940D01*
G37*
G36*
G01X1099488Y182778D02*
X1098922Y182283D01*
X1098639Y182566D01*
X1099134Y183132D01*
X1099276Y183273D01*
X1099629Y182920D01*
X1099488Y182778D01*
G37*
G36*
G01X1097650Y184617D02*
X1097084Y184122D01*
X1096801Y184405D01*
X1097296Y184970D01*
X1097437Y185112D01*
X1097791Y184758D01*
X1097650Y184617D01*
G37*
G36*
G01X1105003Y177263D02*
X1104438Y176768D01*
X1104155Y177051D01*
X1104650Y177616D01*
X1104791Y177758D01*
X1105145Y177404D01*
X1105003Y177263D01*
G37*
G36*
G01X1106842Y175424D02*
X1106276Y174929D01*
X1105993Y175212D01*
X1106488Y175778D01*
X1106630Y175919D01*
X1106983Y175566D01*
X1106842Y175424D01*
G37*
G36*
G01X1108680Y173586D02*
X1108115Y173091D01*
X1107832Y173374D01*
X1108327Y173939D01*
X1108468Y174081D01*
X1108822Y173727D01*
X1108680Y173586D01*
G37*
G36*
G01X1096306Y189052D02*
X1097056Y189002D01*
Y188602D01*
X1096306Y188552D01*
X1096106D01*
Y189052D01*
X1096306D01*
G37*
G36*
G01X1111367Y171464D02*
X1111933Y171959D01*
X1112216Y171677D01*
X1111721Y171111D01*
X1111580Y170969D01*
X1111226Y171323D01*
X1111367Y171464D01*
G37*
G36*
G01X1113206Y169626D02*
X1113772Y170121D01*
X1114054Y169838D01*
X1113559Y169272D01*
X1113418Y169131D01*
X1113064Y169485D01*
X1113206Y169626D01*
G37*
G36*
G01X1113612Y165764D02*
X1112862Y165814D01*
Y166214D01*
X1113612Y166264D01*
X1113812D01*
Y165764D01*
X1113612D01*
G37*
G36*
G01Y163164D02*
X1112862Y163214D01*
Y163614D01*
X1113612Y163664D01*
X1113812D01*
Y163164D01*
X1113612D01*
G37*
G36*
G01X1114012Y167564D02*
X1114762Y167514D01*
Y167114D01*
X1114012Y167064D01*
X1113812D01*
Y167564D01*
X1114012D01*
G37*
G36*
G01Y164964D02*
X1114762Y164914D01*
Y164514D01*
X1114012Y164464D01*
X1113812D01*
Y164964D01*
X1114012D01*
G37*
G36*
G01X1122534Y190564D02*
X1123100Y191059D01*
X1123383Y190777D01*
X1122888Y190211D01*
X1122747Y190069D01*
X1122393Y190423D01*
X1122534Y190564D01*
G37*
G36*
G01X1120696Y192403D02*
X1121262Y192898D01*
X1121544Y192615D01*
X1121050Y192049D01*
X1120908Y191908D01*
X1120555Y192261D01*
X1120696Y192403D01*
G37*
G36*
G01X1121687Y190847D02*
X1121121Y190352D01*
X1120838Y190635D01*
X1121333Y191201D01*
X1121475Y191342D01*
X1121828Y190989D01*
X1121687Y190847D01*
G37*
G36*
G01X1118955Y194140D02*
X1118234Y193914D01*
X1117619Y194529D01*
X1117845Y195250D01*
X1117969Y195374D01*
X1119079Y194264D01*
X1118955Y194140D01*
G37*
G36*
G01X1126211Y186887D02*
X1126777Y187382D01*
X1127060Y187100D01*
X1126565Y186534D01*
X1126424Y186392D01*
X1126070Y186746D01*
X1126211Y186887D01*
G37*
G36*
G01X1124373Y188726D02*
X1124939Y189221D01*
X1125221Y188938D01*
X1124726Y188372D01*
X1124585Y188231D01*
X1124231Y188585D01*
X1124373Y188726D01*
G37*
G36*
G01X1127202Y185332D02*
X1126637Y184837D01*
X1126354Y185120D01*
X1126849Y185685D01*
X1126990Y185827D01*
X1127344Y185473D01*
X1127202Y185332D01*
G37*
G36*
G01X1125364Y187170D02*
X1124798Y186675D01*
X1124515Y186958D01*
X1125010Y187524D01*
X1125152Y187665D01*
X1125505Y187312D01*
X1125364Y187170D01*
G37*
G36*
G01X1123525Y189009D02*
X1122960Y188514D01*
X1122677Y188797D01*
X1123172Y189362D01*
X1123313Y189504D01*
X1123667Y189150D01*
X1123525Y189009D01*
G37*
G36*
G01X1128050Y185049D02*
X1128616Y185544D01*
X1128898Y185261D01*
X1128403Y184695D01*
X1128262Y184554D01*
X1127908Y184908D01*
X1128050Y185049D01*
G37*
G36*
G01X1129888Y183211D02*
X1130454Y183705D01*
X1130737Y183423D01*
X1130242Y182857D01*
X1130100Y182716D01*
X1129747Y183069D01*
X1129888Y183211D01*
G37*
G36*
G01X1129041Y183493D02*
X1128475Y182998D01*
X1128192Y183281D01*
X1128687Y183847D01*
X1128829Y183988D01*
X1129182Y183635D01*
X1129041Y183493D01*
G37*
G36*
G01X1130879Y181655D02*
X1130314Y181160D01*
X1130031Y181443D01*
X1130526Y182008D01*
X1130667Y182150D01*
X1131021Y181796D01*
X1130879Y181655D01*
G37*
G36*
G01X1146843Y180806D02*
X1146793Y180056D01*
X1146393D01*
X1146343Y180806D01*
Y181006D01*
X1146843D01*
Y180806D01*
G37*
G36*
G01X1149443D02*
X1149393Y180056D01*
X1148993D01*
X1148943Y180806D01*
Y181006D01*
X1149443D01*
Y180806D01*
G37*
G36*
G01X1152043D02*
X1151993Y180056D01*
X1151593D01*
X1151543Y180806D01*
Y181006D01*
X1152043D01*
Y180806D01*
G37*
G36*
G01X1144243D02*
X1144193Y180056D01*
X1143793D01*
X1143743Y180806D01*
Y181006D01*
X1144243D01*
Y180806D01*
G37*
G36*
G01X1141643D02*
X1141593Y180056D01*
X1141193D01*
X1141143Y180806D01*
Y181006D01*
X1141643D01*
Y180806D01*
G37*
G36*
G01X1139043D02*
X1138993Y180056D01*
X1138593D01*
X1138543Y180806D01*
Y181006D01*
X1139043D01*
Y180806D01*
G37*
G36*
G01X1136443D02*
X1136393Y180056D01*
X1135993D01*
X1135943Y180806D01*
Y181006D01*
X1136443D01*
Y180806D01*
G37*
G36*
G01X1133843D02*
X1133793Y180056D01*
X1133393D01*
X1133343Y180806D01*
Y181006D01*
X1133843D01*
Y180806D01*
G37*
G36*
G01X1147643Y181206D02*
X1147693Y181956D01*
X1148093D01*
X1148143Y181206D01*
Y181006D01*
X1147643D01*
Y181206D01*
G37*
G36*
G01X1150243D02*
X1150293Y181956D01*
X1150693D01*
X1150743Y181206D01*
Y181006D01*
X1150243D01*
Y181206D01*
G37*
G36*
G01X1145043D02*
X1145093Y181956D01*
X1145493D01*
X1145543Y181206D01*
Y181006D01*
X1145043D01*
Y181206D01*
G37*
G36*
G01X1142443D02*
X1142493Y181956D01*
X1142893D01*
X1142943Y181206D01*
Y181006D01*
X1142443D01*
Y181206D01*
G37*
G36*
G01X1139843D02*
X1139893Y181956D01*
X1140293D01*
X1140343Y181206D01*
Y181006D01*
X1139843D01*
Y181206D01*
G37*
G36*
G01X1137243D02*
X1137293Y181956D01*
X1137693D01*
X1137743Y181206D01*
Y181006D01*
X1137243D01*
Y181206D01*
G37*
G36*
G01X1154643Y180806D02*
X1154593Y180056D01*
X1154193D01*
X1154143Y180806D01*
Y181006D01*
X1154643D01*
Y180806D01*
G37*
G36*
G01X1152843Y181206D02*
X1152893Y181956D01*
X1153293D01*
X1153343Y181206D01*
Y181006D01*
X1152843D01*
Y181206D01*
G37*
G36*
G01X1155443D02*
X1155493Y181956D01*
X1155893D01*
X1155943Y181206D01*
Y181006D01*
X1155443D01*
Y181206D01*
G37*
G36*
G01X1134643D02*
X1134693Y181956D01*
X1135093D01*
X1135143Y181206D01*
Y181006D01*
X1134643D01*
Y181206D01*
G37*
G36*
G01X1100956Y194252D02*
X1101706Y194202D01*
Y193802D01*
X1100956Y193752D01*
X1100756D01*
Y194252D01*
X1100956D01*
G37*
G36*
G01Y191652D02*
X1101706Y191602D01*
Y191202D01*
X1100956Y191152D01*
X1100756D01*
Y191652D01*
X1100956D01*
G37*
G36*
G01X1100556Y192452D02*
X1099806Y192502D01*
Y192902D01*
X1100556Y192952D01*
X1100756D01*
Y192452D01*
X1100556D01*
G37*
G36*
G01Y189852D02*
X1099806Y189902D01*
Y190302D01*
X1100556Y190352D01*
X1100756D01*
Y189852D01*
X1100556D01*
G37*
G36*
G01X1100521Y200930D02*
X1101191Y200580D01*
Y199710D01*
X1100521Y199360D01*
X1100346D01*
Y200930D01*
X1100521D01*
G37*
G36*
G01X1109141Y180269D02*
X1109707Y180764D01*
X1109990Y180482D01*
X1109495Y179916D01*
X1109354Y179774D01*
X1109000Y180128D01*
X1109141Y180269D01*
G37*
G36*
G01X1107303Y182108D02*
X1107869Y182603D01*
X1108152Y182320D01*
X1107657Y181754D01*
X1107515Y181613D01*
X1107162Y181966D01*
X1107303Y182108D01*
G37*
G36*
G01X1105464Y183946D02*
X1106030Y184441D01*
X1106313Y184158D01*
X1105818Y183593D01*
X1105677Y183451D01*
X1105323Y183805D01*
X1105464Y183946D01*
G37*
G36*
G01X1103626Y185785D02*
X1104192Y186280D01*
X1104475Y185997D01*
X1103980Y185431D01*
X1103838Y185290D01*
X1103485Y185643D01*
X1103626Y185785D01*
G37*
G36*
G01X1101788Y187623D02*
X1102353Y188118D01*
X1102636Y187835D01*
X1102141Y187270D01*
X1102000Y187128D01*
X1101646Y187482D01*
X1101788Y187623D01*
G37*
G36*
G01X1110980Y178431D02*
X1111546Y178926D01*
X1111828Y178643D01*
X1111333Y178077D01*
X1111192Y177936D01*
X1110839Y178289D01*
X1110980Y178431D01*
G37*
G36*
G01X1112818Y176592D02*
X1113384Y177087D01*
X1113667Y176805D01*
X1113172Y176239D01*
X1113031Y176097D01*
X1112677Y176451D01*
X1112818Y176592D01*
G37*
G36*
G01X1114657Y174754D02*
X1115223Y175249D01*
X1115505Y174966D01*
X1115010Y174400D01*
X1114869Y174259D01*
X1114515Y174613D01*
X1114657Y174754D01*
G37*
G36*
G01X1108293Y180552D02*
X1107727Y180057D01*
X1107444Y180340D01*
X1107939Y180906D01*
X1108081Y181047D01*
X1108434Y180694D01*
X1108293Y180552D01*
G37*
G36*
G01X1106454Y182391D02*
X1105889Y181896D01*
X1105606Y182179D01*
X1106101Y182744D01*
X1106242Y182886D01*
X1106596Y182532D01*
X1106454Y182391D01*
G37*
G36*
G01X1104616Y184229D02*
X1104050Y183734D01*
X1103767Y184017D01*
X1104262Y184583D01*
X1104404Y184724D01*
X1104757Y184371D01*
X1104616Y184229D01*
G37*
G36*
G01X1102777Y186068D02*
X1102212Y185573D01*
X1101929Y185856D01*
X1102424Y186421D01*
X1102565Y186563D01*
X1102919Y186209D01*
X1102777Y186068D01*
G37*
G36*
G01X1110131Y178714D02*
X1109566Y178219D01*
X1109283Y178502D01*
X1109778Y179067D01*
X1109919Y179209D01*
X1110273Y178855D01*
X1110131Y178714D01*
G37*
G36*
G01X1111970Y176875D02*
X1111404Y176380D01*
X1111121Y176663D01*
X1111616Y177229D01*
X1111758Y177370D01*
X1112111Y177017D01*
X1111970Y176875D01*
G37*
G36*
G01X1113808Y175037D02*
X1113243Y174542D01*
X1112960Y174825D01*
X1113455Y175390D01*
X1113596Y175532D01*
X1113950Y175178D01*
X1113808Y175037D01*
G37*
G36*
G01X1115647Y173198D02*
X1115081Y172703D01*
X1114798Y172986D01*
X1115293Y173552D01*
X1115435Y173693D01*
X1115788Y173340D01*
X1115647Y173198D01*
G37*
G36*
G01X1116495Y172915D02*
X1117061Y173410D01*
X1117344Y173128D01*
X1116849Y172562D01*
X1116707Y172421D01*
X1116354Y172774D01*
X1116495Y172915D01*
G37*
G36*
G01X1118334Y171077D02*
X1118900Y171572D01*
X1119182Y171289D01*
X1118687Y170723D01*
X1118546Y170582D01*
X1118192Y170936D01*
X1118334Y171077D01*
G37*
G36*
G01X1117485Y171360D02*
X1116920Y170865D01*
X1116637Y171148D01*
X1117132Y171713D01*
X1117273Y171855D01*
X1117627Y171501D01*
X1117485Y171360D01*
G37*
G36*
G01X1119862Y167564D02*
X1120612Y167514D01*
Y167114D01*
X1119862Y167064D01*
X1119662D01*
Y167564D01*
X1119862D01*
G37*
G36*
G01Y164964D02*
X1120612Y164914D01*
Y164514D01*
X1119862Y164464D01*
X1119662D01*
Y164964D01*
X1119862D01*
G37*
G36*
G01X1119462Y168364D02*
X1118712Y168414D01*
Y168814D01*
X1119462Y168864D01*
X1119662D01*
Y168364D01*
X1119462D01*
G37*
G36*
G01Y165764D02*
X1118712Y165814D01*
Y166214D01*
X1119462Y166264D01*
X1119662D01*
Y165764D01*
X1119462D01*
G37*
G36*
G01X1125824Y193853D02*
X1126390Y194348D01*
X1126673Y194066D01*
X1126178Y193500D01*
X1126037Y193358D01*
X1125683Y193712D01*
X1125824Y193853D01*
G37*
G36*
G01X1126814Y192298D02*
X1126249Y191803D01*
X1125966Y192086D01*
X1126461Y192651D01*
X1126602Y192793D01*
X1126956Y192439D01*
X1126814Y192298D01*
G37*
G36*
G01X1124976Y194136D02*
X1124410Y193641D01*
X1124127Y193924D01*
X1124622Y194490D01*
X1124764Y194631D01*
X1125117Y194278D01*
X1124976Y194136D01*
G37*
G36*
G01X1120920Y203273D02*
X1121590Y202923D01*
Y202053D01*
X1120920Y201703D01*
X1120745D01*
Y203273D01*
X1120920D01*
G37*
G36*
G01X1120338Y200104D02*
X1121008Y199754D01*
Y198884D01*
X1120338Y198534D01*
X1120163D01*
Y200104D01*
X1120338D01*
G37*
G36*
G01X1120892Y207188D02*
X1121562Y206838D01*
Y205968D01*
X1120892Y205618D01*
X1120718D01*
X1120717Y207189D01*
X1120892Y207188D01*
G37*
G36*
G01X1129501Y190176D02*
X1130067Y190671D01*
X1130350Y190389D01*
X1129855Y189823D01*
X1129714Y189681D01*
X1129360Y190035D01*
X1129501Y190176D01*
G37*
G36*
G01X1127663Y192015D02*
X1128229Y192510D01*
X1128511Y192227D01*
X1128016Y191661D01*
X1127875Y191520D01*
X1127521Y191874D01*
X1127663Y192015D01*
G37*
G36*
G01X1128653Y190459D02*
X1128087Y189964D01*
X1127804Y190247D01*
X1128299Y190813D01*
X1128441Y190954D01*
X1128794Y190601D01*
X1128653Y190459D01*
G37*
G36*
G01X1131340Y188338D02*
X1131906Y188833D01*
X1132188Y188550D01*
X1131693Y187984D01*
X1131552Y187843D01*
X1131198Y188197D01*
X1131340Y188338D01*
G37*
G36*
G01X1132330Y186782D02*
X1131764Y186287D01*
X1131481Y186570D01*
X1131976Y187136D01*
X1132118Y187277D01*
X1132471Y186924D01*
X1132330Y186782D01*
G37*
G36*
G01X1149443Y185456D02*
X1149393Y184706D01*
X1148993D01*
X1148943Y185456D01*
Y185656D01*
X1149443D01*
Y185456D01*
G37*
G36*
G01X1152043D02*
X1151993Y184706D01*
X1151593D01*
X1151543Y185456D01*
Y185656D01*
X1152043D01*
Y185456D01*
G37*
G36*
G01X1146843D02*
X1146793Y184706D01*
X1146393D01*
X1146343Y185456D01*
Y185656D01*
X1146843D01*
Y185456D01*
G37*
G36*
G01X1144243D02*
X1144193Y184706D01*
X1143793D01*
X1143743Y185456D01*
Y185656D01*
X1144243D01*
Y185456D01*
G37*
G36*
G01X1141643D02*
X1141593Y184706D01*
X1141193D01*
X1141143Y185456D01*
Y185656D01*
X1141643D01*
Y185456D01*
G37*
G36*
G01X1139043D02*
X1138993Y184706D01*
X1138593D01*
X1138543Y185456D01*
Y185656D01*
X1139043D01*
Y185456D01*
G37*
G36*
G01X1136443D02*
X1136393Y184706D01*
X1135993D01*
X1135943Y185456D01*
Y185656D01*
X1136443D01*
Y185456D01*
G37*
G36*
G01X1147643Y185856D02*
X1147693Y186606D01*
X1148093D01*
X1148143Y185856D01*
Y185656D01*
X1147643D01*
Y185856D01*
G37*
G36*
G01X1150243D02*
X1150293Y186606D01*
X1150693D01*
X1150743Y185856D01*
Y185656D01*
X1150243D01*
Y185856D01*
G37*
G36*
G01X1145043D02*
X1145093Y186606D01*
X1145493D01*
X1145543Y185856D01*
Y185656D01*
X1145043D01*
Y185856D01*
G37*
G36*
G01X1142443D02*
X1142493Y186606D01*
X1142893D01*
X1142943Y185856D01*
Y185656D01*
X1142443D01*
Y185856D01*
G37*
G36*
G01X1139843D02*
X1139893Y186606D01*
X1140293D01*
X1140343Y185856D01*
Y185656D01*
X1139843D01*
Y185856D01*
G37*
G36*
G01X1137243D02*
X1137293Y186606D01*
X1137693D01*
X1137743Y185856D01*
Y185656D01*
X1137243D01*
Y185856D01*
G37*
G36*
G01X1130491Y188621D02*
X1129926Y188126D01*
X1129643Y188409D01*
X1130138Y188974D01*
X1130279Y189116D01*
X1130633Y188762D01*
X1130491Y188621D01*
G37*
G36*
G01X1154643Y185456D02*
X1154593Y184706D01*
X1154193D01*
X1154143Y185456D01*
Y185656D01*
X1154643D01*
Y185456D01*
G37*
G36*
G01X1152843Y185856D02*
X1152893Y186606D01*
X1153293D01*
X1153343Y185856D01*
Y185656D01*
X1152843D01*
Y185856D01*
G37*
G36*
G01X1155443D02*
X1155493Y186606D01*
X1155893D01*
X1155943Y185856D01*
Y185656D01*
X1155443D01*
Y185856D01*
G37*
G36*
G01X1134643D02*
X1134693Y186606D01*
X1135093D01*
X1135143Y185856D01*
Y185656D01*
X1134643D01*
Y185856D01*
G37*
G36*
G01X1257463Y143816D02*
X1257215Y144064D01*
X1253653D01*
G02X1253296Y144645I0J400D01*
G03X1251009Y146361I-1296J655D01*
G02X1250453Y146370I-273J292D01*
G01X1247134Y149689D01*
X1238417D01*
X1238373Y149712D01*
G03X1237207Y149787I-668J-1289D01*
G01X1237088Y149744D01*
X1235243Y151588D01*
X1229969D01*
X1228070Y149689D01*
X1221511D01*
X1179092Y192108D01*
X1167100D01*
X1164408Y194800D01*
X1156000D01*
X1154400Y196400D01*
Y204608D01*
X1154992Y205200D01*
X1158426D01*
X1158461Y205186D01*
G03X1159439I489J1261D01*
G01X1159474Y205200D01*
X1160454D01*
G03X1161946I746J1246D01*
G01X1165186D01*
X1165221Y205186D01*
G03X1166199I489J1261D01*
G01X1166234Y205200D01*
X1167216D01*
G03X1168704I744J1247D01*
G01X1170096D01*
X1170248Y205048D01*
Y201552D01*
X1171800Y200000D01*
X1172083D01*
X1172088Y199994D01*
X1186632D01*
X1192326Y194300D01*
X1197300D01*
X1202500Y189100D01*
X1238466D01*
X1240344Y187222D01*
X1240359Y187183D01*
G03X1241185Y186357I1353J527D01*
G01X1241224Y186342D01*
X1251360Y176207D01*
X1251353Y176115D01*
G03X1252915Y174553I1447J-115D01*
G01X1253007Y174560D01*
X1258174Y169393D01*
X1258063Y169253D01*
G03X1260103Y167213I1137J-903D01*
G01X1260243Y167324D01*
X1266639Y160928D01*
X1266647Y160918D01*
G03X1266918Y160647I1153J882D01*
G01X1266928Y160639D01*
X1267167Y160400D01*
X1267414D01*
X1267439Y160394D01*
G03X1268161I361J1406D01*
G01X1268186Y160400D01*
X1293499D01*
G02X1293899Y159994I0J-400D01*
G03X1294368Y158838I1601J-24D01*
G01X1295868Y157337D01*
X1295875Y157267D01*
G03X1299352Y157194I1743J178D01*
G02X1300031Y157420I396J-57D01*
G01X1301607Y155844D01*
X1301906D01*
X1301943Y155828D01*
G03X1302857Y159181I674J1617D01*
G01X1302790Y159190D01*
X1302263Y159717D01*
G02X1302545Y160400I283J283D01*
G01X1309798D01*
X1310377Y159821D01*
Y156008D01*
X1311065Y155320D01*
Y154164D01*
X1309180Y152279D01*
Y151201D01*
X1308639Y150660D01*
Y149439D01*
X1309518Y148560D01*
X1310218D01*
X1310371Y148407D01*
Y146403D01*
X1311164Y145610D01*
Y144483D01*
X1310574Y143893D01*
X1303998D01*
X1301848Y146043D01*
X1296644D01*
G03X1295700Y146302I-945J-1593D01*
G01X1284683D01*
X1284425Y146043D01*
X1279436D01*
X1279394Y146187D01*
G03X1278993Y146839I-1394J-408D01*
G02X1278999Y147429I273J292D01*
G03X1277037Y147451I-969J1081D01*
G02X1277031Y146861I-273J-292D01*
G03X1276606Y146187I969J-1082D01*
G01X1276564Y146043D01*
X1271167D01*
X1271061Y145936D01*
X1264981D01*
X1262861Y143816D01*
X1261750D01*
G02X1261362Y144310I1J400D01*
G03X1258538I-1412J340D01*
G02X1258150Y143816I-389J-94D01*
G01X1257463D01*
G37*
G36*
G01X1128481Y312334D02*
Y311159D01*
X1128313Y311131D01*
G03X1127211Y309498I217J-1335D01*
G02X1127063Y309259I-195J-45D01*
G03X1126403Y308903I336J-1413D01*
G01X1126346Y308848D01*
X1126061D01*
X1126006Y308894D01*
G03X1123809Y308016I-856J-1047D01*
G01X1123787Y307841D01*
X1117256D01*
X1115255Y309842D01*
Y315127D01*
X1113541Y316841D01*
X1113148D01*
X1113112Y316855D01*
G03X1111918I-597J-1486D01*
G01X1111882Y316841D01*
X1110858D01*
Y316902D01*
X1107694D01*
X1107498Y317098D01*
Y320598D01*
X1107900Y321000D01*
X1112300D01*
X1113264Y321964D01*
X1113358Y321955D01*
G03X1114491Y322339I142J1445D01*
G01X1117723D01*
G02X1118111Y321843I0J-400D01*
G03X1120518Y320440I1410J-347D01*
G01X1120575Y320494D01*
X1120783D01*
X1120840Y320444D01*
G03X1122830Y320574I931J1047D01*
G02X1123415Y320595I302J-262D01*
G01X1123910Y320100D01*
X1123870Y319982D01*
G03X1124633Y318298I1280J-435D01*
G01X1124756Y318247D01*
Y316947D01*
X1124633Y316896D01*
G03X1126006Y314600I517J-1249D01*
G01X1126061Y314646D01*
X1126346D01*
X1126403Y314591D01*
G03X1127063Y314235I996J1057D01*
G02X1127212Y313996I-46J-195D01*
G03X1128313Y312362I1318J-300D01*
G01X1128481Y312334D01*
G37*
G36*
G01X1109129Y400709D02*
X1108459Y401059D01*
Y401929D01*
X1109129Y402279D01*
X1109304D01*
Y400709D01*
X1109129D01*
G37*
G36*
G01X1096362Y396781D02*
X1095691Y397131D01*
Y398000D01*
X1096360Y398351D01*
X1096534D01*
X1096537Y396781D01*
X1096362D01*
G37*
G36*
G01X1100100Y395617D02*
X1099685Y394986D01*
X1098820Y395073D01*
X1098539Y395774D01*
X1098556Y395948D01*
X1100118Y395792D01*
X1100100Y395617D01*
G37*
G36*
G01X1097235Y404197D02*
X1097905Y403847D01*
Y402977D01*
X1097235Y402627D01*
X1097060D01*
Y404197D01*
X1097235D01*
G37*
G36*
G01X1097331Y399921D02*
X1098086Y399887D01*
X1098454Y399099D01*
X1097994Y398499D01*
X1097836Y398425D01*
X1097172Y399847D01*
X1097331Y399921D01*
G37*
G36*
G01X1107373Y402257D02*
X1108043Y401907D01*
Y401037D01*
X1107373Y400687D01*
X1107198D01*
Y402257D01*
X1107373D01*
G37*
G36*
G01X1106500Y398713D02*
X1105830Y399063D01*
Y399933D01*
X1106500Y400283D01*
X1106675D01*
Y398713D01*
X1106500D01*
G37*
G36*
G01X1129410Y400578D02*
X1128740Y400928D01*
X1128739Y401798D01*
X1129410Y402147D01*
X1129584Y402148D01*
X1129585Y400578D01*
X1129410D01*
G37*
G36*
G01X1131032Y404206D02*
X1131702Y403856D01*
Y402986D01*
X1131032Y402636D01*
X1130857D01*
Y404206D01*
X1131032D01*
G37*
G36*
G01X1118176Y395649D02*
X1117538Y395244D01*
X1116785Y395679D01*
X1116817Y396434D01*
X1116904Y396585D01*
X1118264Y395801D01*
X1118176Y395649D01*
G37*
G36*
G01X1126779Y398731D02*
X1126109Y399081D01*
Y399951D01*
X1126779Y400301D01*
X1126954D01*
Y398731D01*
X1126779D01*
G37*
G36*
G01X1127652Y402207D02*
X1128322Y401857D01*
Y400987D01*
X1127652Y400637D01*
X1127477D01*
Y402207D01*
X1127652D01*
G37*
G36*
G01X1103993Y404206D02*
X1104663Y403856D01*
Y402986D01*
X1103993Y402636D01*
X1103818D01*
Y404206D01*
X1103993D01*
G37*
G36*
G01Y400281D02*
X1104663Y399931D01*
Y399061D01*
X1103993Y398711D01*
X1103818D01*
Y400281D01*
X1103993D01*
G37*
G36*
G01X1124271Y404217D02*
X1124941Y403867D01*
Y402997D01*
X1124271Y402647D01*
X1124096D01*
Y404217D01*
X1124271D01*
G37*
G36*
G01X1102369Y400637D02*
X1101699Y400987D01*
Y401857D01*
X1102369Y402207D01*
X1102544D01*
Y400637D01*
X1102369D01*
G37*
G36*
G01X1122649Y396720D02*
X1121979Y397070D01*
Y397940D01*
X1122649Y398289D01*
X1122823Y398290D01*
X1122824Y396720D01*
X1122649D01*
G37*
G36*
G01X1099005Y413812D02*
X1098245Y414162D01*
Y415062D01*
X1099005Y415412D01*
X1099180D01*
Y413812D01*
X1099005D01*
G37*
G36*
G01Y409912D02*
X1098245Y410262D01*
Y411162D01*
X1099005Y411512D01*
X1099180D01*
Y409912D01*
X1099005D01*
G37*
G36*
G01X1098580Y420376D02*
X1097830Y420426D01*
Y420826D01*
X1098580Y420876D01*
X1098780D01*
Y420376D01*
X1098580D01*
G37*
G36*
G01Y417776D02*
X1097830Y417826D01*
Y418226D01*
X1098580Y418276D01*
X1098780D01*
Y417776D01*
X1098580D01*
G37*
G36*
G01X1098980Y419576D02*
X1099730Y419526D01*
Y419126D01*
X1098980Y419076D01*
X1098780D01*
Y419576D01*
X1098980D01*
G37*
G36*
G01X1098580Y425576D02*
X1097830Y425626D01*
Y426026D01*
X1098580Y426076D01*
X1098780D01*
Y425576D01*
X1098580D01*
G37*
G36*
G01Y428176D02*
X1097830Y428226D01*
Y428626D01*
X1098580Y428676D01*
X1098780D01*
Y428176D01*
X1098580D01*
G37*
G36*
G01Y422976D02*
X1097830Y423026D01*
Y423426D01*
X1098580Y423476D01*
X1098780D01*
Y422976D01*
X1098580D01*
G37*
G36*
G01X1098980Y427376D02*
X1099730Y427326D01*
Y426926D01*
X1098980Y426876D01*
X1098780D01*
Y427376D01*
X1098980D01*
G37*
G36*
G01Y429976D02*
X1099730Y429926D01*
Y429526D01*
X1098980Y429476D01*
X1098780D01*
Y429976D01*
X1098980D01*
G37*
G36*
G01Y424776D02*
X1099730Y424726D01*
Y424326D01*
X1098980Y424276D01*
X1098780D01*
Y424776D01*
X1098980D01*
G37*
G36*
G01Y422176D02*
X1099730Y422126D01*
Y421726D01*
X1098980Y421676D01*
X1098780D01*
Y422176D01*
X1098980D01*
G37*
G36*
G01X1108480Y440365D02*
X1108975Y439799D01*
X1108693Y439516D01*
X1108127Y440011D01*
X1107985Y440152D01*
X1108339Y440506D01*
X1108480Y440365D01*
G37*
G36*
G01X1110319Y442203D02*
X1110814Y441637D01*
X1110531Y441355D01*
X1109965Y441850D01*
X1109824Y441991D01*
X1110178Y442345D01*
X1110319Y442203D01*
G37*
G36*
G01X1106642Y438526D02*
X1107137Y437960D01*
X1106854Y437678D01*
X1106288Y438173D01*
X1106147Y438314D01*
X1106501Y438668D01*
X1106642Y438526D01*
G37*
G36*
G01X1104804Y436688D02*
X1105298Y436122D01*
X1105016Y435839D01*
X1104450Y436334D01*
X1104309Y436476D01*
X1104662Y436829D01*
X1104804Y436688D01*
G37*
G36*
G01X1102965Y434849D02*
X1103460Y434283D01*
X1103177Y434001D01*
X1102611Y434496D01*
X1102470Y434637D01*
X1102824Y434991D01*
X1102965Y434849D01*
G37*
G36*
G01X1101127Y433011D02*
X1101622Y432445D01*
X1101339Y432162D01*
X1100773Y432657D01*
X1100632Y432799D01*
X1100985Y433152D01*
X1101127Y433011D01*
G37*
G36*
G01X1106925Y439375D02*
X1106430Y439940D01*
X1106713Y440223D01*
X1107278Y439728D01*
X1107420Y439587D01*
X1107066Y439233D01*
X1106925Y439375D01*
G37*
G36*
G01X1108763Y441213D02*
X1108268Y441779D01*
X1108551Y442062D01*
X1109117Y441567D01*
X1109258Y441425D01*
X1108905Y441072D01*
X1108763Y441213D01*
G37*
G36*
G01X1110602Y443052D02*
X1110107Y443617D01*
X1110390Y443900D01*
X1110955Y443405D01*
X1111097Y443264D01*
X1110743Y442910D01*
X1110602Y443052D01*
G37*
G36*
G01X1105086Y437536D02*
X1104591Y438102D01*
X1104874Y438385D01*
X1105440Y437890D01*
X1105581Y437748D01*
X1105228Y437395D01*
X1105086Y437536D01*
G37*
G36*
G01X1103248Y435698D02*
X1102753Y436263D01*
X1103036Y436546D01*
X1103601Y436051D01*
X1103743Y435910D01*
X1103389Y435556D01*
X1103248Y435698D01*
G37*
G36*
G01X1101409Y433859D02*
X1100914Y434425D01*
X1101197Y434708D01*
X1101763Y434213D01*
X1101904Y434071D01*
X1101551Y433718D01*
X1101409Y433859D01*
G37*
G36*
G01X1099571Y432021D02*
X1099076Y432586D01*
X1099359Y432869D01*
X1099924Y432374D01*
X1100066Y432233D01*
X1099712Y431879D01*
X1099571Y432021D01*
G37*
G36*
G01X1112157Y444042D02*
X1112652Y443476D01*
X1112369Y443194D01*
X1111803Y443689D01*
X1111662Y443830D01*
X1112016Y444184D01*
X1112157Y444042D01*
G37*
G36*
G01X1100105Y415412D02*
X1100865Y415062D01*
Y414162D01*
X1100105Y413812D01*
X1099930D01*
Y415412D01*
X1100105D01*
G37*
G36*
G01Y411512D02*
X1100865Y411162D01*
Y410262D01*
X1100105Y409912D01*
X1099930D01*
Y411512D01*
X1100105D01*
G37*
G36*
G01X1100130Y420376D02*
X1099380Y420426D01*
Y420826D01*
X1100130Y420876D01*
X1100330D01*
Y420376D01*
X1100130D01*
G37*
G36*
G01Y417776D02*
X1099380Y417826D01*
Y418226D01*
X1100130Y418276D01*
X1100330D01*
Y417776D01*
X1100130D01*
G37*
G36*
G01X1100530Y419576D02*
X1101280Y419526D01*
Y419126D01*
X1100530Y419076D01*
X1100330D01*
Y419576D01*
X1100530D01*
G37*
G36*
G01X1100130Y425576D02*
X1099380Y425626D01*
Y426026D01*
X1100130Y426076D01*
X1100330D01*
Y425576D01*
X1100130D01*
G37*
G36*
G01Y428176D02*
X1099380Y428226D01*
Y428626D01*
X1100130Y428676D01*
X1100330D01*
Y428176D01*
X1100130D01*
G37*
G36*
G01Y422976D02*
X1099380Y423026D01*
Y423426D01*
X1100130Y423476D01*
X1100330D01*
Y422976D01*
X1100130D01*
G37*
G36*
G01X1100530Y427376D02*
X1101280Y427326D01*
Y426926D01*
X1100530Y426876D01*
X1100330D01*
Y427376D01*
X1100530D01*
G37*
G36*
G01Y424776D02*
X1101280Y424726D01*
Y424326D01*
X1100530Y424276D01*
X1100330D01*
Y424776D01*
X1100530D01*
G37*
G36*
G01Y422176D02*
X1101280Y422126D01*
Y421726D01*
X1100530Y421676D01*
X1100330D01*
Y422176D01*
X1100530D01*
G37*
G36*
G01X1109577Y439268D02*
X1110072Y438702D01*
X1109789Y438420D01*
X1109223Y438915D01*
X1109082Y439056D01*
X1109436Y439410D01*
X1109577Y439268D01*
G37*
G36*
G01X1111415Y441107D02*
X1111910Y440541D01*
X1111628Y440258D01*
X1111062Y440753D01*
X1110920Y440894D01*
X1111274Y441248D01*
X1111415Y441107D01*
G37*
G36*
G01X1113254Y442945D02*
X1113749Y442379D01*
X1113466Y442097D01*
X1112900Y442592D01*
X1112759Y442733D01*
X1113112Y443086D01*
X1113254Y442945D01*
G37*
G36*
G01X1107738Y437430D02*
X1108233Y436864D01*
X1107951Y436581D01*
X1107385Y437076D01*
X1107244Y437218D01*
X1107597Y437571D01*
X1107738Y437430D01*
G37*
G36*
G01X1105900Y435591D02*
X1106395Y435025D01*
X1106112Y434743D01*
X1105546Y435238D01*
X1105405Y435379D01*
X1105759Y435733D01*
X1105900Y435591D01*
G37*
G36*
G01X1104062Y433753D02*
X1104557Y433187D01*
X1104274Y432904D01*
X1103708Y433399D01*
X1103567Y433541D01*
X1103920Y433894D01*
X1104062Y433753D01*
G37*
G36*
G01X1102223Y431914D02*
X1102718Y431349D01*
X1102435Y431066D01*
X1101869Y431561D01*
X1101728Y431702D01*
X1102082Y432056D01*
X1102223Y431914D01*
G37*
G36*
G01X1109860Y440117D02*
X1109365Y440682D01*
X1109648Y440965D01*
X1110213Y440470D01*
X1110355Y440329D01*
X1110001Y439975D01*
X1109860Y440117D01*
G37*
G36*
G01X1111698Y441955D02*
X1111203Y442521D01*
X1111486Y442804D01*
X1112052Y442309D01*
X1112193Y442167D01*
X1111840Y441814D01*
X1111698Y441955D01*
G37*
G36*
G01X1108021Y438278D02*
X1107526Y438844D01*
X1107809Y439127D01*
X1108375Y438632D01*
X1108516Y438490D01*
X1108163Y438137D01*
X1108021Y438278D01*
G37*
G36*
G01X1106183Y436440D02*
X1105688Y437005D01*
X1105971Y437288D01*
X1106536Y436793D01*
X1106678Y436652D01*
X1106324Y436298D01*
X1106183Y436440D01*
G37*
G36*
G01X1104344Y434601D02*
X1103849Y435167D01*
X1104132Y435450D01*
X1104698Y434955D01*
X1104839Y434813D01*
X1104486Y434460D01*
X1104344Y434601D01*
G37*
G36*
G01X1102506Y432763D02*
X1102011Y433328D01*
X1102294Y433611D01*
X1102859Y433116D01*
X1103001Y432975D01*
X1102647Y432621D01*
X1102506Y432763D01*
G37*
G36*
G01X1100667Y430924D02*
X1100172Y431490D01*
X1100455Y431773D01*
X1101021Y431278D01*
X1101162Y431136D01*
X1100809Y430783D01*
X1100667Y430924D01*
G37*
G36*
G01X1113536Y443794D02*
X1113041Y444360D01*
X1113324Y444643D01*
X1113890Y444148D01*
X1114031Y444006D01*
X1113678Y443653D01*
X1113536Y443794D01*
G37*
G36*
G01X1111405Y414312D02*
X1110645Y414662D01*
Y415562D01*
X1111405Y415912D01*
X1111580D01*
Y414312D01*
X1111405D01*
G37*
G36*
G01Y410412D02*
X1110645Y410762D01*
Y411662D01*
X1111405Y412012D01*
X1111580D01*
Y410412D01*
X1111405D01*
G37*
G36*
G01X1110980Y420376D02*
X1110230Y420426D01*
Y420826D01*
X1110980Y420876D01*
X1111180D01*
Y420376D01*
X1110980D01*
G37*
G36*
G01Y417776D02*
X1110230Y417826D01*
Y418226D01*
X1110980Y418276D01*
X1111180D01*
Y417776D01*
X1110980D01*
G37*
G36*
G01X1111380Y419576D02*
X1112130Y419526D01*
Y419126D01*
X1111380Y419076D01*
X1111180D01*
Y419576D01*
X1111380D01*
G37*
G36*
G01X1110980Y422976D02*
X1110230Y423026D01*
Y423426D01*
X1110980Y423476D01*
X1111180D01*
Y422976D01*
X1110980D01*
G37*
G36*
G01X1111380Y424776D02*
X1112130Y424726D01*
Y424326D01*
X1111380Y424276D01*
X1111180D01*
Y424776D01*
X1111380D01*
G37*
G36*
G01Y422176D02*
X1112130Y422126D01*
Y421726D01*
X1111380Y421676D01*
X1111180D01*
Y422176D01*
X1111380D01*
G37*
G36*
G01X1120930Y435269D02*
X1121425Y434703D01*
X1121143Y434420D01*
X1120577Y434915D01*
X1120435Y435056D01*
X1120789Y435410D01*
X1120930Y435269D01*
G37*
G36*
G01X1122769Y437107D02*
X1123264Y436541D01*
X1122981Y436259D01*
X1122415Y436753D01*
X1122274Y436895D01*
X1122627Y437248D01*
X1122769Y437107D01*
G37*
G36*
G01X1119092Y433430D02*
X1119587Y432864D01*
X1119304Y432582D01*
X1118738Y433077D01*
X1118597Y433218D01*
X1118951Y433572D01*
X1119092Y433430D01*
G37*
G36*
G01X1117253Y431592D02*
X1117748Y431026D01*
X1117466Y430743D01*
X1116900Y431238D01*
X1116758Y431379D01*
X1117112Y431733D01*
X1117253Y431592D01*
G37*
G36*
G01X1115415Y429753D02*
X1115910Y429187D01*
X1115627Y428905D01*
X1115061Y429400D01*
X1114920Y429541D01*
X1115274Y429895D01*
X1115415Y429753D01*
G37*
G36*
G01X1113577Y427915D02*
X1114071Y427349D01*
X1113789Y427066D01*
X1113223Y427561D01*
X1113082Y427703D01*
X1113435Y428056D01*
X1113577Y427915D01*
G37*
G36*
G01X1119375Y434279D02*
X1118880Y434844D01*
X1119163Y435127D01*
X1119728Y434632D01*
X1119870Y434491D01*
X1119516Y434137D01*
X1119375Y434279D01*
G37*
G36*
G01X1121213Y436117D02*
X1120718Y436683D01*
X1121001Y436966D01*
X1121567Y436471D01*
X1121708Y436329D01*
X1121355Y435976D01*
X1121213Y436117D01*
G37*
G36*
G01X1123052Y437956D02*
X1122557Y438521D01*
X1122840Y438804D01*
X1123405Y438309D01*
X1123547Y438168D01*
X1123193Y437814D01*
X1123052Y437956D01*
G37*
G36*
G01X1117536Y432440D02*
X1117041Y433006D01*
X1117324Y433289D01*
X1117890Y432794D01*
X1118031Y432652D01*
X1117678Y432299D01*
X1117536Y432440D01*
G37*
G36*
G01X1115698Y430602D02*
X1115203Y431167D01*
X1115486Y431450D01*
X1116051Y430955D01*
X1116193Y430814D01*
X1115839Y430460D01*
X1115698Y430602D01*
G37*
G36*
G01X1113859Y428763D02*
X1113364Y429329D01*
X1113647Y429612D01*
X1114213Y429117D01*
X1114354Y428975D01*
X1114001Y428622D01*
X1113859Y428763D01*
G37*
G36*
G01X1112021Y426925D02*
X1111526Y427490D01*
X1111809Y427773D01*
X1112374Y427278D01*
X1112516Y427137D01*
X1112162Y426783D01*
X1112021Y426925D01*
G37*
G36*
G01X1126057Y438950D02*
X1126007Y438200D01*
X1125607D01*
X1125557Y438950D01*
Y439150D01*
X1126057D01*
Y438950D01*
G37*
G36*
G01X1126857Y439350D02*
X1126907Y440100D01*
X1127307D01*
X1127357Y439350D01*
Y439150D01*
X1126857D01*
Y439350D01*
G37*
G36*
G01X1128657Y438950D02*
X1128607Y438200D01*
X1128207D01*
X1128157Y438950D01*
Y439150D01*
X1128657D01*
Y438950D01*
G37*
G36*
G01X1133141Y442351D02*
X1133636Y441785D01*
X1133353Y441503D01*
X1132787Y441998D01*
X1132646Y442139D01*
X1133000Y442493D01*
X1133141Y442351D01*
G37*
G36*
G01X1131302Y440513D02*
X1131797Y439947D01*
X1131515Y439664D01*
X1130949Y440159D01*
X1130807Y440300D01*
X1131161Y440654D01*
X1131302Y440513D01*
G37*
G36*
G01X1131585Y441361D02*
X1131090Y441927D01*
X1131373Y442210D01*
X1131939Y441715D01*
X1132080Y441573D01*
X1131727Y441220D01*
X1131585Y441361D01*
G37*
G36*
G01X1112505Y415912D02*
X1113265Y415562D01*
Y414662D01*
X1112505Y414312D01*
X1112330D01*
Y415912D01*
X1112505D01*
G37*
G36*
G01Y412012D02*
X1113265Y411662D01*
Y410762D01*
X1112505Y410412D01*
X1112330D01*
Y412012D01*
X1112505D01*
G37*
G36*
G01X1112930Y419576D02*
X1113680Y419526D01*
Y419126D01*
X1112930Y419076D01*
X1112730D01*
Y419576D01*
X1112930D01*
G37*
G36*
G01X1112530Y417776D02*
X1111780Y417826D01*
Y418226D01*
X1112530Y418276D01*
X1112730D01*
Y417776D01*
X1112530D01*
G37*
G36*
G01Y420376D02*
X1111780Y420426D01*
Y420826D01*
X1112530Y420876D01*
X1112730D01*
Y420376D01*
X1112530D01*
G37*
G36*
G01X1112930Y422176D02*
X1113680Y422126D01*
Y421726D01*
X1112930Y421676D01*
X1112730D01*
Y422176D01*
X1112930D01*
G37*
G36*
G01Y424776D02*
X1113680Y424726D01*
Y424326D01*
X1112930Y424276D01*
X1112730D01*
Y424776D01*
X1112930D01*
G37*
G36*
G01X1112530Y422976D02*
X1111780Y423026D01*
Y423426D01*
X1112530Y423476D01*
X1112730D01*
Y422976D01*
X1112530D01*
G37*
G36*
G01X1116511Y428657D02*
X1117006Y428091D01*
X1116724Y427808D01*
X1116158Y428303D01*
X1116017Y428445D01*
X1116370Y428798D01*
X1116511Y428657D01*
G37*
G36*
G01X1114673Y426818D02*
X1115168Y426252D01*
X1114885Y425970D01*
X1114319Y426465D01*
X1114178Y426606D01*
X1114532Y426960D01*
X1114673Y426818D01*
G37*
G36*
G01X1118350Y430495D02*
X1118845Y429929D01*
X1118562Y429647D01*
X1117996Y430142D01*
X1117855Y430283D01*
X1118209Y430637D01*
X1118350Y430495D01*
G37*
G36*
G01X1120188Y432334D02*
X1120683Y431768D01*
X1120401Y431485D01*
X1119835Y431980D01*
X1119693Y432121D01*
X1120047Y432475D01*
X1120188Y432334D01*
G37*
G36*
G01X1122027Y434172D02*
X1122522Y433606D01*
X1122239Y433324D01*
X1121673Y433819D01*
X1121532Y433960D01*
X1121885Y434313D01*
X1122027Y434172D01*
G37*
G36*
G01X1123865Y436011D02*
X1124360Y435445D01*
X1124078Y435162D01*
X1123512Y435657D01*
X1123370Y435798D01*
X1123724Y436152D01*
X1123865Y436011D01*
G37*
G36*
G01X1116794Y429505D02*
X1116299Y430071D01*
X1116582Y430354D01*
X1117148Y429859D01*
X1117289Y429717D01*
X1116936Y429364D01*
X1116794Y429505D01*
G37*
G36*
G01X1114956Y427667D02*
X1114461Y428232D01*
X1114744Y428515D01*
X1115309Y428020D01*
X1115451Y427879D01*
X1115097Y427525D01*
X1114956Y427667D01*
G37*
G36*
G01X1113117Y425828D02*
X1112622Y426394D01*
X1112905Y426677D01*
X1113471Y426182D01*
X1113612Y426040D01*
X1113259Y425687D01*
X1113117Y425828D01*
G37*
G36*
G01X1118633Y431344D02*
X1118138Y431909D01*
X1118421Y432192D01*
X1118986Y431697D01*
X1119128Y431556D01*
X1118774Y431202D01*
X1118633Y431344D01*
G37*
G36*
G01X1120471Y433182D02*
X1119976Y433748D01*
X1120259Y434031D01*
X1120825Y433536D01*
X1120966Y433394D01*
X1120613Y433041D01*
X1120471Y433182D01*
G37*
G36*
G01X1122310Y435021D02*
X1121815Y435586D01*
X1122098Y435869D01*
X1122663Y435374D01*
X1122805Y435233D01*
X1122451Y434879D01*
X1122310Y435021D01*
G37*
G36*
G01X1124148Y436859D02*
X1123653Y437425D01*
X1123936Y437708D01*
X1124502Y437213D01*
X1124643Y437071D01*
X1124290Y436718D01*
X1124148Y436859D01*
G37*
G36*
G01X1126057Y437400D02*
X1126007Y436650D01*
X1125607D01*
X1125557Y437400D01*
Y437600D01*
X1126057D01*
Y437400D01*
G37*
G36*
G01X1128657D02*
X1128607Y436650D01*
X1128207D01*
X1128157Y437400D01*
Y437600D01*
X1128657D01*
Y437400D01*
G37*
G36*
G01X1126857Y437800D02*
X1126907Y438550D01*
X1127307D01*
X1127357Y437800D01*
Y437600D01*
X1126857D01*
Y437800D01*
G37*
G36*
G01X1132399Y439416D02*
X1132894Y438850D01*
X1132611Y438568D01*
X1132045Y439063D01*
X1131904Y439204D01*
X1132258Y439558D01*
X1132399Y439416D01*
G37*
G36*
G01X1134237Y441255D02*
X1134732Y440689D01*
X1134450Y440406D01*
X1133884Y440901D01*
X1133742Y441042D01*
X1134096Y441396D01*
X1134237Y441255D01*
G37*
G36*
G01X1130843Y438426D02*
X1130348Y438992D01*
X1130631Y439275D01*
X1131197Y438780D01*
X1131338Y438638D01*
X1130985Y438285D01*
X1130843Y438426D01*
G37*
G36*
G01X1132682Y440265D02*
X1132187Y440830D01*
X1132470Y441113D01*
X1133035Y440618D01*
X1133177Y440477D01*
X1132823Y440123D01*
X1132682Y440265D01*
G37*
G36*
G01X1095905Y414304D02*
X1095145Y414654D01*
Y415554D01*
X1095905Y415904D01*
X1096080D01*
Y414304D01*
X1095905D01*
G37*
G36*
G01Y410804D02*
X1095145Y411154D01*
Y412054D01*
X1095905Y412404D01*
X1096080D01*
Y410804D01*
X1095905D01*
G37*
G36*
G01X1095880Y419576D02*
X1096630Y419526D01*
Y419126D01*
X1095880Y419076D01*
X1095680D01*
Y419576D01*
X1095880D01*
G37*
G36*
G01Y427376D02*
X1096630Y427326D01*
Y426926D01*
X1095880Y426876D01*
X1095680D01*
Y427376D01*
X1095880D01*
G37*
G36*
G01Y429976D02*
X1096630Y429926D01*
Y429526D01*
X1095880Y429476D01*
X1095680D01*
Y429976D01*
X1095880D01*
G37*
G36*
G01Y424776D02*
X1096630Y424726D01*
Y424326D01*
X1095880Y424276D01*
X1095680D01*
Y424776D01*
X1095880D01*
G37*
G36*
G01Y422176D02*
X1096630Y422126D01*
Y421726D01*
X1095880Y421676D01*
X1095680D01*
Y422176D01*
X1095880D01*
G37*
G36*
G01X1097378Y434214D02*
X1096883Y434779D01*
X1097166Y435062D01*
X1097731Y434567D01*
X1097873Y434426D01*
X1097519Y434072D01*
X1097378Y434214D01*
G37*
G36*
G01X1097095Y433365D02*
X1097590Y432800D01*
X1097307Y432517D01*
X1096742Y433012D01*
X1096600Y433153D01*
X1096954Y433507D01*
X1097095Y433365D01*
G37*
G36*
G01X1104732Y441568D02*
X1104237Y442133D01*
X1104520Y442416D01*
X1105085Y441921D01*
X1105227Y441780D01*
X1104873Y441426D01*
X1104732Y441568D01*
G37*
G36*
G01X1106570Y443406D02*
X1106075Y443972D01*
X1106358Y444255D01*
X1106924Y443760D01*
X1107065Y443618D01*
X1106712Y443265D01*
X1106570Y443406D01*
G37*
G36*
G01X1102893Y439729D02*
X1102398Y440295D01*
X1102681Y440578D01*
X1103247Y440083D01*
X1103388Y439941D01*
X1103035Y439588D01*
X1102893Y439729D01*
G37*
G36*
G01X1101055Y437891D02*
X1100560Y438456D01*
X1100843Y438739D01*
X1101408Y438244D01*
X1101550Y438103D01*
X1101196Y437749D01*
X1101055Y437891D01*
G37*
G36*
G01X1099216Y436052D02*
X1098721Y436618D01*
X1099004Y436901D01*
X1099570Y436406D01*
X1099711Y436264D01*
X1099358Y435911D01*
X1099216Y436052D01*
G37*
G36*
G01X1104449Y440719D02*
X1104944Y440153D01*
X1104661Y439871D01*
X1104095Y440366D01*
X1103954Y440507D01*
X1104308Y440861D01*
X1104449Y440719D01*
G37*
G36*
G01X1106287Y442558D02*
X1106782Y441992D01*
X1106500Y441709D01*
X1105934Y442204D01*
X1105792Y442345D01*
X1106146Y442699D01*
X1106287Y442558D01*
G37*
G36*
G01X1102611Y438881D02*
X1103105Y438315D01*
X1102823Y438032D01*
X1102257Y438527D01*
X1102116Y438669D01*
X1102469Y439022D01*
X1102611Y438881D01*
G37*
G36*
G01X1100772Y437042D02*
X1101267Y436476D01*
X1100984Y436194D01*
X1100418Y436689D01*
X1100277Y436830D01*
X1100631Y437184D01*
X1100772Y437042D01*
G37*
G36*
G01X1098934Y435204D02*
X1099429Y434638D01*
X1099146Y434355D01*
X1098580Y434850D01*
X1098439Y434992D01*
X1098792Y435345D01*
X1098934Y435204D01*
G37*
G36*
G01X1108126Y444396D02*
X1108621Y443830D01*
X1108339Y443547D01*
X1107773Y444042D01*
X1107631Y444183D01*
X1107985Y444537D01*
X1108126Y444396D01*
G37*
G36*
G01X1097005Y415904D02*
X1097765Y415554D01*
Y414654D01*
X1097005Y414304D01*
X1096830D01*
Y415904D01*
X1097005D01*
G37*
G36*
G01Y412404D02*
X1097765Y412054D01*
Y411154D01*
X1097005Y410804D01*
X1096830D01*
Y412404D01*
X1097005D01*
G37*
G36*
G01X1097030Y420376D02*
X1096280Y420426D01*
Y420826D01*
X1097030Y420876D01*
X1097230D01*
Y420376D01*
X1097030D01*
G37*
G36*
G01Y417776D02*
X1096280Y417826D01*
Y418226D01*
X1097030Y418276D01*
X1097230D01*
Y417776D01*
X1097030D01*
G37*
G36*
G01X1097430Y419576D02*
X1098180Y419526D01*
Y419126D01*
X1097430Y419076D01*
X1097230D01*
Y419576D01*
X1097430D01*
G37*
G36*
G01X1097030Y425576D02*
X1096280Y425626D01*
Y426026D01*
X1097030Y426076D01*
X1097230D01*
Y425576D01*
X1097030D01*
G37*
G36*
G01Y428176D02*
X1096280Y428226D01*
Y428626D01*
X1097030Y428676D01*
X1097230D01*
Y428176D01*
X1097030D01*
G37*
G36*
G01Y430776D02*
X1096280Y430826D01*
Y431226D01*
X1097030Y431276D01*
X1097230D01*
Y430776D01*
X1097030D01*
G37*
G36*
G01Y422976D02*
X1096280Y423026D01*
Y423426D01*
X1097030Y423476D01*
X1097230D01*
Y422976D01*
X1097030D01*
G37*
G36*
G01X1097430Y427376D02*
X1098180Y427326D01*
Y426926D01*
X1097430Y426876D01*
X1097230D01*
Y427376D01*
X1097430D01*
G37*
G36*
G01Y429976D02*
X1098180Y429926D01*
Y429526D01*
X1097430Y429476D01*
X1097230D01*
Y429976D01*
X1097430D01*
G37*
G36*
G01Y424776D02*
X1098180Y424726D01*
Y424326D01*
X1097430Y424276D01*
X1097230D01*
Y424776D01*
X1097430D01*
G37*
G36*
G01Y422176D02*
X1098180Y422126D01*
Y421726D01*
X1097430Y421676D01*
X1097230D01*
Y422176D01*
X1097430D01*
G37*
G36*
G01X1105545Y439623D02*
X1106040Y439057D01*
X1105758Y438774D01*
X1105192Y439269D01*
X1105051Y439411D01*
X1105404Y439764D01*
X1105545Y439623D01*
G37*
G36*
G01X1107384Y441461D02*
X1107879Y440895D01*
X1107596Y440613D01*
X1107030Y441108D01*
X1106889Y441249D01*
X1107243Y441603D01*
X1107384Y441461D01*
G37*
G36*
G01X1109222Y443300D02*
X1109717Y442734D01*
X1109435Y442451D01*
X1108869Y442946D01*
X1108727Y443087D01*
X1109081Y443441D01*
X1109222Y443300D01*
G37*
G36*
G01X1103707Y437784D02*
X1104202Y437218D01*
X1103919Y436936D01*
X1103353Y437431D01*
X1103212Y437572D01*
X1103566Y437926D01*
X1103707Y437784D01*
G37*
G36*
G01X1101869Y435946D02*
X1102364Y435380D01*
X1102081Y435097D01*
X1101515Y435592D01*
X1101374Y435734D01*
X1101727Y436087D01*
X1101869Y435946D01*
G37*
G36*
G01X1100030Y434107D02*
X1100525Y433542D01*
X1100242Y433259D01*
X1099676Y433754D01*
X1099535Y433895D01*
X1099889Y434249D01*
X1100030Y434107D01*
G37*
G36*
G01X1098192Y432269D02*
X1098687Y431703D01*
X1098404Y431420D01*
X1097838Y431915D01*
X1097697Y432057D01*
X1098050Y432410D01*
X1098192Y432269D01*
G37*
G36*
G01X1105828Y440471D02*
X1105333Y441037D01*
X1105616Y441320D01*
X1106182Y440825D01*
X1106323Y440683D01*
X1105970Y440330D01*
X1105828Y440471D01*
G37*
G36*
G01X1107667Y442310D02*
X1107172Y442875D01*
X1107455Y443158D01*
X1108020Y442663D01*
X1108162Y442522D01*
X1107808Y442168D01*
X1107667Y442310D01*
G37*
G36*
G01X1103990Y438633D02*
X1103495Y439198D01*
X1103778Y439481D01*
X1104343Y438986D01*
X1104485Y438845D01*
X1104131Y438491D01*
X1103990Y438633D01*
G37*
G36*
G01X1102151Y436794D02*
X1101656Y437360D01*
X1101939Y437643D01*
X1102505Y437148D01*
X1102646Y437006D01*
X1102293Y436653D01*
X1102151Y436794D01*
G37*
G36*
G01X1100313Y434956D02*
X1099818Y435521D01*
X1100101Y435804D01*
X1100666Y435309D01*
X1100808Y435168D01*
X1100454Y434814D01*
X1100313Y434956D01*
G37*
G36*
G01X1098474Y433117D02*
X1097979Y433683D01*
X1098262Y433966D01*
X1098828Y433471D01*
X1098969Y433329D01*
X1098616Y432976D01*
X1098474Y433117D01*
G37*
G36*
G01X1109506Y444148D02*
X1109011Y444713D01*
X1109294Y444996D01*
X1109859Y444501D01*
X1110001Y444360D01*
X1109647Y444006D01*
X1109506Y444148D01*
G37*
G36*
G01X1108278Y414312D02*
X1107518Y414662D01*
Y415562D01*
X1108278Y415912D01*
X1108453D01*
Y414312D01*
X1108278D01*
G37*
G36*
G01Y410412D02*
X1107518Y410762D01*
Y411662D01*
X1108278Y412012D01*
X1108453D01*
Y410412D01*
X1108278D01*
G37*
G36*
G01X1107880Y420376D02*
X1107130Y420426D01*
Y420826D01*
X1107880Y420876D01*
X1108080D01*
Y420376D01*
X1107880D01*
G37*
G36*
G01Y417776D02*
X1107130Y417826D01*
Y418226D01*
X1107880Y418276D01*
X1108080D01*
Y417776D01*
X1107880D01*
G37*
G36*
G01X1108280Y419576D02*
X1109030Y419526D01*
Y419126D01*
X1108280Y419076D01*
X1108080D01*
Y419576D01*
X1108280D01*
G37*
G36*
G01X1107880Y425576D02*
X1107130Y425626D01*
Y426026D01*
X1107880Y426076D01*
X1108080D01*
Y425576D01*
X1107880D01*
G37*
G36*
G01Y422976D02*
X1107130Y423026D01*
Y423426D01*
X1107880Y423476D01*
X1108080D01*
Y422976D01*
X1107880D01*
G37*
G36*
G01X1108280Y424776D02*
X1109030Y424726D01*
Y424326D01*
X1108280Y424276D01*
X1108080D01*
Y424776D01*
X1108280D01*
G37*
G36*
G01Y422176D02*
X1109030Y422126D01*
Y421726D01*
X1108280Y421676D01*
X1108080D01*
Y422176D01*
X1108280D01*
G37*
G36*
G01X1118737Y437462D02*
X1119232Y436896D01*
X1118950Y436613D01*
X1118384Y437108D01*
X1118242Y437249D01*
X1118596Y437603D01*
X1118737Y437462D01*
G37*
G36*
G01X1120576Y439300D02*
X1121071Y438734D01*
X1120788Y438452D01*
X1120222Y438946D01*
X1120081Y439088D01*
X1120434Y439441D01*
X1120576Y439300D01*
G37*
G36*
G01X1122414Y441139D02*
X1122909Y440573D01*
X1122627Y440290D01*
X1122061Y440785D01*
X1121919Y440926D01*
X1122273Y441280D01*
X1122414Y441139D01*
G37*
G36*
G01X1116899Y435623D02*
X1117394Y435057D01*
X1117111Y434775D01*
X1116545Y435270D01*
X1116404Y435411D01*
X1116758Y435765D01*
X1116899Y435623D01*
G37*
G36*
G01X1115060Y433785D02*
X1115555Y433219D01*
X1115273Y432936D01*
X1114707Y433431D01*
X1114565Y433572D01*
X1114919Y433926D01*
X1115060Y433785D01*
G37*
G36*
G01X1113222Y431946D02*
X1113717Y431380D01*
X1113434Y431098D01*
X1112868Y431593D01*
X1112727Y431734D01*
X1113081Y432088D01*
X1113222Y431946D01*
G37*
G36*
G01X1111384Y430108D02*
X1111878Y429542D01*
X1111596Y429259D01*
X1111030Y429754D01*
X1110889Y429896D01*
X1111242Y430249D01*
X1111384Y430108D01*
G37*
G36*
G01X1109545Y428269D02*
X1110040Y427703D01*
X1109757Y427421D01*
X1109191Y427916D01*
X1109050Y428057D01*
X1109404Y428411D01*
X1109545Y428269D01*
G37*
G36*
G01X1117182Y436472D02*
X1116687Y437037D01*
X1116970Y437320D01*
X1117535Y436825D01*
X1117677Y436684D01*
X1117323Y436330D01*
X1117182Y436472D01*
G37*
G36*
G01X1119020Y438310D02*
X1118525Y438876D01*
X1118808Y439159D01*
X1119374Y438664D01*
X1119515Y438522D01*
X1119162Y438169D01*
X1119020Y438310D01*
G37*
G36*
G01X1120859Y440149D02*
X1120364Y440714D01*
X1120647Y440997D01*
X1121212Y440502D01*
X1121354Y440361D01*
X1121000Y440007D01*
X1120859Y440149D01*
G37*
G36*
G01X1115343Y434633D02*
X1114848Y435199D01*
X1115131Y435482D01*
X1115697Y434987D01*
X1115838Y434845D01*
X1115485Y434492D01*
X1115343Y434633D01*
G37*
G36*
G01X1113505Y432795D02*
X1113010Y433360D01*
X1113293Y433643D01*
X1113858Y433148D01*
X1114000Y433007D01*
X1113646Y432653D01*
X1113505Y432795D01*
G37*
G36*
G01X1111666Y430956D02*
X1111171Y431522D01*
X1111454Y431805D01*
X1112020Y431310D01*
X1112161Y431168D01*
X1111808Y430815D01*
X1111666Y430956D01*
G37*
G36*
G01X1109828Y429118D02*
X1109333Y429683D01*
X1109616Y429966D01*
X1110181Y429471D01*
X1110323Y429330D01*
X1109969Y428976D01*
X1109828Y429118D01*
G37*
G36*
G01X1124257Y442450D02*
X1124307Y443200D01*
X1124707D01*
X1124757Y442450D01*
Y442250D01*
X1124257D01*
Y442450D01*
G37*
G36*
G01X1126057Y442050D02*
X1126007Y441300D01*
X1125607D01*
X1125557Y442050D01*
Y442250D01*
X1126057D01*
Y442050D01*
G37*
G36*
G01X1126857Y442450D02*
X1126907Y443200D01*
X1127307D01*
X1127357Y442450D01*
Y442250D01*
X1126857D01*
Y442450D01*
G37*
G36*
G01X1109378Y415912D02*
X1110138Y415562D01*
Y414662D01*
X1109378Y414312D01*
X1109203D01*
Y415912D01*
X1109378D01*
G37*
G36*
G01Y412012D02*
X1110138Y411662D01*
Y410762D01*
X1109378Y410412D01*
X1109203D01*
Y412012D01*
X1109378D01*
G37*
G36*
G01X1109430Y417776D02*
X1108680Y417826D01*
Y418226D01*
X1109430Y418276D01*
X1109630D01*
Y417776D01*
X1109430D01*
G37*
G36*
G01Y420376D02*
X1108680Y420426D01*
Y420826D01*
X1109430Y420876D01*
X1109630D01*
Y420376D01*
X1109430D01*
G37*
G36*
G01X1109830Y419576D02*
X1110580Y419526D01*
Y419126D01*
X1109830Y419076D01*
X1109630D01*
Y419576D01*
X1109830D01*
G37*
G36*
G01X1109430Y422976D02*
X1108680Y423026D01*
Y423426D01*
X1109430Y423476D01*
X1109630D01*
Y422976D01*
X1109430D01*
G37*
G36*
G01Y425576D02*
X1108680Y425626D01*
Y426026D01*
X1109430Y426076D01*
X1109630D01*
Y425576D01*
X1109430D01*
G37*
G36*
G01X1109830Y422176D02*
X1110580Y422126D01*
Y421726D01*
X1109830Y421676D01*
X1109630D01*
Y422176D01*
X1109830D01*
G37*
G36*
G01Y424776D02*
X1110580Y424726D01*
Y424326D01*
X1109830Y424276D01*
X1109630D01*
Y424776D01*
X1109830D01*
G37*
G36*
G01X1114318Y430850D02*
X1114813Y430284D01*
X1114531Y430001D01*
X1113965Y430496D01*
X1113824Y430638D01*
X1114177Y430991D01*
X1114318Y430850D01*
G37*
G36*
G01X1112480Y429011D02*
X1112975Y428445D01*
X1112692Y428163D01*
X1112126Y428658D01*
X1111985Y428799D01*
X1112339Y429153D01*
X1112480Y429011D01*
G37*
G36*
G01X1110642Y427173D02*
X1111137Y426607D01*
X1110854Y426324D01*
X1110288Y426819D01*
X1110147Y426961D01*
X1110500Y427314D01*
X1110642Y427173D01*
G37*
G36*
G01X1116157Y432688D02*
X1116652Y432122D01*
X1116369Y431840D01*
X1115803Y432335D01*
X1115662Y432476D01*
X1116016Y432830D01*
X1116157Y432688D01*
G37*
G36*
G01X1117995Y434527D02*
X1118490Y433961D01*
X1118208Y433678D01*
X1117642Y434173D01*
X1117500Y434314D01*
X1117854Y434668D01*
X1117995Y434527D01*
G37*
G36*
G01X1119834Y436365D02*
X1120329Y435799D01*
X1120046Y435517D01*
X1119480Y436012D01*
X1119339Y436153D01*
X1119692Y436506D01*
X1119834Y436365D01*
G37*
G36*
G01X1121672Y438204D02*
X1122167Y437638D01*
X1121885Y437355D01*
X1121319Y437850D01*
X1121177Y437991D01*
X1121531Y438345D01*
X1121672Y438204D01*
G37*
G36*
G01X1123511Y440042D02*
X1124006Y439476D01*
X1123723Y439193D01*
X1123157Y439688D01*
X1123016Y439830D01*
X1123369Y440183D01*
X1123511Y440042D01*
G37*
G36*
G01X1114601Y431698D02*
X1114106Y432264D01*
X1114389Y432547D01*
X1114955Y432052D01*
X1115096Y431910D01*
X1114743Y431557D01*
X1114601Y431698D01*
G37*
G36*
G01X1112763Y429860D02*
X1112268Y430425D01*
X1112551Y430708D01*
X1113116Y430213D01*
X1113258Y430072D01*
X1112904Y429718D01*
X1112763Y429860D01*
G37*
G36*
G01X1110924Y428021D02*
X1110429Y428587D01*
X1110712Y428870D01*
X1111278Y428375D01*
X1111419Y428233D01*
X1111066Y427880D01*
X1110924Y428021D01*
G37*
G36*
G01X1116440Y433537D02*
X1115945Y434102D01*
X1116228Y434385D01*
X1116793Y433890D01*
X1116935Y433749D01*
X1116581Y433395D01*
X1116440Y433537D01*
G37*
G36*
G01X1118278Y435375D02*
X1117783Y435941D01*
X1118066Y436224D01*
X1118632Y435729D01*
X1118773Y435587D01*
X1118420Y435234D01*
X1118278Y435375D01*
G37*
G36*
G01X1120117Y437214D02*
X1119622Y437779D01*
X1119905Y438062D01*
X1120470Y437567D01*
X1120612Y437426D01*
X1120258Y437072D01*
X1120117Y437214D01*
G37*
G36*
G01X1121955Y439052D02*
X1121460Y439618D01*
X1121743Y439901D01*
X1122309Y439406D01*
X1122450Y439264D01*
X1122097Y438911D01*
X1121955Y439052D01*
G37*
G36*
G01X1124257Y440900D02*
X1124307Y441650D01*
X1124707D01*
X1124757Y440900D01*
Y440700D01*
X1124257D01*
Y440900D01*
G37*
G36*
G01X1126057Y440500D02*
X1126007Y439750D01*
X1125607D01*
X1125557Y440500D01*
Y440700D01*
X1126057D01*
Y440500D01*
G37*
G36*
G01X1126857Y440900D02*
X1126907Y441650D01*
X1127307D01*
X1127357Y440900D01*
Y440700D01*
X1126857D01*
Y440900D01*
G37*
G36*
G01X1128657Y440500D02*
X1128607Y439750D01*
X1128207D01*
X1128157Y440500D01*
Y440700D01*
X1128657D01*
Y440500D01*
G37*
G36*
G01X1119000Y411024D02*
X1118240Y411374D01*
Y412274D01*
X1119000Y412624D01*
X1119200D01*
Y411024D01*
X1119000D01*
G37*
G36*
G01X1123570Y419579D02*
X1124065Y419013D01*
X1123782Y418731D01*
X1123216Y419226D01*
X1123075Y419367D01*
X1123429Y419721D01*
X1123570Y419579D01*
G37*
G36*
G01X1123853Y420428D02*
X1123358Y420993D01*
X1123641Y421276D01*
X1124206Y420781D01*
X1124348Y420640D01*
X1123994Y420286D01*
X1123853Y420428D01*
G37*
G36*
G01X1121731Y417741D02*
X1122226Y417175D01*
X1121944Y416892D01*
X1121378Y417387D01*
X1121236Y417528D01*
X1121590Y417882D01*
X1121731Y417741D01*
G37*
G36*
G01X1120176Y416751D02*
X1119681Y417316D01*
X1119964Y417599D01*
X1120529Y417104D01*
X1120671Y416963D01*
X1120317Y416609D01*
X1120176Y416751D01*
G37*
G36*
G01X1122014Y418589D02*
X1121519Y419155D01*
X1121802Y419438D01*
X1122368Y418943D01*
X1122509Y418801D01*
X1122156Y418448D01*
X1122014Y418589D01*
G37*
G36*
G01X1125408Y421418D02*
X1125903Y420852D01*
X1125621Y420569D01*
X1125055Y421064D01*
X1124913Y421205D01*
X1125267Y421559D01*
X1125408Y421418D01*
G37*
G36*
G01X1125691Y422266D02*
X1125196Y422832D01*
X1125479Y423115D01*
X1126045Y422620D01*
X1126186Y422478D01*
X1125833Y422125D01*
X1125691Y422266D01*
G37*
G36*
G01X1130590Y424351D02*
X1130540Y423601D01*
X1130140D01*
X1130090Y424351D01*
Y424551D01*
X1130590D01*
Y424351D01*
G37*
G36*
G01X1133190D02*
X1133140Y423601D01*
X1132740D01*
X1132690Y424351D01*
Y424551D01*
X1133190D01*
Y424351D01*
G37*
G36*
G01X1135790D02*
X1135740Y423601D01*
X1135340D01*
X1135290Y424351D01*
Y424551D01*
X1135790D01*
Y424351D01*
G37*
G36*
G01X1128790Y424751D02*
X1128840Y425501D01*
X1129240D01*
X1129290Y424751D01*
Y424551D01*
X1128790D01*
Y424751D01*
G37*
G36*
G01X1131390D02*
X1131440Y425501D01*
X1131840D01*
X1131890Y424751D01*
Y424551D01*
X1131390D01*
Y424751D01*
G37*
G36*
G01X1133990D02*
X1134040Y425501D01*
X1134440D01*
X1134490Y424751D01*
Y424551D01*
X1133990D01*
Y424751D01*
G37*
G36*
G01X1127247Y423256D02*
X1127742Y422690D01*
X1127459Y422408D01*
X1126893Y422902D01*
X1126752Y423044D01*
X1127105Y423397D01*
X1127247Y423256D01*
G37*
G36*
G01X1127530Y424105D02*
X1127035Y424670D01*
X1127318Y424953D01*
X1127883Y424458D01*
X1128025Y424317D01*
X1127671Y423963D01*
X1127530Y424105D01*
G37*
G36*
G01X1153990Y424351D02*
X1153940Y423601D01*
X1153540D01*
X1153490Y424351D01*
Y424551D01*
X1153990D01*
Y424351D01*
G37*
G36*
G01X1151390D02*
X1151340Y423601D01*
X1150940D01*
X1150890Y424351D01*
Y424551D01*
X1151390D01*
Y424351D01*
G37*
G36*
G01X1148790D02*
X1148740Y423601D01*
X1148340D01*
X1148290Y424351D01*
Y424551D01*
X1148790D01*
Y424351D01*
G37*
G36*
G01X1146190D02*
X1146140Y423601D01*
X1145740D01*
X1145690Y424351D01*
Y424551D01*
X1146190D01*
Y424351D01*
G37*
G36*
G01X1143590D02*
X1143540Y423601D01*
X1143140D01*
X1143090Y424351D01*
Y424551D01*
X1143590D01*
Y424351D01*
G37*
G36*
G01X1138390D02*
X1138340Y423601D01*
X1137940D01*
X1137890Y424351D01*
Y424551D01*
X1138390D01*
Y424351D01*
G37*
G36*
G01X1140990D02*
X1140940Y423601D01*
X1140540D01*
X1140490Y424351D01*
Y424551D01*
X1140990D01*
Y424351D01*
G37*
G36*
G01X1154790Y424751D02*
X1154840Y425501D01*
X1155240D01*
X1155290Y424751D01*
Y424551D01*
X1154790D01*
Y424751D01*
G37*
G36*
G01X1152190D02*
X1152240Y425501D01*
X1152640D01*
X1152690Y424751D01*
Y424551D01*
X1152190D01*
Y424751D01*
G37*
G36*
G01X1149590D02*
X1149640Y425501D01*
X1150040D01*
X1150090Y424751D01*
Y424551D01*
X1149590D01*
Y424751D01*
G37*
G36*
G01X1146990D02*
X1147040Y425501D01*
X1147440D01*
X1147490Y424751D01*
Y424551D01*
X1146990D01*
Y424751D01*
G37*
G36*
G01X1144390D02*
X1144440Y425501D01*
X1144840D01*
X1144890Y424751D01*
Y424551D01*
X1144390D01*
Y424751D01*
G37*
G36*
G01X1136590D02*
X1136640Y425501D01*
X1137040D01*
X1137090Y424751D01*
Y424551D01*
X1136590D01*
Y424751D01*
G37*
G36*
G01X1139190D02*
X1139240Y425501D01*
X1139640D01*
X1139690Y424751D01*
Y424551D01*
X1139190D01*
Y424751D01*
G37*
G36*
G01X1141790D02*
X1141840Y425501D01*
X1142240D01*
X1142290Y424751D01*
Y424551D01*
X1141790D01*
Y424751D01*
G37*
G36*
G01X1156590Y424351D02*
X1156540Y423601D01*
X1156140D01*
X1156090Y424351D01*
Y424551D01*
X1156590D01*
Y424351D01*
G37*
G36*
G01X1120150Y412624D02*
X1120910Y412274D01*
Y411374D01*
X1120150Y411024D01*
X1119950D01*
Y412624D01*
X1120150D01*
G37*
G36*
G01X1121272Y415654D02*
X1120777Y416220D01*
X1121060Y416503D01*
X1121626Y416008D01*
X1121767Y415866D01*
X1121414Y415513D01*
X1121272Y415654D01*
G37*
G36*
G01X1123111Y417493D02*
X1122616Y418058D01*
X1122899Y418341D01*
X1123464Y417846D01*
X1123606Y417705D01*
X1123252Y417351D01*
X1123111Y417493D01*
G37*
G36*
G01X1124666Y418483D02*
X1125161Y417917D01*
X1124879Y417634D01*
X1124313Y418129D01*
X1124171Y418270D01*
X1124525Y418624D01*
X1124666Y418483D01*
G37*
G36*
G01X1126505Y420321D02*
X1127000Y419755D01*
X1126717Y419473D01*
X1126151Y419968D01*
X1126010Y420109D01*
X1126363Y420462D01*
X1126505Y420321D01*
G37*
G36*
G01X1124949Y419331D02*
X1124454Y419897D01*
X1124737Y420180D01*
X1125303Y419685D01*
X1125444Y419543D01*
X1125091Y419190D01*
X1124949Y419331D01*
G37*
G36*
G01X1126788Y421170D02*
X1126293Y421735D01*
X1126576Y422018D01*
X1127141Y421523D01*
X1127283Y421382D01*
X1126929Y421028D01*
X1126788Y421170D01*
G37*
G36*
G01X1130590Y422801D02*
X1130540Y422051D01*
X1130140D01*
X1130090Y422801D01*
Y423001D01*
X1130590D01*
Y422801D01*
G37*
G36*
G01X1133190D02*
X1133140Y422051D01*
X1132740D01*
X1132690Y422801D01*
Y423001D01*
X1133190D01*
Y422801D01*
G37*
G36*
G01X1135790D02*
X1135740Y422051D01*
X1135340D01*
X1135290Y422801D01*
Y423001D01*
X1135790D01*
Y422801D01*
G37*
G36*
G01X1128343Y422160D02*
X1128838Y421594D01*
X1128556Y421311D01*
X1127990Y421806D01*
X1127848Y421947D01*
X1128202Y422301D01*
X1128343Y422160D01*
G37*
G36*
G01X1131390Y423201D02*
X1131440Y423951D01*
X1131840D01*
X1131890Y423201D01*
Y423001D01*
X1131390D01*
Y423201D01*
G37*
G36*
G01X1133990D02*
X1134040Y423951D01*
X1134440D01*
X1134490Y423201D01*
Y423001D01*
X1133990D01*
Y423201D01*
G37*
G36*
G01X1153990Y422801D02*
X1153940Y422051D01*
X1153540D01*
X1153490Y422801D01*
Y423001D01*
X1153990D01*
Y422801D01*
G37*
G36*
G01X1151390D02*
X1151340Y422051D01*
X1150940D01*
X1150890Y422801D01*
Y423001D01*
X1151390D01*
Y422801D01*
G37*
G36*
G01X1148790D02*
X1148740Y422051D01*
X1148340D01*
X1148290Y422801D01*
Y423001D01*
X1148790D01*
Y422801D01*
G37*
G36*
G01X1146190D02*
X1146140Y422051D01*
X1145740D01*
X1145690Y422801D01*
Y423001D01*
X1146190D01*
Y422801D01*
G37*
G36*
G01X1143590D02*
X1143540Y422051D01*
X1143140D01*
X1143090Y422801D01*
Y423001D01*
X1143590D01*
Y422801D01*
G37*
G36*
G01X1138390D02*
X1138340Y422051D01*
X1137940D01*
X1137890Y422801D01*
Y423001D01*
X1138390D01*
Y422801D01*
G37*
G36*
G01X1140990D02*
X1140940Y422051D01*
X1140540D01*
X1140490Y422801D01*
Y423001D01*
X1140990D01*
Y422801D01*
G37*
G36*
G01X1156590D02*
X1156540Y422051D01*
X1156140D01*
X1156090Y422801D01*
Y423001D01*
X1156590D01*
Y422801D01*
G37*
G36*
G01X1154790Y423201D02*
X1154840Y423951D01*
X1155240D01*
X1155290Y423201D01*
Y423001D01*
X1154790D01*
Y423201D01*
G37*
G36*
G01X1152190D02*
X1152240Y423951D01*
X1152640D01*
X1152690Y423201D01*
Y423001D01*
X1152190D01*
Y423201D01*
G37*
G36*
G01X1149590D02*
X1149640Y423951D01*
X1150040D01*
X1150090Y423201D01*
Y423001D01*
X1149590D01*
Y423201D01*
G37*
G36*
G01X1146990D02*
X1147040Y423951D01*
X1147440D01*
X1147490Y423201D01*
Y423001D01*
X1146990D01*
Y423201D01*
G37*
G36*
G01X1144390D02*
X1144440Y423951D01*
X1144840D01*
X1144890Y423201D01*
Y423001D01*
X1144390D01*
Y423201D01*
G37*
G36*
G01X1136590D02*
X1136640Y423951D01*
X1137040D01*
X1137090Y423201D01*
Y423001D01*
X1136590D01*
Y423201D01*
G37*
G36*
G01X1139190D02*
X1139240Y423951D01*
X1139640D01*
X1139690Y423201D01*
Y423001D01*
X1139190D01*
Y423201D01*
G37*
G36*
G01X1141790D02*
X1141840Y423951D01*
X1142240D01*
X1142290Y423201D01*
Y423001D01*
X1141790D01*
Y423201D01*
G37*
G36*
G01X1135790Y411951D02*
X1135740Y411201D01*
X1135340D01*
X1135290Y411951D01*
Y412151D01*
X1135790D01*
Y411951D01*
G37*
G36*
G01X1132726Y410423D02*
X1133221Y409857D01*
X1132939Y409574D01*
X1132373Y410069D01*
X1132231Y410210D01*
X1132585Y410564D01*
X1132726Y410423D01*
G37*
G36*
G01X1133009Y411271D02*
X1132514Y411837D01*
X1132797Y412120D01*
X1133363Y411625D01*
X1133504Y411483D01*
X1133151Y411130D01*
X1133009Y411271D01*
G37*
G36*
G01X1131171Y409433D02*
X1130676Y409998D01*
X1130959Y410281D01*
X1131524Y409786D01*
X1131666Y409645D01*
X1131312Y409291D01*
X1131171Y409433D01*
G37*
G36*
G01X1130888Y408584D02*
X1131383Y408018D01*
X1131100Y407736D01*
X1130534Y408231D01*
X1130393Y408372D01*
X1130747Y408726D01*
X1130888Y408584D01*
G37*
G36*
G01X1136590Y412351D02*
X1136640Y413101D01*
X1137040D01*
X1137090Y412351D01*
Y412151D01*
X1136590D01*
Y412351D01*
G37*
G36*
G01X1138390Y411951D02*
X1138340Y411201D01*
X1137940D01*
X1137890Y411951D01*
Y412151D01*
X1138390D01*
Y411951D01*
G37*
G36*
G01X1140990D02*
X1140940Y411201D01*
X1140540D01*
X1140490Y411951D01*
Y412151D01*
X1140990D01*
Y411951D01*
G37*
G36*
G01X1143590D02*
X1143540Y411201D01*
X1143140D01*
X1143090Y411951D01*
Y412151D01*
X1143590D01*
Y411951D01*
G37*
G36*
G01X1146190D02*
X1146140Y411201D01*
X1145740D01*
X1145690Y411951D01*
Y412151D01*
X1146190D01*
Y411951D01*
G37*
G36*
G01X1148790D02*
X1148740Y411201D01*
X1148340D01*
X1148290Y411951D01*
Y412151D01*
X1148790D01*
Y411951D01*
G37*
G36*
G01X1153990D02*
X1153940Y411201D01*
X1153540D01*
X1153490Y411951D01*
Y412151D01*
X1153990D01*
Y411951D01*
G37*
G36*
G01X1151390D02*
X1151340Y411201D01*
X1150940D01*
X1150890Y411951D01*
Y412151D01*
X1151390D01*
Y411951D01*
G37*
G36*
G01X1139190Y412351D02*
X1139240Y413101D01*
X1139640D01*
X1139690Y412351D01*
Y412151D01*
X1139190D01*
Y412351D01*
G37*
G36*
G01X1141790D02*
X1141840Y413101D01*
X1142240D01*
X1142290Y412351D01*
Y412151D01*
X1141790D01*
Y412351D01*
G37*
G36*
G01X1144390D02*
X1144440Y413101D01*
X1144840D01*
X1144890Y412351D01*
Y412151D01*
X1144390D01*
Y412351D01*
G37*
G36*
G01X1146990D02*
X1147040Y413101D01*
X1147440D01*
X1147490Y412351D01*
Y412151D01*
X1146990D01*
Y412351D01*
G37*
G36*
G01X1149590D02*
X1149640Y413101D01*
X1150040D01*
X1150090Y412351D01*
Y412151D01*
X1149590D01*
Y412351D01*
G37*
G36*
G01X1154790D02*
X1154840Y413101D01*
X1155240D01*
X1155290Y412351D01*
Y412151D01*
X1154790D01*
Y412351D01*
G37*
G36*
G01X1152190D02*
X1152240Y413101D01*
X1152640D01*
X1152690Y412351D01*
Y412151D01*
X1152190D01*
Y412351D01*
G37*
G36*
G01X1156590Y411951D02*
X1156540Y411201D01*
X1156140D01*
X1156090Y411951D01*
Y412151D01*
X1156590D01*
Y411951D01*
G37*
G36*
G01X1135790Y410401D02*
X1135740Y409651D01*
X1135340D01*
X1135290Y410401D01*
Y410601D01*
X1135790D01*
Y410401D01*
G37*
G36*
G01X1133823Y409326D02*
X1134318Y408760D01*
X1134036Y408477D01*
X1133470Y408972D01*
X1133328Y409113D01*
X1133682Y409467D01*
X1133823Y409326D01*
G37*
G36*
G01X1134106Y410174D02*
X1133611Y410740D01*
X1133894Y411023D01*
X1134460Y410528D01*
X1134601Y410386D01*
X1134248Y410033D01*
X1134106Y410174D01*
G37*
G36*
G01X1132268Y408336D02*
X1131773Y408901D01*
X1132056Y409184D01*
X1132621Y408689D01*
X1132763Y408548D01*
X1132409Y408194D01*
X1132268Y408336D01*
G37*
G36*
G01X1136590Y410801D02*
X1136640Y411551D01*
X1137040D01*
X1137090Y410801D01*
Y410601D01*
X1136590D01*
Y410801D01*
G37*
G36*
G01X1154790D02*
X1154840Y411551D01*
X1155240D01*
X1155290Y410801D01*
Y410601D01*
X1154790D01*
Y410801D01*
G37*
G36*
G01X1152190D02*
X1152240Y411551D01*
X1152640D01*
X1152690Y410801D01*
Y410601D01*
X1152190D01*
Y410801D01*
G37*
G36*
G01X1149590D02*
X1149640Y411551D01*
X1150040D01*
X1150090Y410801D01*
Y410601D01*
X1149590D01*
Y410801D01*
G37*
G36*
G01X1139190D02*
X1139240Y411551D01*
X1139640D01*
X1139690Y410801D01*
Y410601D01*
X1139190D01*
Y410801D01*
G37*
G36*
G01X1141790D02*
X1141840Y411551D01*
X1142240D01*
X1142290Y410801D01*
Y410601D01*
X1141790D01*
Y410801D01*
G37*
G36*
G01X1144390D02*
X1144440Y411551D01*
X1144840D01*
X1144890Y410801D01*
Y410601D01*
X1144390D01*
Y410801D01*
G37*
G36*
G01X1146990D02*
X1147040Y411551D01*
X1147440D01*
X1147490Y410801D01*
Y410601D01*
X1146990D01*
Y410801D01*
G37*
G36*
G01X1153990Y410401D02*
X1153940Y409651D01*
X1153540D01*
X1153490Y410401D01*
Y410601D01*
X1153990D01*
Y410401D01*
G37*
G36*
G01X1151390D02*
X1151340Y409651D01*
X1150940D01*
X1150890Y410401D01*
Y410601D01*
X1151390D01*
Y410401D01*
G37*
G36*
G01X1148790D02*
X1148740Y409651D01*
X1148340D01*
X1148290Y410401D01*
Y410601D01*
X1148790D01*
Y410401D01*
G37*
G36*
G01X1138390D02*
X1138340Y409651D01*
X1137940D01*
X1137890Y410401D01*
Y410601D01*
X1138390D01*
Y410401D01*
G37*
G36*
G01X1140990D02*
X1140940Y409651D01*
X1140540D01*
X1140490Y410401D01*
Y410601D01*
X1140990D01*
Y410401D01*
G37*
G36*
G01X1143590D02*
X1143540Y409651D01*
X1143140D01*
X1143090Y410401D01*
Y410601D01*
X1143590D01*
Y410401D01*
G37*
G36*
G01X1146190D02*
X1146140Y409651D01*
X1145740D01*
X1145690Y410401D01*
Y410601D01*
X1146190D01*
Y410401D01*
G37*
G36*
G01X1156590D02*
X1156540Y409651D01*
X1156140D01*
X1156090Y410401D01*
Y410601D01*
X1156590D01*
Y410401D01*
G37*
G36*
G01X1115800Y411968D02*
X1115040Y412318D01*
Y413218D01*
X1115800Y413568D01*
X1116000D01*
Y411968D01*
X1115800D01*
G37*
G36*
G01X1117982Y418945D02*
X1117487Y419510D01*
X1117770Y419793D01*
X1118335Y419298D01*
X1118477Y419157D01*
X1118123Y418803D01*
X1117982Y418945D01*
G37*
G36*
G01X1119820Y420783D02*
X1119325Y421349D01*
X1119608Y421632D01*
X1120174Y421137D01*
X1120315Y420995D01*
X1119962Y420642D01*
X1119820Y420783D01*
G37*
G36*
G01X1119537Y419935D02*
X1120032Y419369D01*
X1119750Y419086D01*
X1119184Y419581D01*
X1119042Y419722D01*
X1119396Y420076D01*
X1119537Y419935D01*
G37*
G36*
G01X1117699Y418096D02*
X1118194Y417530D01*
X1117911Y417248D01*
X1117345Y417743D01*
X1117204Y417884D01*
X1117558Y418238D01*
X1117699Y418096D01*
G37*
G36*
G01X1121376Y421773D02*
X1121871Y421207D01*
X1121588Y420925D01*
X1121022Y421420D01*
X1120881Y421561D01*
X1121235Y421915D01*
X1121376Y421773D01*
G37*
G36*
G01X1123497Y424460D02*
X1123002Y425026D01*
X1123285Y425309D01*
X1123851Y424814D01*
X1123992Y424672D01*
X1123639Y424319D01*
X1123497Y424460D01*
G37*
G36*
G01X1123214Y423612D02*
X1123709Y423046D01*
X1123427Y422763D01*
X1122861Y423258D01*
X1122719Y423399D01*
X1123073Y423753D01*
X1123214Y423612D01*
G37*
G36*
G01X1121659Y422622D02*
X1121164Y423187D01*
X1121447Y423470D01*
X1122012Y422975D01*
X1122154Y422834D01*
X1121800Y422480D01*
X1121659Y422622D01*
G37*
G36*
G01X1125336Y426299D02*
X1124841Y426864D01*
X1125124Y427147D01*
X1125689Y426652D01*
X1125831Y426511D01*
X1125477Y426157D01*
X1125336Y426299D01*
G37*
G36*
G01X1125053Y425450D02*
X1125548Y424884D01*
X1125265Y424602D01*
X1124699Y425096D01*
X1124558Y425238D01*
X1124911Y425591D01*
X1125053Y425450D01*
G37*
G36*
G01X1127990Y427451D02*
X1127940Y426701D01*
X1127540D01*
X1127490Y427451D01*
Y427651D01*
X1127990D01*
Y427451D01*
G37*
G36*
G01X1130590D02*
X1130540Y426701D01*
X1130140D01*
X1130090Y427451D01*
Y427651D01*
X1130590D01*
Y427451D01*
G37*
G36*
G01X1133190D02*
X1133140Y426701D01*
X1132740D01*
X1132690Y427451D01*
Y427651D01*
X1133190D01*
Y427451D01*
G37*
G36*
G01X1135790D02*
X1135740Y426701D01*
X1135340D01*
X1135290Y427451D01*
Y427651D01*
X1135790D01*
Y427451D01*
G37*
G36*
G01X1128790Y427851D02*
X1128840Y428601D01*
X1129240D01*
X1129290Y427851D01*
Y427651D01*
X1128790D01*
Y427851D01*
G37*
G36*
G01X1131390D02*
X1131440Y428601D01*
X1131840D01*
X1131890Y427851D01*
Y427651D01*
X1131390D01*
Y427851D01*
G37*
G36*
G01X1133990D02*
X1134040Y428601D01*
X1134440D01*
X1134490Y427851D01*
Y427651D01*
X1133990D01*
Y427851D01*
G37*
G36*
G01X1138390Y427451D02*
X1138340Y426701D01*
X1137940D01*
X1137890Y427451D01*
Y427651D01*
X1138390D01*
Y427451D01*
G37*
G36*
G01X1140990D02*
X1140940Y426701D01*
X1140540D01*
X1140490Y427451D01*
Y427651D01*
X1140990D01*
Y427451D01*
G37*
G36*
G01X1143590D02*
X1143540Y426701D01*
X1143140D01*
X1143090Y427451D01*
Y427651D01*
X1143590D01*
Y427451D01*
G37*
G36*
G01X1153990D02*
X1153940Y426701D01*
X1153540D01*
X1153490Y427451D01*
Y427651D01*
X1153990D01*
Y427451D01*
G37*
G36*
G01X1151390D02*
X1151340Y426701D01*
X1150940D01*
X1150890Y427451D01*
Y427651D01*
X1151390D01*
Y427451D01*
G37*
G36*
G01X1148790D02*
X1148740Y426701D01*
X1148340D01*
X1148290Y427451D01*
Y427651D01*
X1148790D01*
Y427451D01*
G37*
G36*
G01X1146190D02*
X1146140Y426701D01*
X1145740D01*
X1145690Y427451D01*
Y427651D01*
X1146190D01*
Y427451D01*
G37*
G36*
G01X1136590Y427851D02*
X1136640Y428601D01*
X1137040D01*
X1137090Y427851D01*
Y427651D01*
X1136590D01*
Y427851D01*
G37*
G36*
G01X1139190D02*
X1139240Y428601D01*
X1139640D01*
X1139690Y427851D01*
Y427651D01*
X1139190D01*
Y427851D01*
G37*
G36*
G01X1141790D02*
X1141840Y428601D01*
X1142240D01*
X1142290Y427851D01*
Y427651D01*
X1141790D01*
Y427851D01*
G37*
G36*
G01X1144390D02*
X1144440Y428601D01*
X1144840D01*
X1144890Y427851D01*
Y427651D01*
X1144390D01*
Y427851D01*
G37*
G36*
G01X1154790D02*
X1154840Y428601D01*
X1155240D01*
X1155290Y427851D01*
Y427651D01*
X1154790D01*
Y427851D01*
G37*
G36*
G01X1152190D02*
X1152240Y428601D01*
X1152640D01*
X1152690Y427851D01*
Y427651D01*
X1152190D01*
Y427851D01*
G37*
G36*
G01X1149590D02*
X1149640Y428601D01*
X1150040D01*
X1150090Y427851D01*
Y427651D01*
X1149590D01*
Y427851D01*
G37*
G36*
G01X1146990D02*
X1147040Y428601D01*
X1147440D01*
X1147490Y427851D01*
Y427651D01*
X1146990D01*
Y427851D01*
G37*
G36*
G01X1156590Y427451D02*
X1156540Y426701D01*
X1156140D01*
X1156090Y427451D01*
Y427651D01*
X1156590D01*
Y427451D01*
G37*
G36*
G01X1116950Y413568D02*
X1117710Y413218D01*
Y412318D01*
X1116950Y411968D01*
X1116750D01*
Y413568D01*
X1116950D01*
G37*
G36*
G01X1122472Y420677D02*
X1122967Y420111D01*
X1122685Y419828D01*
X1122119Y420323D01*
X1121977Y420464D01*
X1122331Y420818D01*
X1122472Y420677D01*
G37*
G36*
G01X1120634Y418838D02*
X1121129Y418272D01*
X1120846Y417990D01*
X1120280Y418485D01*
X1120139Y418626D01*
X1120493Y418980D01*
X1120634Y418838D01*
G37*
G36*
G01X1120917Y419687D02*
X1120422Y420252D01*
X1120705Y420535D01*
X1121270Y420040D01*
X1121412Y419899D01*
X1121058Y419545D01*
X1120917Y419687D01*
G37*
G36*
G01X1119078Y417848D02*
X1118583Y418414D01*
X1118866Y418697D01*
X1119432Y418202D01*
X1119573Y418060D01*
X1119220Y417707D01*
X1119078Y417848D01*
G37*
G36*
G01X1122755Y421525D02*
X1122260Y422091D01*
X1122543Y422374D01*
X1123109Y421879D01*
X1123250Y421737D01*
X1122897Y421384D01*
X1122755Y421525D01*
G37*
G36*
G01X1124311Y422515D02*
X1124806Y421949D01*
X1124523Y421667D01*
X1123957Y422162D01*
X1123816Y422303D01*
X1124169Y422656D01*
X1124311Y422515D01*
G37*
G36*
G01X1126149Y424354D02*
X1126644Y423788D01*
X1126362Y423505D01*
X1125796Y424000D01*
X1125654Y424141D01*
X1126008Y424495D01*
X1126149Y424354D01*
G37*
G36*
G01X1124594Y423364D02*
X1124099Y423929D01*
X1124382Y424212D01*
X1124947Y423717D01*
X1125089Y423576D01*
X1124735Y423222D01*
X1124594Y423364D01*
G37*
G36*
G01X1126432Y425202D02*
X1125937Y425768D01*
X1126220Y426051D01*
X1126786Y425556D01*
X1126927Y425414D01*
X1126574Y425061D01*
X1126432Y425202D01*
G37*
G36*
G01X1130590Y425901D02*
X1130540Y425151D01*
X1130140D01*
X1130090Y425901D01*
Y426101D01*
X1130590D01*
Y425901D01*
G37*
G36*
G01X1133190D02*
X1133140Y425151D01*
X1132740D01*
X1132690Y425901D01*
Y426101D01*
X1133190D01*
Y425901D01*
G37*
G36*
G01X1135790D02*
X1135740Y425151D01*
X1135340D01*
X1135290Y425901D01*
Y426101D01*
X1135790D01*
Y425901D01*
G37*
G36*
G01X1128790Y426301D02*
X1128840Y427051D01*
X1129240D01*
X1129290Y426301D01*
Y426101D01*
X1128790D01*
Y426301D01*
G37*
G36*
G01X1131390D02*
X1131440Y427051D01*
X1131840D01*
X1131890Y426301D01*
Y426101D01*
X1131390D01*
Y426301D01*
G37*
G36*
G01X1133990D02*
X1134040Y427051D01*
X1134440D01*
X1134490Y426301D01*
Y426101D01*
X1133990D01*
Y426301D01*
G37*
G36*
G01X1138390Y425901D02*
X1138340Y425151D01*
X1137940D01*
X1137890Y425901D01*
Y426101D01*
X1138390D01*
Y425901D01*
G37*
G36*
G01X1140990D02*
X1140940Y425151D01*
X1140540D01*
X1140490Y425901D01*
Y426101D01*
X1140990D01*
Y425901D01*
G37*
G36*
G01X1143590D02*
X1143540Y425151D01*
X1143140D01*
X1143090Y425901D01*
Y426101D01*
X1143590D01*
Y425901D01*
G37*
G36*
G01X1153990D02*
X1153940Y425151D01*
X1153540D01*
X1153490Y425901D01*
Y426101D01*
X1153990D01*
Y425901D01*
G37*
G36*
G01X1151390D02*
X1151340Y425151D01*
X1150940D01*
X1150890Y425901D01*
Y426101D01*
X1151390D01*
Y425901D01*
G37*
G36*
G01X1148790D02*
X1148740Y425151D01*
X1148340D01*
X1148290Y425901D01*
Y426101D01*
X1148790D01*
Y425901D01*
G37*
G36*
G01X1146190D02*
X1146140Y425151D01*
X1145740D01*
X1145690Y425901D01*
Y426101D01*
X1146190D01*
Y425901D01*
G37*
G36*
G01X1136590Y426301D02*
X1136640Y427051D01*
X1137040D01*
X1137090Y426301D01*
Y426101D01*
X1136590D01*
Y426301D01*
G37*
G36*
G01X1139190D02*
X1139240Y427051D01*
X1139640D01*
X1139690Y426301D01*
Y426101D01*
X1139190D01*
Y426301D01*
G37*
G36*
G01X1141790D02*
X1141840Y427051D01*
X1142240D01*
X1142290Y426301D01*
Y426101D01*
X1141790D01*
Y426301D01*
G37*
G36*
G01X1144390D02*
X1144440Y427051D01*
X1144840D01*
X1144890Y426301D01*
Y426101D01*
X1144390D01*
Y426301D01*
G37*
G36*
G01X1154790D02*
X1154840Y427051D01*
X1155240D01*
X1155290Y426301D01*
Y426101D01*
X1154790D01*
Y426301D01*
G37*
G36*
G01X1152190D02*
X1152240Y427051D01*
X1152640D01*
X1152690Y426301D01*
Y426101D01*
X1152190D01*
Y426301D01*
G37*
G36*
G01X1149590D02*
X1149640Y427051D01*
X1150040D01*
X1150090Y426301D01*
Y426101D01*
X1149590D01*
Y426301D01*
G37*
G36*
G01X1146990D02*
X1147040Y427051D01*
X1147440D01*
X1147490Y426301D01*
Y426101D01*
X1146990D01*
Y426301D01*
G37*
G36*
G01X1156590Y425901D02*
X1156540Y425151D01*
X1156140D01*
X1156090Y425901D01*
Y426101D01*
X1156590D01*
Y425901D01*
G37*
G36*
G01X1135790Y415051D02*
X1135740Y414301D01*
X1135340D01*
X1135290Y415051D01*
Y415251D01*
X1135790D01*
Y415051D01*
G37*
G36*
G01X1133990Y415451D02*
X1134040Y416201D01*
X1134440D01*
X1134490Y415451D01*
Y415251D01*
X1133990D01*
Y415451D01*
G37*
G36*
G01X1132372Y414454D02*
X1132867Y413888D01*
X1132584Y413606D01*
X1132018Y414101D01*
X1131877Y414242D01*
X1132230Y414595D01*
X1132372Y414454D01*
G37*
G36*
G01X1130533Y412616D02*
X1131028Y412050D01*
X1130746Y411767D01*
X1130180Y412262D01*
X1130038Y412403D01*
X1130392Y412757D01*
X1130533Y412616D01*
G37*
G36*
G01X1130816Y413464D02*
X1130321Y414030D01*
X1130604Y414313D01*
X1131170Y413818D01*
X1131311Y413676D01*
X1130958Y413323D01*
X1130816Y413464D01*
G37*
G36*
G01X1128695Y410777D02*
X1129190Y410211D01*
X1128907Y409929D01*
X1128341Y410424D01*
X1128200Y410565D01*
X1128554Y410919D01*
X1128695Y410777D01*
G37*
G36*
G01X1128978Y411626D02*
X1128483Y412191D01*
X1128766Y412474D01*
X1129331Y411979D01*
X1129473Y411838D01*
X1129119Y411484D01*
X1128978Y411626D01*
G37*
G36*
G01X1153990Y415051D02*
X1153940Y414301D01*
X1153540D01*
X1153490Y415051D01*
Y415251D01*
X1153990D01*
Y415051D01*
G37*
G36*
G01X1151390D02*
X1151340Y414301D01*
X1150940D01*
X1150890Y415051D01*
Y415251D01*
X1151390D01*
Y415051D01*
G37*
G36*
G01X1148790D02*
X1148740Y414301D01*
X1148340D01*
X1148290Y415051D01*
Y415251D01*
X1148790D01*
Y415051D01*
G37*
G36*
G01X1138390D02*
X1138340Y414301D01*
X1137940D01*
X1137890Y415051D01*
Y415251D01*
X1138390D01*
Y415051D01*
G37*
G36*
G01X1140990D02*
X1140940Y414301D01*
X1140540D01*
X1140490Y415051D01*
Y415251D01*
X1140990D01*
Y415051D01*
G37*
G36*
G01X1143590D02*
X1143540Y414301D01*
X1143140D01*
X1143090Y415051D01*
Y415251D01*
X1143590D01*
Y415051D01*
G37*
G36*
G01X1146190D02*
X1146140Y414301D01*
X1145740D01*
X1145690Y415051D01*
Y415251D01*
X1146190D01*
Y415051D01*
G37*
G36*
G01X1154790Y415451D02*
X1154840Y416201D01*
X1155240D01*
X1155290Y415451D01*
Y415251D01*
X1154790D01*
Y415451D01*
G37*
G36*
G01X1152190D02*
X1152240Y416201D01*
X1152640D01*
X1152690Y415451D01*
Y415251D01*
X1152190D01*
Y415451D01*
G37*
G36*
G01X1149590D02*
X1149640Y416201D01*
X1150040D01*
X1150090Y415451D01*
Y415251D01*
X1149590D01*
Y415451D01*
G37*
G36*
G01X1136590D02*
X1136640Y416201D01*
X1137040D01*
X1137090Y415451D01*
Y415251D01*
X1136590D01*
Y415451D01*
G37*
G36*
G01X1139190D02*
X1139240Y416201D01*
X1139640D01*
X1139690Y415451D01*
Y415251D01*
X1139190D01*
Y415451D01*
G37*
G36*
G01X1141790D02*
X1141840Y416201D01*
X1142240D01*
X1142290Y415451D01*
Y415251D01*
X1141790D01*
Y415451D01*
G37*
G36*
G01X1144390D02*
X1144440Y416201D01*
X1144840D01*
X1144890Y415451D01*
Y415251D01*
X1144390D01*
Y415451D01*
G37*
G36*
G01X1146990D02*
X1147040Y416201D01*
X1147440D01*
X1147490Y415451D01*
Y415251D01*
X1146990D01*
Y415451D01*
G37*
G36*
G01X1156590Y415051D02*
X1156540Y414301D01*
X1156140D01*
X1156090Y415051D01*
Y415251D01*
X1156590D01*
Y415051D01*
G37*
G36*
G01X1135790Y413501D02*
X1135740Y412751D01*
X1135340D01*
X1135290Y413501D01*
Y413701D01*
X1135790D01*
Y413501D01*
G37*
G36*
G01X1133990Y413901D02*
X1134040Y414651D01*
X1134440D01*
X1134490Y413901D01*
Y413701D01*
X1133990D01*
Y413901D01*
G37*
G36*
G01X1131630Y411519D02*
X1132125Y410953D01*
X1131842Y410671D01*
X1131276Y411166D01*
X1131135Y411307D01*
X1131489Y411661D01*
X1131630Y411519D01*
G37*
G36*
G01X1131913Y412368D02*
X1131418Y412933D01*
X1131701Y413216D01*
X1132266Y412721D01*
X1132408Y412580D01*
X1132054Y412226D01*
X1131913Y412368D01*
G37*
G36*
G01X1129791Y409681D02*
X1130286Y409115D01*
X1130004Y408832D01*
X1129438Y409327D01*
X1129296Y409468D01*
X1129650Y409822D01*
X1129791Y409681D01*
G37*
G36*
G01X1130074Y410529D02*
X1129579Y411095D01*
X1129862Y411378D01*
X1130428Y410883D01*
X1130569Y410741D01*
X1130216Y410388D01*
X1130074Y410529D01*
G37*
G36*
G01X1136590Y413901D02*
X1136640Y414651D01*
X1137040D01*
X1137090Y413901D01*
Y413701D01*
X1136590D01*
Y413901D01*
G37*
G36*
G01X1153990Y413501D02*
X1153940Y412751D01*
X1153540D01*
X1153490Y413501D01*
Y413701D01*
X1153990D01*
Y413501D01*
G37*
G36*
G01X1151390D02*
X1151340Y412751D01*
X1150940D01*
X1150890Y413501D01*
Y413701D01*
X1151390D01*
Y413501D01*
G37*
G36*
G01X1148790D02*
X1148740Y412751D01*
X1148340D01*
X1148290Y413501D01*
Y413701D01*
X1148790D01*
Y413501D01*
G37*
G36*
G01X1138390D02*
X1138340Y412751D01*
X1137940D01*
X1137890Y413501D01*
Y413701D01*
X1138390D01*
Y413501D01*
G37*
G36*
G01X1140990D02*
X1140940Y412751D01*
X1140540D01*
X1140490Y413501D01*
Y413701D01*
X1140990D01*
Y413501D01*
G37*
G36*
G01X1143590D02*
X1143540Y412751D01*
X1143140D01*
X1143090Y413501D01*
Y413701D01*
X1143590D01*
Y413501D01*
G37*
G36*
G01X1146190D02*
X1146140Y412751D01*
X1145740D01*
X1145690Y413501D01*
Y413701D01*
X1146190D01*
Y413501D01*
G37*
G36*
G01X1154790Y413901D02*
X1154840Y414651D01*
X1155240D01*
X1155290Y413901D01*
Y413701D01*
X1154790D01*
Y413901D01*
G37*
G36*
G01X1152190D02*
X1152240Y414651D01*
X1152640D01*
X1152690Y413901D01*
Y413701D01*
X1152190D01*
Y413901D01*
G37*
G36*
G01X1149590D02*
X1149640Y414651D01*
X1150040D01*
X1150090Y413901D01*
Y413701D01*
X1149590D01*
Y413901D01*
G37*
G36*
G01X1139190D02*
X1139240Y414651D01*
X1139640D01*
X1139690Y413901D01*
Y413701D01*
X1139190D01*
Y413901D01*
G37*
G36*
G01X1141790D02*
X1141840Y414651D01*
X1142240D01*
X1142290Y413901D01*
Y413701D01*
X1141790D01*
Y413901D01*
G37*
G36*
G01X1144390D02*
X1144440Y414651D01*
X1144840D01*
X1144890Y413901D01*
Y413701D01*
X1144390D01*
Y413901D01*
G37*
G36*
G01X1146990D02*
X1147040Y414651D01*
X1147440D01*
X1147490Y413901D01*
Y413701D01*
X1146990D01*
Y413901D01*
G37*
G36*
G01X1156590Y413501D02*
X1156540Y412751D01*
X1156140D01*
X1156090Y413501D01*
Y413701D01*
X1156590D01*
Y413501D01*
G37*
G36*
G01X1103205Y415912D02*
X1103965Y415562D01*
Y414662D01*
X1103205Y414312D01*
X1103030D01*
Y415912D01*
X1103205D01*
G37*
G36*
G01Y412012D02*
X1103965Y411662D01*
Y410762D01*
X1103205Y410412D01*
X1103030D01*
Y412012D01*
X1103205D01*
G37*
G36*
G01X1103230Y420376D02*
X1102480Y420426D01*
Y420826D01*
X1103230Y420876D01*
X1103430D01*
Y420376D01*
X1103230D01*
G37*
G36*
G01Y417776D02*
X1102480Y417826D01*
Y418226D01*
X1103230Y418276D01*
X1103430D01*
Y417776D01*
X1103230D01*
G37*
G36*
G01X1103630Y419576D02*
X1104380Y419526D01*
Y419126D01*
X1103630Y419076D01*
X1103430D01*
Y419576D01*
X1103630D01*
G37*
G36*
G01X1103230Y425576D02*
X1102480Y425626D01*
Y426026D01*
X1103230Y426076D01*
X1103430D01*
Y425576D01*
X1103230D01*
G37*
G36*
G01Y428176D02*
X1102480Y428226D01*
Y428626D01*
X1103230Y428676D01*
X1103430D01*
Y428176D01*
X1103230D01*
G37*
G36*
G01Y422976D02*
X1102480Y423026D01*
Y423426D01*
X1103230Y423476D01*
X1103430D01*
Y422976D01*
X1103230D01*
G37*
G36*
G01X1103630Y427376D02*
X1104380Y427326D01*
Y426926D01*
X1103630Y426876D01*
X1103430D01*
Y427376D01*
X1103630D01*
G37*
G36*
G01Y424776D02*
X1104380Y424726D01*
Y424326D01*
X1103630Y424276D01*
X1103430D01*
Y424776D01*
X1103630D01*
G37*
G36*
G01Y422176D02*
X1104380Y422126D01*
Y421726D01*
X1103630Y421676D01*
X1103430D01*
Y422176D01*
X1103630D01*
G37*
G36*
G01X1115447Y440752D02*
X1115942Y440186D01*
X1115659Y439904D01*
X1115093Y440399D01*
X1114952Y440540D01*
X1115305Y440893D01*
X1115447Y440752D01*
G37*
G36*
G01X1117285Y442591D02*
X1117780Y442025D01*
X1117498Y441742D01*
X1116932Y442237D01*
X1116790Y442378D01*
X1117144Y442732D01*
X1117285Y442591D01*
G37*
G36*
G01X1119124Y444429D02*
X1119619Y443863D01*
X1119336Y443580D01*
X1118770Y444075D01*
X1118629Y444217D01*
X1118982Y444570D01*
X1119124Y444429D01*
G37*
G36*
G01X1113608Y438914D02*
X1114103Y438348D01*
X1113821Y438065D01*
X1113255Y438560D01*
X1113113Y438701D01*
X1113467Y439055D01*
X1113608Y438914D01*
G37*
G36*
G01X1111770Y437075D02*
X1112265Y436509D01*
X1111982Y436227D01*
X1111416Y436722D01*
X1111275Y436863D01*
X1111629Y437217D01*
X1111770Y437075D01*
G37*
G36*
G01X1109931Y435237D02*
X1110426Y434671D01*
X1110144Y434388D01*
X1109578Y434883D01*
X1109437Y435025D01*
X1109790Y435378D01*
X1109931Y435237D01*
G37*
G36*
G01X1108093Y433398D02*
X1108588Y432832D01*
X1108305Y432550D01*
X1107739Y433045D01*
X1107598Y433186D01*
X1107952Y433540D01*
X1108093Y433398D01*
G37*
G36*
G01X1106255Y431560D02*
X1106750Y430994D01*
X1106467Y430711D01*
X1105901Y431206D01*
X1105760Y431348D01*
X1106113Y431701D01*
X1106255Y431560D01*
G37*
G36*
G01X1104416Y429721D02*
X1104911Y429156D01*
X1104628Y428873D01*
X1104062Y429368D01*
X1103921Y429509D01*
X1104275Y429863D01*
X1104416Y429721D01*
G37*
G36*
G01X1113891Y439762D02*
X1113396Y440328D01*
X1113679Y440611D01*
X1114245Y440116D01*
X1114386Y439974D01*
X1114033Y439621D01*
X1113891Y439762D01*
G37*
G36*
G01X1115730Y441601D02*
X1115235Y442166D01*
X1115518Y442449D01*
X1116083Y441954D01*
X1116225Y441813D01*
X1115871Y441459D01*
X1115730Y441601D01*
G37*
G36*
G01X1117568Y443439D02*
X1117073Y444005D01*
X1117356Y444288D01*
X1117922Y443793D01*
X1118063Y443651D01*
X1117710Y443298D01*
X1117568Y443439D01*
G37*
G36*
G01X1112053Y437924D02*
X1111558Y438489D01*
X1111841Y438772D01*
X1112406Y438277D01*
X1112548Y438136D01*
X1112194Y437782D01*
X1112053Y437924D01*
G37*
G36*
G01X1110214Y436085D02*
X1109719Y436651D01*
X1110002Y436934D01*
X1110568Y436439D01*
X1110709Y436297D01*
X1110356Y435944D01*
X1110214Y436085D01*
G37*
G36*
G01X1108376Y434247D02*
X1107881Y434812D01*
X1108164Y435095D01*
X1108729Y434600D01*
X1108871Y434459D01*
X1108517Y434105D01*
X1108376Y434247D01*
G37*
G36*
G01X1106537Y432408D02*
X1106042Y432974D01*
X1106325Y433257D01*
X1106891Y432762D01*
X1107032Y432620D01*
X1106679Y432267D01*
X1106537Y432408D01*
G37*
G36*
G01X1104699Y430570D02*
X1104204Y431135D01*
X1104487Y431418D01*
X1105052Y430923D01*
X1105194Y430782D01*
X1104840Y430428D01*
X1104699Y430570D01*
G37*
G36*
G01X1123350Y412240D02*
X1124110Y411890D01*
Y410990D01*
X1123350Y410640D01*
X1123150D01*
Y412240D01*
X1123350D01*
G37*
G36*
G01X1126860Y416289D02*
X1127355Y415723D01*
X1127073Y415440D01*
X1126507Y415935D01*
X1126365Y416076D01*
X1126719Y416430D01*
X1126860Y416289D01*
G37*
G36*
G01X1125305Y415299D02*
X1124810Y415864D01*
X1125093Y416147D01*
X1125658Y415652D01*
X1125800Y415511D01*
X1125446Y415157D01*
X1125305Y415299D01*
G37*
G36*
G01X1133190Y419701D02*
X1133140Y418951D01*
X1132740D01*
X1132690Y419701D01*
Y419901D01*
X1133190D01*
Y419701D01*
G37*
G36*
G01X1135790D02*
X1135740Y418951D01*
X1135340D01*
X1135290Y419701D01*
Y419901D01*
X1135790D01*
Y419701D01*
G37*
G36*
G01X1131390Y420101D02*
X1131440Y420851D01*
X1131840D01*
X1131890Y420101D01*
Y419901D01*
X1131390D01*
Y420101D01*
G37*
G36*
G01X1133990D02*
X1134040Y420851D01*
X1134440D01*
X1134490Y420101D01*
Y419901D01*
X1133990D01*
Y420101D01*
G37*
G36*
G01X1128699Y418127D02*
X1129194Y417561D01*
X1128911Y417279D01*
X1128345Y417774D01*
X1128204Y417915D01*
X1128557Y418268D01*
X1128699Y418127D01*
G37*
G36*
G01X1127143Y417137D02*
X1126648Y417703D01*
X1126931Y417986D01*
X1127497Y417491D01*
X1127638Y417349D01*
X1127285Y416996D01*
X1127143Y417137D01*
G37*
G36*
G01X1128982Y418976D02*
X1128487Y419541D01*
X1128770Y419824D01*
X1129335Y419329D01*
X1129477Y419188D01*
X1129123Y418834D01*
X1128982Y418976D01*
G37*
G36*
G01X1138390Y419701D02*
X1138340Y418951D01*
X1137940D01*
X1137890Y419701D01*
Y419901D01*
X1138390D01*
Y419701D01*
G37*
G36*
G01X1140990D02*
X1140940Y418951D01*
X1140540D01*
X1140490Y419701D01*
Y419901D01*
X1140990D01*
Y419701D01*
G37*
G36*
G01X1143590D02*
X1143540Y418951D01*
X1143140D01*
X1143090Y419701D01*
Y419901D01*
X1143590D01*
Y419701D01*
G37*
G36*
G01X1146190D02*
X1146140Y418951D01*
X1145740D01*
X1145690Y419701D01*
Y419901D01*
X1146190D01*
Y419701D01*
G37*
G36*
G01X1153990D02*
X1153940Y418951D01*
X1153540D01*
X1153490Y419701D01*
Y419901D01*
X1153990D01*
Y419701D01*
G37*
G36*
G01X1151390D02*
X1151340Y418951D01*
X1150940D01*
X1150890Y419701D01*
Y419901D01*
X1151390D01*
Y419701D01*
G37*
G36*
G01X1148790D02*
X1148740Y418951D01*
X1148340D01*
X1148290Y419701D01*
Y419901D01*
X1148790D01*
Y419701D01*
G37*
G36*
G01X1136590Y420101D02*
X1136640Y420851D01*
X1137040D01*
X1137090Y420101D01*
Y419901D01*
X1136590D01*
Y420101D01*
G37*
G36*
G01X1139190D02*
X1139240Y420851D01*
X1139640D01*
X1139690Y420101D01*
Y419901D01*
X1139190D01*
Y420101D01*
G37*
G36*
G01X1141790D02*
X1141840Y420851D01*
X1142240D01*
X1142290Y420101D01*
Y419901D01*
X1141790D01*
Y420101D01*
G37*
G36*
G01X1144390D02*
X1144440Y420851D01*
X1144840D01*
X1144890Y420101D01*
Y419901D01*
X1144390D01*
Y420101D01*
G37*
G36*
G01X1146990D02*
X1147040Y420851D01*
X1147440D01*
X1147490Y420101D01*
Y419901D01*
X1146990D01*
Y420101D01*
G37*
G36*
G01X1154790D02*
X1154840Y420851D01*
X1155240D01*
X1155290Y420101D01*
Y419901D01*
X1154790D01*
Y420101D01*
G37*
G36*
G01X1152190D02*
X1152240Y420851D01*
X1152640D01*
X1152690Y420101D01*
Y419901D01*
X1152190D01*
Y420101D01*
G37*
G36*
G01X1149590D02*
X1149640Y420851D01*
X1150040D01*
X1150090Y420101D01*
Y419901D01*
X1149590D01*
Y420101D01*
G37*
G36*
G01X1156590Y419701D02*
X1156540Y418951D01*
X1156140D01*
X1156090Y419701D01*
Y419901D01*
X1156590D01*
Y419701D01*
G37*
G36*
G01X1105205Y414308D02*
X1104445Y414658D01*
Y415558D01*
X1105205Y415908D01*
X1105380D01*
Y414308D01*
X1105205D01*
G37*
G36*
G01Y410408D02*
X1104445Y410758D01*
Y411658D01*
X1105205Y412008D01*
X1105380D01*
Y410408D01*
X1105205D01*
G37*
G36*
G01X1104780Y420376D02*
X1104030Y420426D01*
Y420826D01*
X1104780Y420876D01*
X1104980D01*
Y420376D01*
X1104780D01*
G37*
G36*
G01Y417776D02*
X1104030Y417826D01*
Y418226D01*
X1104780Y418276D01*
X1104980D01*
Y417776D01*
X1104780D01*
G37*
G36*
G01X1105180Y419576D02*
X1105930Y419526D01*
Y419126D01*
X1105180Y419076D01*
X1104980D01*
Y419576D01*
X1105180D01*
G37*
G36*
G01X1104780Y425576D02*
X1104030Y425626D01*
Y426026D01*
X1104780Y426076D01*
X1104980D01*
Y425576D01*
X1104780D01*
G37*
G36*
G01Y422976D02*
X1104030Y423026D01*
Y423426D01*
X1104780Y423476D01*
X1104980D01*
Y422976D01*
X1104780D01*
G37*
G36*
G01X1105180Y427376D02*
X1105930Y427326D01*
Y426926D01*
X1105180Y426876D01*
X1104980D01*
Y427376D01*
X1105180D01*
G37*
G36*
G01Y424776D02*
X1105930Y424726D01*
Y424326D01*
X1105180Y424276D01*
X1104980D01*
Y424776D01*
X1105180D01*
G37*
G36*
G01Y422176D02*
X1105930Y422126D01*
Y421726D01*
X1105180Y421676D01*
X1104980D01*
Y422176D01*
X1105180D01*
G37*
G36*
G01X1116544Y439655D02*
X1117039Y439089D01*
X1116756Y438807D01*
X1116190Y439302D01*
X1116049Y439443D01*
X1116402Y439796D01*
X1116544Y439655D01*
G37*
G36*
G01X1118382Y441494D02*
X1118877Y440928D01*
X1118595Y440645D01*
X1118029Y441140D01*
X1117887Y441281D01*
X1118241Y441635D01*
X1118382Y441494D01*
G37*
G36*
G01X1120221Y443332D02*
X1120716Y442766D01*
X1120433Y442483D01*
X1119867Y442978D01*
X1119726Y443120D01*
X1120079Y443473D01*
X1120221Y443332D01*
G37*
G36*
G01X1114705Y437817D02*
X1115200Y437251D01*
X1114918Y436968D01*
X1114352Y437463D01*
X1114210Y437604D01*
X1114564Y437958D01*
X1114705Y437817D01*
G37*
G36*
G01X1112867Y435978D02*
X1113362Y435412D01*
X1113079Y435130D01*
X1112513Y435625D01*
X1112372Y435766D01*
X1112726Y436120D01*
X1112867Y435978D01*
G37*
G36*
G01X1111028Y434140D02*
X1111523Y433574D01*
X1111241Y433291D01*
X1110675Y433786D01*
X1110534Y433928D01*
X1110887Y434281D01*
X1111028Y434140D01*
G37*
G36*
G01X1109190Y432301D02*
X1109685Y431735D01*
X1109402Y431453D01*
X1108836Y431948D01*
X1108695Y432089D01*
X1109049Y432443D01*
X1109190Y432301D01*
G37*
G36*
G01X1107352Y430463D02*
X1107847Y429897D01*
X1107564Y429614D01*
X1106998Y430109D01*
X1106857Y430251D01*
X1107210Y430604D01*
X1107352Y430463D01*
G37*
G36*
G01X1114988Y438665D02*
X1114493Y439231D01*
X1114776Y439514D01*
X1115342Y439019D01*
X1115483Y438877D01*
X1115130Y438524D01*
X1114988Y438665D01*
G37*
G36*
G01X1116827Y440504D02*
X1116332Y441069D01*
X1116615Y441352D01*
X1117180Y440857D01*
X1117322Y440716D01*
X1116968Y440362D01*
X1116827Y440504D01*
G37*
G36*
G01X1118665Y442342D02*
X1118170Y442908D01*
X1118453Y443191D01*
X1119019Y442696D01*
X1119160Y442554D01*
X1118807Y442201D01*
X1118665Y442342D01*
G37*
G36*
G01X1120504Y444181D02*
X1120009Y444746D01*
X1120292Y445029D01*
X1120857Y444534D01*
X1120999Y444393D01*
X1120645Y444039D01*
X1120504Y444181D01*
G37*
G36*
G01X1113150Y436827D02*
X1112655Y437392D01*
X1112938Y437675D01*
X1113503Y437180D01*
X1113645Y437039D01*
X1113291Y436685D01*
X1113150Y436827D01*
G37*
G36*
G01X1111311Y434988D02*
X1110816Y435554D01*
X1111099Y435837D01*
X1111665Y435342D01*
X1111806Y435200D01*
X1111453Y434847D01*
X1111311Y434988D01*
G37*
G36*
G01X1109473Y433150D02*
X1108978Y433715D01*
X1109261Y433998D01*
X1109826Y433503D01*
X1109968Y433362D01*
X1109614Y433008D01*
X1109473Y433150D01*
G37*
G36*
G01X1107634Y431311D02*
X1107139Y431877D01*
X1107422Y432160D01*
X1107988Y431665D01*
X1108129Y431523D01*
X1107776Y431170D01*
X1107634Y431311D01*
G37*
G36*
G01X1105796Y429473D02*
X1105301Y430038D01*
X1105584Y430321D01*
X1106149Y429826D01*
X1106291Y429685D01*
X1105937Y429331D01*
X1105796Y429473D01*
G37*
G36*
G01X1127957Y415192D02*
X1128452Y414626D01*
X1128170Y414343D01*
X1127604Y414838D01*
X1127462Y414979D01*
X1127816Y415333D01*
X1127957Y415192D01*
G37*
G36*
G01X1133190Y418151D02*
X1133140Y417401D01*
X1132740D01*
X1132690Y418151D01*
Y418351D01*
X1133190D01*
Y418151D01*
G37*
G36*
G01X1135790D02*
X1135740Y417401D01*
X1135340D01*
X1135290Y418151D01*
Y418351D01*
X1135790D01*
Y418151D01*
G37*
G36*
G01X1131390Y418551D02*
X1131440Y419301D01*
X1131840D01*
X1131890Y418551D01*
Y418351D01*
X1131390D01*
Y418551D01*
G37*
G36*
G01X1133990D02*
X1134040Y419301D01*
X1134440D01*
X1134490Y418551D01*
Y418351D01*
X1133990D01*
Y418551D01*
G37*
G36*
G01X1129796Y417030D02*
X1130291Y416464D01*
X1130008Y416182D01*
X1129442Y416677D01*
X1129301Y416818D01*
X1129654Y417171D01*
X1129796Y417030D01*
G37*
G36*
G01X1128240Y416040D02*
X1127745Y416606D01*
X1128028Y416889D01*
X1128594Y416394D01*
X1128735Y416252D01*
X1128382Y415899D01*
X1128240Y416040D01*
G37*
G36*
G01X1130079Y417879D02*
X1129584Y418444D01*
X1129867Y418727D01*
X1130432Y418232D01*
X1130574Y418091D01*
X1130220Y417737D01*
X1130079Y417879D01*
G37*
G36*
G01X1138390Y418151D02*
X1138340Y417401D01*
X1137940D01*
X1137890Y418151D01*
Y418351D01*
X1138390D01*
Y418151D01*
G37*
G36*
G01X1140990D02*
X1140940Y417401D01*
X1140540D01*
X1140490Y418151D01*
Y418351D01*
X1140990D01*
Y418151D01*
G37*
G36*
G01X1143590D02*
X1143540Y417401D01*
X1143140D01*
X1143090Y418151D01*
Y418351D01*
X1143590D01*
Y418151D01*
G37*
G36*
G01X1146190D02*
X1146140Y417401D01*
X1145740D01*
X1145690Y418151D01*
Y418351D01*
X1146190D01*
Y418151D01*
G37*
G36*
G01X1153990D02*
X1153940Y417401D01*
X1153540D01*
X1153490Y418151D01*
Y418351D01*
X1153990D01*
Y418151D01*
G37*
G36*
G01X1151390D02*
X1151340Y417401D01*
X1150940D01*
X1150890Y418151D01*
Y418351D01*
X1151390D01*
Y418151D01*
G37*
G36*
G01X1148790D02*
X1148740Y417401D01*
X1148340D01*
X1148290Y418151D01*
Y418351D01*
X1148790D01*
Y418151D01*
G37*
G36*
G01X1136590Y418551D02*
X1136640Y419301D01*
X1137040D01*
X1137090Y418551D01*
Y418351D01*
X1136590D01*
Y418551D01*
G37*
G36*
G01X1139190D02*
X1139240Y419301D01*
X1139640D01*
X1139690Y418551D01*
Y418351D01*
X1139190D01*
Y418551D01*
G37*
G36*
G01X1141790D02*
X1141840Y419301D01*
X1142240D01*
X1142290Y418551D01*
Y418351D01*
X1141790D01*
Y418551D01*
G37*
G36*
G01X1144390D02*
X1144440Y419301D01*
X1144840D01*
X1144890Y418551D01*
Y418351D01*
X1144390D01*
Y418551D01*
G37*
G36*
G01X1146990D02*
X1147040Y419301D01*
X1147440D01*
X1147490Y418551D01*
Y418351D01*
X1146990D01*
Y418551D01*
G37*
G36*
G01X1154790D02*
X1154840Y419301D01*
X1155240D01*
X1155290Y418551D01*
Y418351D01*
X1154790D01*
Y418551D01*
G37*
G36*
G01X1152190D02*
X1152240Y419301D01*
X1152640D01*
X1152690Y418551D01*
Y418351D01*
X1152190D01*
Y418551D01*
G37*
G36*
G01X1149590D02*
X1149640Y419301D01*
X1150040D01*
X1150090Y418551D01*
Y418351D01*
X1149590D01*
Y418551D01*
G37*
G36*
G01X1156590Y418151D02*
X1156540Y417401D01*
X1156140D01*
X1156090Y418151D01*
Y418351D01*
X1156590D01*
Y418151D01*
G37*
G36*
G01X1102105Y414312D02*
X1101345Y414662D01*
Y415562D01*
X1102105Y415912D01*
X1102280D01*
Y414312D01*
X1102105D01*
G37*
G36*
G01Y410412D02*
X1101345Y410762D01*
Y411662D01*
X1102105Y412012D01*
X1102280D01*
Y410412D01*
X1102105D01*
G37*
G36*
G01X1101680Y420376D02*
X1100930Y420426D01*
Y420826D01*
X1101680Y420876D01*
X1101880D01*
Y420376D01*
X1101680D01*
G37*
G36*
G01Y417776D02*
X1100930Y417826D01*
Y418226D01*
X1101680Y418276D01*
X1101880D01*
Y417776D01*
X1101680D01*
G37*
G36*
G01X1102080Y419576D02*
X1102830Y419526D01*
Y419126D01*
X1102080Y419076D01*
X1101880D01*
Y419576D01*
X1102080D01*
G37*
G36*
G01X1101680Y425576D02*
X1100930Y425626D01*
Y426026D01*
X1101680Y426076D01*
X1101880D01*
Y425576D01*
X1101680D01*
G37*
G36*
G01Y428176D02*
X1100930Y428226D01*
Y428626D01*
X1101680Y428676D01*
X1101880D01*
Y428176D01*
X1101680D01*
G37*
G36*
G01Y422976D02*
X1100930Y423026D01*
Y423426D01*
X1101680Y423476D01*
X1101880D01*
Y422976D01*
X1101680D01*
G37*
G36*
G01X1102080Y427376D02*
X1102830Y427326D01*
Y426926D01*
X1102080Y426876D01*
X1101880D01*
Y427376D01*
X1102080D01*
G37*
G36*
G01Y424776D02*
X1102830Y424726D01*
Y424326D01*
X1102080Y424276D01*
X1101880D01*
Y424776D01*
X1102080D01*
G37*
G36*
G01Y422176D02*
X1102830Y422126D01*
Y421726D01*
X1102080Y421676D01*
X1101880D01*
Y422176D01*
X1102080D01*
G37*
G36*
G01X1112512Y440010D02*
X1113007Y439444D01*
X1112724Y439162D01*
X1112158Y439657D01*
X1112017Y439798D01*
X1112371Y440152D01*
X1112512Y440010D01*
G37*
G36*
G01X1114350Y441849D02*
X1114845Y441283D01*
X1114563Y441000D01*
X1113997Y441495D01*
X1113855Y441636D01*
X1114209Y441990D01*
X1114350Y441849D01*
G37*
G36*
G01X1116189Y443687D02*
X1116684Y443121D01*
X1116401Y442839D01*
X1115835Y443333D01*
X1115694Y443475D01*
X1116047Y443828D01*
X1116189Y443687D01*
G37*
G36*
G01X1118027Y445526D02*
X1118522Y444960D01*
X1118240Y444677D01*
X1117674Y445172D01*
X1117532Y445313D01*
X1117886Y445667D01*
X1118027Y445526D01*
G37*
G36*
G01X1110673Y438172D02*
X1111168Y437606D01*
X1110886Y437323D01*
X1110320Y437818D01*
X1110178Y437959D01*
X1110532Y438313D01*
X1110673Y438172D01*
G37*
G36*
G01X1108835Y436333D02*
X1109330Y435767D01*
X1109047Y435485D01*
X1108481Y435980D01*
X1108340Y436121D01*
X1108694Y436475D01*
X1108835Y436333D01*
G37*
G36*
G01X1106997Y434495D02*
X1107491Y433929D01*
X1107209Y433646D01*
X1106643Y434141D01*
X1106502Y434283D01*
X1106855Y434636D01*
X1106997Y434495D01*
G37*
G36*
G01X1105158Y432656D02*
X1105653Y432090D01*
X1105370Y431808D01*
X1104804Y432303D01*
X1104663Y432444D01*
X1105017Y432798D01*
X1105158Y432656D01*
G37*
G36*
G01X1103320Y430818D02*
X1103815Y430252D01*
X1103532Y429969D01*
X1102966Y430464D01*
X1102825Y430606D01*
X1103178Y430959D01*
X1103320Y430818D01*
G37*
G36*
G01X1110956Y439020D02*
X1110461Y439586D01*
X1110744Y439869D01*
X1111310Y439374D01*
X1111451Y439232D01*
X1111098Y438879D01*
X1110956Y439020D01*
G37*
G36*
G01X1112795Y440859D02*
X1112300Y441424D01*
X1112583Y441707D01*
X1113148Y441212D01*
X1113290Y441071D01*
X1112936Y440717D01*
X1112795Y440859D01*
G37*
G36*
G01X1114633Y442697D02*
X1114138Y443263D01*
X1114421Y443546D01*
X1114987Y443051D01*
X1115128Y442909D01*
X1114775Y442556D01*
X1114633Y442697D01*
G37*
G36*
G01X1109118Y437182D02*
X1108623Y437747D01*
X1108906Y438030D01*
X1109471Y437535D01*
X1109613Y437394D01*
X1109259Y437040D01*
X1109118Y437182D01*
G37*
G36*
G01X1107279Y435343D02*
X1106784Y435909D01*
X1107067Y436192D01*
X1107633Y435697D01*
X1107774Y435555D01*
X1107421Y435202D01*
X1107279Y435343D01*
G37*
G36*
G01X1105441Y433505D02*
X1104946Y434070D01*
X1105229Y434353D01*
X1105794Y433858D01*
X1105936Y433717D01*
X1105582Y433363D01*
X1105441Y433505D01*
G37*
G36*
G01X1103602Y431666D02*
X1103107Y432232D01*
X1103390Y432515D01*
X1103956Y432020D01*
X1104097Y431878D01*
X1103744Y431525D01*
X1103602Y431666D01*
G37*
G36*
G01X1122200Y410640D02*
X1121440Y410990D01*
Y411890D01*
X1122200Y412240D01*
X1122400D01*
Y410640D01*
X1122200D01*
G37*
G36*
G01X1125763Y417386D02*
X1126258Y416820D01*
X1125976Y416537D01*
X1125410Y417032D01*
X1125268Y417173D01*
X1125622Y417527D01*
X1125763Y417386D01*
G37*
G36*
G01X1124208Y416396D02*
X1123713Y416961D01*
X1123996Y417244D01*
X1124561Y416749D01*
X1124703Y416608D01*
X1124349Y416254D01*
X1124208Y416396D01*
G37*
G36*
G01X1126046Y418234D02*
X1125551Y418800D01*
X1125834Y419083D01*
X1126400Y418588D01*
X1126541Y418446D01*
X1126188Y418093D01*
X1126046Y418234D01*
G37*
G36*
G01X1130590Y421251D02*
X1130540Y420501D01*
X1130140D01*
X1130090Y421251D01*
Y421451D01*
X1130590D01*
Y421251D01*
G37*
G36*
G01X1133190D02*
X1133140Y420501D01*
X1132740D01*
X1132690Y421251D01*
Y421451D01*
X1133190D01*
Y421251D01*
G37*
G36*
G01X1135790D02*
X1135740Y420501D01*
X1135340D01*
X1135290Y421251D01*
Y421451D01*
X1135790D01*
Y421251D01*
G37*
G36*
G01X1127602Y419224D02*
X1128097Y418658D01*
X1127814Y418376D01*
X1127248Y418871D01*
X1127107Y419012D01*
X1127460Y419365D01*
X1127602Y419224D01*
G37*
G36*
G01X1127885Y420073D02*
X1127390Y420638D01*
X1127673Y420921D01*
X1128238Y420426D01*
X1128380Y420285D01*
X1128026Y419931D01*
X1127885Y420073D01*
G37*
G36*
G01X1131390Y421651D02*
X1131440Y422401D01*
X1131840D01*
X1131890Y421651D01*
Y421451D01*
X1131390D01*
Y421651D01*
G37*
G36*
G01X1133990D02*
X1134040Y422401D01*
X1134440D01*
X1134490Y421651D01*
Y421451D01*
X1133990D01*
Y421651D01*
G37*
G36*
G01X1138390Y421251D02*
X1138340Y420501D01*
X1137940D01*
X1137890Y421251D01*
Y421451D01*
X1138390D01*
Y421251D01*
G37*
G36*
G01X1140990D02*
X1140940Y420501D01*
X1140540D01*
X1140490Y421251D01*
Y421451D01*
X1140990D01*
Y421251D01*
G37*
G36*
G01X1143590D02*
X1143540Y420501D01*
X1143140D01*
X1143090Y421251D01*
Y421451D01*
X1143590D01*
Y421251D01*
G37*
G36*
G01X1146190D02*
X1146140Y420501D01*
X1145740D01*
X1145690Y421251D01*
Y421451D01*
X1146190D01*
Y421251D01*
G37*
G36*
G01X1153990D02*
X1153940Y420501D01*
X1153540D01*
X1153490Y421251D01*
Y421451D01*
X1153990D01*
Y421251D01*
G37*
G36*
G01X1151390D02*
X1151340Y420501D01*
X1150940D01*
X1150890Y421251D01*
Y421451D01*
X1151390D01*
Y421251D01*
G37*
G36*
G01X1148790D02*
X1148740Y420501D01*
X1148340D01*
X1148290Y421251D01*
Y421451D01*
X1148790D01*
Y421251D01*
G37*
G36*
G01X1156590D02*
X1156540Y420501D01*
X1156140D01*
X1156090Y421251D01*
Y421451D01*
X1156590D01*
Y421251D01*
G37*
G36*
G01X1136590Y421651D02*
X1136640Y422401D01*
X1137040D01*
X1137090Y421651D01*
Y421451D01*
X1136590D01*
Y421651D01*
G37*
G36*
G01X1139190D02*
X1139240Y422401D01*
X1139640D01*
X1139690Y421651D01*
Y421451D01*
X1139190D01*
Y421651D01*
G37*
G36*
G01X1141790D02*
X1141840Y422401D01*
X1142240D01*
X1142290Y421651D01*
Y421451D01*
X1141790D01*
Y421651D01*
G37*
G36*
G01X1144390D02*
X1144440Y422401D01*
X1144840D01*
X1144890Y421651D01*
Y421451D01*
X1144390D01*
Y421651D01*
G37*
G36*
G01X1154790D02*
X1154840Y422401D01*
X1155240D01*
X1155290Y421651D01*
Y421451D01*
X1154790D01*
Y421651D01*
G37*
G36*
G01X1152190D02*
X1152240Y422401D01*
X1152640D01*
X1152690Y421651D01*
Y421451D01*
X1152190D01*
Y421651D01*
G37*
G36*
G01X1149590D02*
X1149640Y422401D01*
X1150040D01*
X1150090Y421651D01*
Y421451D01*
X1149590D01*
Y421651D01*
G37*
G36*
G01X1146990D02*
X1147040Y422401D01*
X1147440D01*
X1147490Y421651D01*
Y421451D01*
X1146990D01*
Y421651D01*
G37*
G36*
G01X1106305Y415908D02*
X1107065Y415558D01*
Y414658D01*
X1106305Y414308D01*
X1106130D01*
Y415908D01*
X1106305D01*
G37*
G36*
G01Y412008D02*
X1107065Y411658D01*
Y410758D01*
X1106305Y410408D01*
X1106130D01*
Y412008D01*
X1106305D01*
G37*
G36*
G01X1106330Y420376D02*
X1105580Y420426D01*
Y420826D01*
X1106330Y420876D01*
X1106530D01*
Y420376D01*
X1106330D01*
G37*
G36*
G01Y417776D02*
X1105580Y417826D01*
Y418226D01*
X1106330Y418276D01*
X1106530D01*
Y417776D01*
X1106330D01*
G37*
G36*
G01X1106730Y419576D02*
X1107480Y419526D01*
Y419126D01*
X1106730Y419076D01*
X1106530D01*
Y419576D01*
X1106730D01*
G37*
G36*
G01X1106330Y425576D02*
X1105580Y425626D01*
Y426026D01*
X1106330Y426076D01*
X1106530D01*
Y425576D01*
X1106330D01*
G37*
G36*
G01Y422976D02*
X1105580Y423026D01*
Y423426D01*
X1106330Y423476D01*
X1106530D01*
Y422976D01*
X1106330D01*
G37*
G36*
G01X1106730Y424776D02*
X1107480Y424726D01*
Y424326D01*
X1106730Y424276D01*
X1106530D01*
Y424776D01*
X1106730D01*
G37*
G36*
G01Y422176D02*
X1107480Y422126D01*
Y421726D01*
X1106730Y421676D01*
X1106530D01*
Y422176D01*
X1106730D01*
G37*
G36*
G01X1117640Y438559D02*
X1118135Y437993D01*
X1117853Y437710D01*
X1117287Y438205D01*
X1117145Y438346D01*
X1117499Y438700D01*
X1117640Y438559D01*
G37*
G36*
G01X1119479Y440397D02*
X1119974Y439831D01*
X1119691Y439549D01*
X1119125Y440043D01*
X1118984Y440185D01*
X1119337Y440538D01*
X1119479Y440397D01*
G37*
G36*
G01X1121317Y442236D02*
X1121812Y441670D01*
X1121530Y441387D01*
X1120964Y441882D01*
X1120822Y442023D01*
X1121176Y442377D01*
X1121317Y442236D01*
G37*
G36*
G01X1115802Y436720D02*
X1116297Y436154D01*
X1116014Y435872D01*
X1115448Y436367D01*
X1115307Y436508D01*
X1115661Y436862D01*
X1115802Y436720D01*
G37*
G36*
G01X1113963Y434882D02*
X1114458Y434316D01*
X1114176Y434033D01*
X1113610Y434528D01*
X1113468Y434669D01*
X1113822Y435023D01*
X1113963Y434882D01*
G37*
G36*
G01X1112125Y433043D02*
X1112620Y432477D01*
X1112337Y432195D01*
X1111771Y432690D01*
X1111630Y432831D01*
X1111984Y433185D01*
X1112125Y433043D01*
G37*
G36*
G01X1110287Y431205D02*
X1110781Y430639D01*
X1110499Y430356D01*
X1109933Y430851D01*
X1109792Y430993D01*
X1110145Y431346D01*
X1110287Y431205D01*
G37*
G36*
G01X1108448Y429366D02*
X1108943Y428800D01*
X1108660Y428518D01*
X1108094Y429013D01*
X1107953Y429154D01*
X1108307Y429508D01*
X1108448Y429366D01*
G37*
G36*
G01X1116085Y437569D02*
X1115590Y438134D01*
X1115873Y438417D01*
X1116438Y437922D01*
X1116580Y437781D01*
X1116226Y437427D01*
X1116085Y437569D01*
G37*
G36*
G01X1117923Y439407D02*
X1117428Y439973D01*
X1117711Y440256D01*
X1118277Y439761D01*
X1118418Y439619D01*
X1118065Y439266D01*
X1117923Y439407D01*
G37*
G36*
G01X1119762Y441246D02*
X1119267Y441811D01*
X1119550Y442094D01*
X1120115Y441599D01*
X1120257Y441458D01*
X1119903Y441104D01*
X1119762Y441246D01*
G37*
G36*
G01X1121600Y443084D02*
X1121105Y443650D01*
X1121388Y443933D01*
X1121954Y443438D01*
X1122095Y443296D01*
X1121742Y442943D01*
X1121600Y443084D01*
G37*
G36*
G01X1114246Y435730D02*
X1113751Y436296D01*
X1114034Y436579D01*
X1114600Y436084D01*
X1114741Y435942D01*
X1114388Y435589D01*
X1114246Y435730D01*
G37*
G36*
G01X1112408Y433892D02*
X1111913Y434457D01*
X1112196Y434740D01*
X1112761Y434245D01*
X1112903Y434104D01*
X1112549Y433750D01*
X1112408Y433892D01*
G37*
G36*
G01X1110569Y432053D02*
X1110074Y432619D01*
X1110357Y432902D01*
X1110923Y432407D01*
X1111064Y432265D01*
X1110711Y431912D01*
X1110569Y432053D01*
G37*
G36*
G01X1108731Y430215D02*
X1108236Y430780D01*
X1108519Y431063D01*
X1109084Y430568D01*
X1109226Y430427D01*
X1108872Y430073D01*
X1108731Y430215D01*
G37*
G36*
G01X1106892Y428376D02*
X1106397Y428942D01*
X1106680Y429225D01*
X1107246Y428730D01*
X1107387Y428588D01*
X1107034Y428235D01*
X1106892Y428376D01*
G37*
G36*
G01X1133190Y416601D02*
X1133140Y415851D01*
X1132740D01*
X1132690Y416601D01*
Y416801D01*
X1133190D01*
Y416601D01*
G37*
G36*
G01X1135790D02*
X1135740Y415851D01*
X1135340D01*
X1135290Y416601D01*
Y416801D01*
X1135790D01*
Y416601D01*
G37*
G36*
G01X1133990Y417001D02*
X1134040Y417751D01*
X1134440D01*
X1134490Y417001D01*
Y416801D01*
X1133990D01*
Y417001D01*
G37*
G36*
G01X1129054Y414095D02*
X1129549Y413529D01*
X1129267Y413246D01*
X1128701Y413741D01*
X1128559Y413882D01*
X1128913Y414236D01*
X1129054Y414095D01*
G37*
G36*
G01X1129337Y414943D02*
X1128842Y415509D01*
X1129125Y415792D01*
X1129691Y415297D01*
X1129832Y415155D01*
X1129479Y414802D01*
X1129337Y414943D01*
G37*
G36*
G01X1130893Y415933D02*
X1131388Y415367D01*
X1131105Y415085D01*
X1130539Y415580D01*
X1130398Y415721D01*
X1130751Y416074D01*
X1130893Y415933D01*
G37*
G36*
G01X1138390Y416601D02*
X1138340Y415851D01*
X1137940D01*
X1137890Y416601D01*
Y416801D01*
X1138390D01*
Y416601D01*
G37*
G36*
G01X1140990D02*
X1140940Y415851D01*
X1140540D01*
X1140490Y416601D01*
Y416801D01*
X1140990D01*
Y416601D01*
G37*
G36*
G01X1143590D02*
X1143540Y415851D01*
X1143140D01*
X1143090Y416601D01*
Y416801D01*
X1143590D01*
Y416601D01*
G37*
G36*
G01X1146190D02*
X1146140Y415851D01*
X1145740D01*
X1145690Y416601D01*
Y416801D01*
X1146190D01*
Y416601D01*
G37*
G36*
G01X1148790D02*
X1148740Y415851D01*
X1148340D01*
X1148290Y416601D01*
Y416801D01*
X1148790D01*
Y416601D01*
G37*
G36*
G01X1153990D02*
X1153940Y415851D01*
X1153540D01*
X1153490Y416601D01*
Y416801D01*
X1153990D01*
Y416601D01*
G37*
G36*
G01X1151390D02*
X1151340Y415851D01*
X1150940D01*
X1150890Y416601D01*
Y416801D01*
X1151390D01*
Y416601D01*
G37*
G36*
G01X1136590Y417001D02*
X1136640Y417751D01*
X1137040D01*
X1137090Y417001D01*
Y416801D01*
X1136590D01*
Y417001D01*
G37*
G36*
G01X1139190D02*
X1139240Y417751D01*
X1139640D01*
X1139690Y417001D01*
Y416801D01*
X1139190D01*
Y417001D01*
G37*
G36*
G01X1141790D02*
X1141840Y417751D01*
X1142240D01*
X1142290Y417001D01*
Y416801D01*
X1141790D01*
Y417001D01*
G37*
G36*
G01X1144390D02*
X1144440Y417751D01*
X1144840D01*
X1144890Y417001D01*
Y416801D01*
X1144390D01*
Y417001D01*
G37*
G36*
G01X1146990D02*
X1147040Y417751D01*
X1147440D01*
X1147490Y417001D01*
Y416801D01*
X1146990D01*
Y417001D01*
G37*
G36*
G01X1154790D02*
X1154840Y417751D01*
X1155240D01*
X1155290Y417001D01*
Y416801D01*
X1154790D01*
Y417001D01*
G37*
G36*
G01X1152190D02*
X1152240Y417751D01*
X1152640D01*
X1152690Y417001D01*
Y416801D01*
X1152190D01*
Y417001D01*
G37*
G36*
G01X1149590D02*
X1149640Y417751D01*
X1150040D01*
X1150090Y417001D01*
Y416801D01*
X1149590D01*
Y417001D01*
G37*
G36*
G01X1156590Y416601D02*
X1156540Y415851D01*
X1156140D01*
X1156090Y416601D01*
Y416801D01*
X1156590D01*
Y416601D01*
G37*
G36*
G01X1102605Y554354D02*
Y547127D01*
X1101816Y546338D01*
X1096210D01*
X1095553Y546995D01*
X1095646Y547132D01*
G03X1095395Y548991I-1158J790D01*
G01Y554733D01*
X1095904Y555242D01*
Y556352D01*
X1096210Y556657D01*
X1099303D01*
G02X1099698Y556194I0J-400D01*
G03X1101990Y554691I1483J-237D01*
G02X1102605Y554354I215J-337D01*
G37*
G36*
G01Y592154D02*
Y584927D01*
X1101816Y584138D01*
X1096210D01*
X1095553Y584795D01*
X1095646Y584932D01*
G03X1095395Y586791I-1158J790D01*
G01Y592421D01*
X1095905Y592931D01*
Y594151D01*
X1095964Y594210D01*
X1096210Y594457D01*
X1099303D01*
G02X1099698Y593994I0J-400D01*
G03X1101990Y592491I1483J-237D01*
G02X1102605Y592154I215J-337D01*
G37*
G36*
G01X1161137Y174485D02*
X1161703Y174980D01*
X1161986Y174698D01*
X1161491Y174132D01*
X1161350Y173990D01*
X1160996Y174344D01*
X1161137Y174485D01*
G37*
G36*
G01X1159299Y176324D02*
X1159865Y176819D01*
X1160147Y176536D01*
X1159653Y175970D01*
X1159511Y175829D01*
X1159158Y176182D01*
X1159299Y176324D01*
G37*
G36*
G01X1160289Y174768D02*
X1159723Y174273D01*
X1159440Y174556D01*
X1159935Y175122D01*
X1160077Y175263D01*
X1160430Y174910D01*
X1160289Y174768D01*
G37*
G36*
G01X1158450Y176607D02*
X1157885Y176112D01*
X1157602Y176395D01*
X1158097Y176960D01*
X1158238Y177102D01*
X1158592Y176748D01*
X1158450Y176607D01*
G37*
G36*
G01X1162976Y172647D02*
X1163542Y173142D01*
X1163824Y172859D01*
X1163329Y172293D01*
X1163188Y172152D01*
X1162834Y172506D01*
X1162976Y172647D01*
G37*
G36*
G01X1164814Y170808D02*
X1165380Y171303D01*
X1165663Y171021D01*
X1165168Y170455D01*
X1165027Y170313D01*
X1164673Y170667D01*
X1164814Y170808D01*
G37*
G36*
G01X1163966Y171091D02*
X1163400Y170596D01*
X1163117Y170879D01*
X1163612Y171445D01*
X1163754Y171586D01*
X1164107Y171233D01*
X1163966Y171091D01*
G37*
G36*
G01X1162127Y172930D02*
X1161562Y172435D01*
X1161279Y172718D01*
X1161774Y173283D01*
X1161915Y173425D01*
X1162269Y173071D01*
X1162127Y172930D01*
G37*
G36*
G01X1157243Y179256D02*
X1157193Y178506D01*
X1156793D01*
X1156743Y179256D01*
Y179456D01*
X1157243D01*
Y179256D01*
G37*
G36*
G01X1162234Y175582D02*
X1162800Y176077D01*
X1163082Y175794D01*
X1162587Y175228D01*
X1162446Y175087D01*
X1162093Y175440D01*
X1162234Y175582D01*
G37*
G36*
G01X1160395Y177420D02*
X1160961Y177915D01*
X1161244Y177633D01*
X1160749Y177067D01*
X1160608Y176925D01*
X1160254Y177279D01*
X1160395Y177420D01*
G37*
G36*
G01X1158557Y179259D02*
X1159123Y179754D01*
X1159406Y179471D01*
X1158911Y178905D01*
X1158769Y178764D01*
X1158416Y179117D01*
X1158557Y179259D01*
G37*
G36*
G01X1163224Y174026D02*
X1162658Y173531D01*
X1162375Y173814D01*
X1162870Y174380D01*
X1163012Y174521D01*
X1163365Y174168D01*
X1163224Y174026D01*
G37*
G36*
G01X1161385Y175865D02*
X1160820Y175370D01*
X1160537Y175653D01*
X1161032Y176218D01*
X1161173Y176360D01*
X1161527Y176006D01*
X1161385Y175865D01*
G37*
G36*
G01X1159547Y177703D02*
X1158981Y177208D01*
X1158698Y177491D01*
X1159193Y178057D01*
X1159335Y178198D01*
X1159688Y177845D01*
X1159547Y177703D01*
G37*
G36*
G01X1165911Y171905D02*
X1166477Y172400D01*
X1166759Y172117D01*
X1166264Y171551D01*
X1166123Y171410D01*
X1165769Y171764D01*
X1165911Y171905D01*
G37*
G36*
G01X1167749Y170066D02*
X1168315Y170561D01*
X1168598Y170279D01*
X1168103Y169713D01*
X1167961Y169572D01*
X1167608Y169925D01*
X1167749Y170066D01*
G37*
G36*
G01X1165062Y172188D02*
X1164497Y171693D01*
X1164214Y171976D01*
X1164709Y172541D01*
X1164850Y172683D01*
X1165204Y172329D01*
X1165062Y172188D01*
G37*
G36*
G01X1164072Y173743D02*
X1164638Y174238D01*
X1164921Y173956D01*
X1164426Y173390D01*
X1164285Y173248D01*
X1163931Y173602D01*
X1164072Y173743D01*
G37*
G36*
G01X1157243Y190106D02*
X1157193Y189356D01*
X1156793D01*
X1156743Y190106D01*
Y190306D01*
X1157243D01*
Y190106D01*
G37*
G36*
G01X1159843D02*
X1159793Y189356D01*
X1159393D01*
X1159343Y190106D01*
Y190306D01*
X1159843D01*
Y190106D01*
G37*
G36*
G01X1158043Y190506D02*
X1158093Y191256D01*
X1158493D01*
X1158543Y190506D01*
Y190306D01*
X1158043D01*
Y190506D01*
G37*
G36*
G01X1160643D02*
X1160693Y191256D01*
X1161093D01*
X1161143Y190506D01*
Y190306D01*
X1160643D01*
Y190506D01*
G37*
G36*
G01X1166232Y186934D02*
X1166798Y187429D01*
X1167081Y187147D01*
X1166586Y186581D01*
X1166445Y186439D01*
X1166091Y186793D01*
X1166232Y186934D01*
G37*
G36*
G01X1164394Y188773D02*
X1164960Y189268D01*
X1165243Y188985D01*
X1164748Y188419D01*
X1164606Y188278D01*
X1164253Y188631D01*
X1164394Y188773D01*
G37*
G36*
G01X1165384Y187217D02*
X1164818Y186722D01*
X1164535Y187005D01*
X1165030Y187571D01*
X1165172Y187712D01*
X1165525Y187359D01*
X1165384Y187217D01*
G37*
G36*
G01X1163545Y189056D02*
X1162980Y188561D01*
X1162697Y188844D01*
X1163192Y189409D01*
X1163333Y189551D01*
X1163687Y189197D01*
X1163545Y189056D01*
G37*
G36*
G01X1175425Y177742D02*
X1175991Y178237D01*
X1176273Y177954D01*
X1175778Y177388D01*
X1175637Y177247D01*
X1175283Y177601D01*
X1175425Y177742D01*
G37*
G36*
G01X1177263Y175904D02*
X1177829Y176398D01*
X1178112Y176116D01*
X1177617Y175550D01*
X1177475Y175409D01*
X1177122Y175762D01*
X1177263Y175904D01*
G37*
G36*
G01X1179102Y174065D02*
X1179668Y174560D01*
X1179950Y174277D01*
X1179455Y173711D01*
X1179314Y173570D01*
X1178960Y173924D01*
X1179102Y174065D01*
G37*
G36*
G01X1173586Y179580D02*
X1174152Y180075D01*
X1174435Y179793D01*
X1173940Y179227D01*
X1173799Y179085D01*
X1173445Y179439D01*
X1173586Y179580D01*
G37*
G36*
G01X1171748Y181419D02*
X1172314Y181914D01*
X1172596Y181631D01*
X1172101Y181065D01*
X1171960Y180924D01*
X1171606Y181278D01*
X1171748Y181419D01*
G37*
G36*
G01X1169909Y183257D02*
X1170475Y183752D01*
X1170758Y183470D01*
X1170263Y182904D01*
X1170122Y182762D01*
X1169768Y183116D01*
X1169909Y183257D01*
G37*
G36*
G01X1168071Y185096D02*
X1168637Y185591D01*
X1168919Y185308D01*
X1168425Y184742D01*
X1168283Y184601D01*
X1167930Y184954D01*
X1168071Y185096D01*
G37*
G36*
G01X1174576Y178025D02*
X1174011Y177530D01*
X1173728Y177813D01*
X1174223Y178378D01*
X1174364Y178520D01*
X1174718Y178166D01*
X1174576Y178025D01*
G37*
G36*
G01X1176415Y176186D02*
X1175849Y175691D01*
X1175566Y175974D01*
X1176061Y176540D01*
X1176203Y176681D01*
X1176556Y176328D01*
X1176415Y176186D01*
G37*
G36*
G01X1178253Y174348D02*
X1177688Y173853D01*
X1177405Y174136D01*
X1177900Y174701D01*
X1178041Y174843D01*
X1178395Y174489D01*
X1178253Y174348D01*
G37*
G36*
G01X1172738Y179863D02*
X1172172Y179368D01*
X1171889Y179651D01*
X1172384Y180217D01*
X1172526Y180358D01*
X1172879Y180005D01*
X1172738Y179863D01*
G37*
G36*
G01X1170899Y181702D02*
X1170334Y181207D01*
X1170051Y181490D01*
X1170546Y182055D01*
X1170687Y182197D01*
X1171041Y181843D01*
X1170899Y181702D01*
G37*
G36*
G01X1169061Y183540D02*
X1168495Y183045D01*
X1168212Y183328D01*
X1168707Y183894D01*
X1168849Y184035D01*
X1169202Y183682D01*
X1169061Y183540D01*
G37*
G36*
G01X1167222Y185379D02*
X1166657Y184884D01*
X1166374Y185167D01*
X1166869Y185732D01*
X1167010Y185874D01*
X1167364Y185520D01*
X1167222Y185379D01*
G37*
G36*
G01X1157243Y191656D02*
X1157193Y190906D01*
X1156793D01*
X1156743Y191656D01*
Y191856D01*
X1157243D01*
Y191656D01*
G37*
G36*
G01X1158043Y192056D02*
X1158093Y192806D01*
X1158493D01*
X1158543Y192056D01*
Y191856D01*
X1158043D01*
Y192056D01*
G37*
G36*
G01X1160643D02*
X1160693Y192806D01*
X1161093D01*
X1161143Y192056D01*
Y191856D01*
X1160643D01*
Y192056D01*
G37*
G36*
G01X1159843Y191656D02*
X1159793Y190906D01*
X1159393D01*
X1159343Y191656D01*
Y191856D01*
X1159843D01*
Y191656D01*
G37*
G36*
G01X1165490Y189869D02*
X1166056Y190364D01*
X1166339Y190081D01*
X1165844Y189516D01*
X1165703Y189374D01*
X1165349Y189728D01*
X1165490Y189869D01*
G37*
G36*
G01X1163652Y191708D02*
X1164218Y192203D01*
X1164501Y191920D01*
X1164006Y191354D01*
X1163864Y191213D01*
X1163511Y191566D01*
X1163652Y191708D01*
G37*
G36*
G01X1166480Y188314D02*
X1165915Y187819D01*
X1165632Y188102D01*
X1166127Y188667D01*
X1166268Y188809D01*
X1166622Y188455D01*
X1166480Y188314D01*
G37*
G36*
G01X1164642Y190152D02*
X1164076Y189657D01*
X1163793Y189940D01*
X1164288Y190506D01*
X1164430Y190647D01*
X1164783Y190294D01*
X1164642Y190152D01*
G37*
G36*
G01X1172844Y182515D02*
X1173410Y183010D01*
X1173693Y182728D01*
X1173198Y182162D01*
X1173057Y182020D01*
X1172703Y182374D01*
X1172844Y182515D01*
G37*
G36*
G01X1171006Y184354D02*
X1171572Y184849D01*
X1171854Y184566D01*
X1171359Y184000D01*
X1171218Y183859D01*
X1170865Y184212D01*
X1171006Y184354D01*
G37*
G36*
G01X1169167Y186192D02*
X1169733Y186687D01*
X1170016Y186405D01*
X1169521Y185839D01*
X1169380Y185697D01*
X1169026Y186051D01*
X1169167Y186192D01*
G37*
G36*
G01X1174683Y180677D02*
X1175249Y181172D01*
X1175531Y180889D01*
X1175036Y180323D01*
X1174895Y180182D01*
X1174541Y180536D01*
X1174683Y180677D01*
G37*
G36*
G01X1176521Y178838D02*
X1177087Y179333D01*
X1177370Y179051D01*
X1176875Y178485D01*
X1176733Y178344D01*
X1176380Y178697D01*
X1176521Y178838D01*
G37*
G36*
G01X1178360Y177000D02*
X1178926Y177495D01*
X1179208Y177212D01*
X1178713Y176646D01*
X1178572Y176505D01*
X1178218Y176859D01*
X1178360Y177000D01*
G37*
G36*
G01X1180198Y175162D02*
X1180764Y175657D01*
X1181047Y175374D01*
X1180552Y174808D01*
X1180410Y174667D01*
X1180057Y175020D01*
X1180198Y175162D01*
G37*
G36*
G01X1171996Y182798D02*
X1171430Y182303D01*
X1171147Y182586D01*
X1171642Y183152D01*
X1171784Y183293D01*
X1172137Y182940D01*
X1171996Y182798D01*
G37*
G36*
G01X1170157Y184637D02*
X1169592Y184142D01*
X1169309Y184425D01*
X1169804Y184990D01*
X1169945Y185132D01*
X1170299Y184778D01*
X1170157Y184637D01*
G37*
G36*
G01X1168319Y186475D02*
X1167753Y185980D01*
X1167470Y186263D01*
X1167965Y186829D01*
X1168107Y186970D01*
X1168460Y186617D01*
X1168319Y186475D01*
G37*
G36*
G01X1173834Y180960D02*
X1173269Y180465D01*
X1172986Y180748D01*
X1173481Y181313D01*
X1173622Y181455D01*
X1173976Y181101D01*
X1173834Y180960D01*
G37*
G36*
G01X1175673Y179121D02*
X1175107Y178626D01*
X1174824Y178909D01*
X1175319Y179475D01*
X1175461Y179616D01*
X1175814Y179263D01*
X1175673Y179121D01*
G37*
G36*
G01X1177511Y177283D02*
X1176946Y176788D01*
X1176663Y177071D01*
X1177158Y177636D01*
X1177299Y177778D01*
X1177653Y177424D01*
X1177511Y177283D01*
G37*
G36*
G01X1179350Y175444D02*
X1178784Y174949D01*
X1178501Y175232D01*
X1178996Y175798D01*
X1179138Y175939D01*
X1179491Y175586D01*
X1179350Y175444D01*
G37*
G36*
G01X1167329Y188031D02*
X1167895Y188526D01*
X1168178Y188243D01*
X1167683Y187677D01*
X1167541Y187536D01*
X1167188Y187889D01*
X1167329Y188031D01*
G37*
G36*
G01X1157106Y174131D02*
X1157672Y174626D01*
X1157954Y174343D01*
X1157460Y173777D01*
X1157318Y173636D01*
X1156965Y173989D01*
X1157106Y174131D01*
G37*
G36*
G01X1158096Y172575D02*
X1157530Y172080D01*
X1157247Y172363D01*
X1157742Y172929D01*
X1157884Y173070D01*
X1158237Y172717D01*
X1158096Y172575D01*
G37*
G36*
G01X1159934Y170737D02*
X1159369Y170242D01*
X1159086Y170525D01*
X1159581Y171090D01*
X1159722Y171232D01*
X1160076Y170878D01*
X1159934Y170737D01*
G37*
G36*
G01X1158944Y172292D02*
X1159510Y172787D01*
X1159793Y172505D01*
X1159298Y171939D01*
X1159157Y171797D01*
X1158803Y172151D01*
X1158944Y172292D01*
G37*
G36*
G01X1158202Y175227D02*
X1158768Y175722D01*
X1159051Y175440D01*
X1158556Y174874D01*
X1158415Y174732D01*
X1158061Y175086D01*
X1158202Y175227D01*
G37*
G36*
G01X1160041Y173389D02*
X1160607Y173884D01*
X1160889Y173601D01*
X1160394Y173035D01*
X1160253Y172894D01*
X1159900Y173247D01*
X1160041Y173389D01*
G37*
G36*
G01X1159192Y173672D02*
X1158627Y173177D01*
X1158344Y173460D01*
X1158839Y174025D01*
X1158980Y174167D01*
X1159334Y173813D01*
X1159192Y173672D01*
G37*
G36*
G01X1161879Y171550D02*
X1162445Y172045D01*
X1162728Y171763D01*
X1162233Y171197D01*
X1162092Y171055D01*
X1161738Y171409D01*
X1161879Y171550D01*
G37*
G36*
G01X1161031Y171833D02*
X1160465Y171338D01*
X1160182Y171621D01*
X1160677Y172187D01*
X1160819Y172328D01*
X1161172Y171975D01*
X1161031Y171833D01*
G37*
G36*
G01X1157243Y187006D02*
X1157193Y186256D01*
X1156793D01*
X1156743Y187006D01*
Y187206D01*
X1157243D01*
Y187006D01*
G37*
G36*
G01X1159843D02*
X1159793Y186256D01*
X1159393D01*
X1159343Y187006D01*
Y187206D01*
X1159843D01*
Y187006D01*
G37*
G36*
G01X1158043Y187406D02*
X1158093Y188156D01*
X1158493D01*
X1158543Y187406D01*
Y187206D01*
X1158043D01*
Y187406D01*
G37*
G36*
G01X1162201Y186580D02*
X1162767Y187075D01*
X1163050Y186792D01*
X1162555Y186226D01*
X1162413Y186085D01*
X1162060Y186438D01*
X1162201Y186580D01*
G37*
G36*
G01X1163191Y185024D02*
X1162625Y184529D01*
X1162342Y184812D01*
X1162837Y185378D01*
X1162979Y185519D01*
X1163332Y185166D01*
X1163191Y185024D01*
G37*
G36*
G01X1164039Y184741D02*
X1164605Y185236D01*
X1164888Y184954D01*
X1164393Y184388D01*
X1164252Y184246D01*
X1163898Y184600D01*
X1164039Y184741D01*
G37*
G36*
G01X1176909Y171872D02*
X1177475Y172367D01*
X1177757Y172084D01*
X1177262Y171518D01*
X1177121Y171377D01*
X1176767Y171731D01*
X1176909Y171872D01*
G37*
G36*
G01X1176060Y172155D02*
X1175495Y171660D01*
X1175212Y171943D01*
X1175707Y172508D01*
X1175848Y172650D01*
X1176202Y172296D01*
X1176060Y172155D01*
G37*
G36*
G01X1169555Y179226D02*
X1170121Y179721D01*
X1170403Y179438D01*
X1169908Y178872D01*
X1169767Y178731D01*
X1169413Y179085D01*
X1169555Y179226D01*
G37*
G36*
G01X1167716Y181064D02*
X1168282Y181559D01*
X1168565Y181277D01*
X1168070Y180711D01*
X1167929Y180569D01*
X1167575Y180923D01*
X1167716Y181064D01*
G37*
G36*
G01X1165878Y182903D02*
X1166444Y183398D01*
X1166726Y183115D01*
X1166232Y182549D01*
X1166090Y182408D01*
X1165737Y182761D01*
X1165878Y182903D01*
G37*
G36*
G01X1171393Y177387D02*
X1171959Y177882D01*
X1172242Y177600D01*
X1171747Y177034D01*
X1171606Y176892D01*
X1171252Y177246D01*
X1171393Y177387D01*
G37*
G36*
G01X1173232Y175549D02*
X1173798Y176044D01*
X1174080Y175761D01*
X1173585Y175195D01*
X1173444Y175054D01*
X1173090Y175408D01*
X1173232Y175549D01*
G37*
G36*
G01X1175070Y173711D02*
X1175636Y174205D01*
X1175919Y173923D01*
X1175424Y173357D01*
X1175282Y173216D01*
X1174929Y173569D01*
X1175070Y173711D01*
G37*
G36*
G01X1168706Y179509D02*
X1168141Y179014D01*
X1167858Y179297D01*
X1168353Y179862D01*
X1168494Y180004D01*
X1168848Y179650D01*
X1168706Y179509D01*
G37*
G36*
G01X1166868Y181347D02*
X1166302Y180852D01*
X1166019Y181135D01*
X1166514Y181701D01*
X1166656Y181842D01*
X1167009Y181489D01*
X1166868Y181347D01*
G37*
G36*
G01X1165029Y183186D02*
X1164464Y182691D01*
X1164181Y182974D01*
X1164676Y183539D01*
X1164817Y183681D01*
X1165171Y183327D01*
X1165029Y183186D01*
G37*
G36*
G01X1170545Y177670D02*
X1169979Y177175D01*
X1169696Y177458D01*
X1170191Y178024D01*
X1170333Y178165D01*
X1170686Y177812D01*
X1170545Y177670D01*
G37*
G36*
G01X1172383Y175832D02*
X1171818Y175337D01*
X1171535Y175620D01*
X1172030Y176185D01*
X1172171Y176327D01*
X1172525Y175973D01*
X1172383Y175832D01*
G37*
G36*
G01X1174222Y173993D02*
X1173656Y173498D01*
X1173373Y173781D01*
X1173868Y174347D01*
X1174010Y174488D01*
X1174363Y174135D01*
X1174222Y173993D01*
G37*
G36*
G01X1157243Y188556D02*
X1157193Y187806D01*
X1156793D01*
X1156743Y188556D01*
Y188756D01*
X1157243D01*
Y188556D01*
G37*
G36*
G01X1159843D02*
X1159793Y187806D01*
X1159393D01*
X1159343Y188556D01*
Y188756D01*
X1159843D01*
Y188556D01*
G37*
G36*
G01X1158043Y188956D02*
X1158093Y189706D01*
X1158493D01*
X1158543Y188956D01*
Y188756D01*
X1158043D01*
Y188956D01*
G37*
G36*
G01X1162449Y187959D02*
X1161883Y187464D01*
X1161600Y187747D01*
X1162095Y188313D01*
X1162237Y188454D01*
X1162590Y188101D01*
X1162449Y187959D01*
G37*
G36*
G01X1165136Y185838D02*
X1165702Y186333D01*
X1165985Y186050D01*
X1165490Y185484D01*
X1165348Y185343D01*
X1164995Y185696D01*
X1165136Y185838D01*
G37*
G36*
G01X1163297Y187676D02*
X1163863Y188171D01*
X1164146Y187888D01*
X1163651Y187323D01*
X1163510Y187181D01*
X1163156Y187535D01*
X1163297Y187676D01*
G37*
G36*
G01X1166126Y184282D02*
X1165560Y183787D01*
X1165277Y184070D01*
X1165772Y184636D01*
X1165914Y184777D01*
X1166267Y184424D01*
X1166126Y184282D01*
G37*
G36*
G01X1164287Y186121D02*
X1163722Y185626D01*
X1163439Y185909D01*
X1163934Y186474D01*
X1164075Y186616D01*
X1164429Y186262D01*
X1164287Y186121D01*
G37*
G36*
G01X1178005Y172969D02*
X1178571Y173464D01*
X1178854Y173181D01*
X1178359Y172615D01*
X1178217Y172474D01*
X1177864Y172827D01*
X1178005Y172969D01*
G37*
G36*
G01X1177157Y173251D02*
X1176591Y172756D01*
X1176308Y173039D01*
X1176803Y173605D01*
X1176945Y173746D01*
X1177298Y173393D01*
X1177157Y173251D01*
G37*
G36*
G01X1170651Y180322D02*
X1171217Y180817D01*
X1171500Y180535D01*
X1171005Y179969D01*
X1170864Y179827D01*
X1170510Y180181D01*
X1170651Y180322D01*
G37*
G36*
G01X1168813Y182161D02*
X1169379Y182656D01*
X1169661Y182373D01*
X1169166Y181807D01*
X1169025Y181666D01*
X1168672Y182019D01*
X1168813Y182161D01*
G37*
G36*
G01X1166974Y183999D02*
X1167540Y184494D01*
X1167823Y184212D01*
X1167328Y183646D01*
X1167187Y183504D01*
X1166833Y183858D01*
X1166974Y183999D01*
G37*
G36*
G01X1172490Y178484D02*
X1173056Y178979D01*
X1173338Y178696D01*
X1172843Y178130D01*
X1172702Y177989D01*
X1172348Y178343D01*
X1172490Y178484D01*
G37*
G36*
G01X1174328Y176645D02*
X1174894Y177140D01*
X1175177Y176858D01*
X1174682Y176292D01*
X1174540Y176151D01*
X1174187Y176504D01*
X1174328Y176645D01*
G37*
G36*
G01X1176167Y174807D02*
X1176733Y175302D01*
X1177015Y175019D01*
X1176520Y174453D01*
X1176379Y174312D01*
X1176025Y174666D01*
X1176167Y174807D01*
G37*
G36*
G01X1169803Y180605D02*
X1169237Y180110D01*
X1168954Y180393D01*
X1169449Y180959D01*
X1169591Y181100D01*
X1169944Y180747D01*
X1169803Y180605D01*
G37*
G36*
G01X1167964Y182444D02*
X1167399Y181949D01*
X1167116Y182232D01*
X1167611Y182797D01*
X1167752Y182939D01*
X1168106Y182585D01*
X1167964Y182444D01*
G37*
G36*
G01X1171641Y178767D02*
X1171076Y178272D01*
X1170793Y178555D01*
X1171288Y179120D01*
X1171429Y179262D01*
X1171783Y178908D01*
X1171641Y178767D01*
G37*
G36*
G01X1173480Y176928D02*
X1172914Y176433D01*
X1172631Y176716D01*
X1173126Y177282D01*
X1173268Y177423D01*
X1173621Y177070D01*
X1173480Y176928D01*
G37*
G36*
G01X1175318Y175090D02*
X1174753Y174595D01*
X1174470Y174878D01*
X1174965Y175443D01*
X1175106Y175585D01*
X1175460Y175231D01*
X1175318Y175090D01*
G37*
G36*
G01X1157243Y182356D02*
X1157193Y181606D01*
X1156793D01*
X1156743Y182356D01*
Y182556D01*
X1157243D01*
Y182356D01*
G37*
G36*
G01X1158043Y182756D02*
X1158093Y183506D01*
X1158493D01*
X1158543Y182756D01*
Y182556D01*
X1158043D01*
Y182756D01*
G37*
G36*
G01X1162588Y179613D02*
X1163154Y180108D01*
X1163437Y179826D01*
X1162942Y179260D01*
X1162801Y179118D01*
X1162447Y179472D01*
X1162588Y179613D01*
G37*
G36*
G01X1160750Y181452D02*
X1161316Y181947D01*
X1161599Y181664D01*
X1161104Y181098D01*
X1160962Y180957D01*
X1160609Y181310D01*
X1160750Y181452D01*
G37*
G36*
G01X1161740Y179896D02*
X1161174Y179401D01*
X1160891Y179684D01*
X1161386Y180250D01*
X1161528Y180391D01*
X1161881Y180038D01*
X1161740Y179896D01*
G37*
G36*
G01X1159901Y181735D02*
X1159336Y181240D01*
X1159053Y181523D01*
X1159548Y182088D01*
X1159689Y182230D01*
X1160043Y181876D01*
X1159901Y181735D01*
G37*
G36*
G01X1169942Y172259D02*
X1170508Y172754D01*
X1170791Y172472D01*
X1170296Y171906D01*
X1170154Y171765D01*
X1169801Y172118D01*
X1169942Y172259D01*
G37*
G36*
G01X1169094Y172542D02*
X1168528Y172047D01*
X1168245Y172330D01*
X1168740Y172896D01*
X1168882Y173037D01*
X1169235Y172684D01*
X1169094Y172542D01*
G37*
G36*
G01X1170932Y170704D02*
X1170367Y170209D01*
X1170084Y170492D01*
X1170579Y171057D01*
X1170720Y171199D01*
X1171074Y170845D01*
X1170932Y170704D01*
G37*
G36*
G01X1168104Y174098D02*
X1168670Y174593D01*
X1168952Y174310D01*
X1168457Y173744D01*
X1168316Y173603D01*
X1167962Y173957D01*
X1168104Y174098D01*
G37*
G36*
G01X1166265Y175936D02*
X1166831Y176431D01*
X1167114Y176149D01*
X1166619Y175583D01*
X1166478Y175441D01*
X1166124Y175795D01*
X1166265Y175936D01*
G37*
G36*
G01X1164427Y177775D02*
X1164993Y178270D01*
X1165275Y177987D01*
X1164780Y177421D01*
X1164639Y177280D01*
X1164286Y177633D01*
X1164427Y177775D01*
G37*
G36*
G01X1167255Y174381D02*
X1166690Y173886D01*
X1166407Y174169D01*
X1166902Y174734D01*
X1167043Y174876D01*
X1167397Y174522D01*
X1167255Y174381D01*
G37*
G36*
G01X1165417Y176219D02*
X1164851Y175724D01*
X1164568Y176007D01*
X1165063Y176573D01*
X1165205Y176714D01*
X1165558Y176361D01*
X1165417Y176219D01*
G37*
G36*
G01X1163578Y178058D02*
X1163013Y177563D01*
X1162730Y177846D01*
X1163225Y178411D01*
X1163366Y178553D01*
X1163720Y178199D01*
X1163578Y178058D01*
G37*
G36*
G01X1157243Y183906D02*
X1157193Y183156D01*
X1156793D01*
X1156743Y183906D01*
Y184106D01*
X1157243D01*
Y183906D01*
G37*
G36*
G01X1158043Y184306D02*
X1158093Y185056D01*
X1158493D01*
X1158543Y184306D01*
Y184106D01*
X1158043D01*
Y184306D01*
G37*
G36*
G01X1161846Y182548D02*
X1162412Y183043D01*
X1162695Y182761D01*
X1162200Y182195D01*
X1162059Y182053D01*
X1161705Y182407D01*
X1161846Y182548D01*
G37*
G36*
G01X1162836Y180993D02*
X1162271Y180498D01*
X1161988Y180781D01*
X1162483Y181346D01*
X1162624Y181488D01*
X1162978Y181134D01*
X1162836Y180993D01*
G37*
G36*
G01X1160998Y182831D02*
X1160432Y182336D01*
X1160149Y182619D01*
X1160644Y183185D01*
X1160786Y183326D01*
X1161139Y182973D01*
X1160998Y182831D01*
G37*
G36*
G01X1171039Y173356D02*
X1171605Y173851D01*
X1171887Y173568D01*
X1171392Y173002D01*
X1171251Y172861D01*
X1170897Y173215D01*
X1171039Y173356D01*
G37*
G36*
G01X1172877Y171518D02*
X1173443Y172012D01*
X1173726Y171730D01*
X1173231Y171164D01*
X1173089Y171023D01*
X1172736Y171376D01*
X1172877Y171518D01*
G37*
G36*
G01X1172029Y171800D02*
X1171463Y171305D01*
X1171180Y171588D01*
X1171675Y172154D01*
X1171817Y172295D01*
X1172170Y171942D01*
X1172029Y171800D01*
G37*
G36*
G01X1174715Y169680D02*
X1175281Y170174D01*
X1175564Y169892D01*
X1175069Y169326D01*
X1174927Y169185D01*
X1174574Y169538D01*
X1174715Y169680D01*
G37*
G36*
G01X1173868Y169962D02*
X1173302Y169467D01*
X1173019Y169750D01*
X1173514Y170316D01*
X1173656Y170457D01*
X1174009Y170104D01*
X1173868Y169962D01*
G37*
G36*
G01X1169200Y175194D02*
X1169766Y175689D01*
X1170049Y175407D01*
X1169554Y174841D01*
X1169413Y174699D01*
X1169059Y175053D01*
X1169200Y175194D01*
G37*
G36*
G01X1165523Y178871D02*
X1166089Y179366D01*
X1166372Y179084D01*
X1165877Y178518D01*
X1165736Y178376D01*
X1165382Y178730D01*
X1165523Y178871D01*
G37*
G36*
G01X1163685Y180710D02*
X1164251Y181205D01*
X1164533Y180922D01*
X1164039Y180356D01*
X1163897Y180215D01*
X1163544Y180568D01*
X1163685Y180710D01*
G37*
G36*
G01X1170190Y173639D02*
X1169625Y173144D01*
X1169342Y173427D01*
X1169837Y173992D01*
X1169978Y174134D01*
X1170332Y173780D01*
X1170190Y173639D01*
G37*
G36*
G01X1168352Y175477D02*
X1167786Y174982D01*
X1167503Y175265D01*
X1167998Y175831D01*
X1168140Y175972D01*
X1168493Y175619D01*
X1168352Y175477D01*
G37*
G36*
G01X1166513Y177316D02*
X1165948Y176821D01*
X1165665Y177104D01*
X1166160Y177669D01*
X1166301Y177811D01*
X1166655Y177457D01*
X1166513Y177316D01*
G37*
G36*
G01X1164675Y179154D02*
X1164109Y178659D01*
X1163826Y178942D01*
X1164321Y179508D01*
X1164463Y179649D01*
X1164816Y179296D01*
X1164675Y179154D01*
G37*
G36*
G01X1167362Y177033D02*
X1167928Y177528D01*
X1168210Y177245D01*
X1167715Y176679D01*
X1167574Y176538D01*
X1167220Y176892D01*
X1167362Y177033D01*
G37*
G36*
G01X1157243Y180806D02*
X1157193Y180056D01*
X1156793D01*
X1156743Y180806D01*
Y181006D01*
X1157243D01*
Y180806D01*
G37*
G36*
G01X1161492Y178517D02*
X1162058Y179012D01*
X1162340Y178729D01*
X1161846Y178163D01*
X1161704Y178022D01*
X1161351Y178375D01*
X1161492Y178517D01*
G37*
G36*
G01X1159653Y180355D02*
X1160219Y180850D01*
X1160502Y180568D01*
X1160007Y180002D01*
X1159866Y179860D01*
X1159512Y180214D01*
X1159653Y180355D01*
G37*
G36*
G01X1162482Y176961D02*
X1161916Y176466D01*
X1161633Y176749D01*
X1162128Y177315D01*
X1162270Y177456D01*
X1162623Y177103D01*
X1162482Y176961D01*
G37*
G36*
G01X1160643Y178800D02*
X1160078Y178305D01*
X1159795Y178588D01*
X1160290Y179153D01*
X1160431Y179295D01*
X1160785Y178941D01*
X1160643Y178800D01*
G37*
G36*
G01X1158043Y181206D02*
X1158093Y181956D01*
X1158493D01*
X1158543Y181206D01*
Y181006D01*
X1158043D01*
Y181206D01*
G37*
G36*
G01X1167007Y173001D02*
X1167573Y173496D01*
X1167856Y173214D01*
X1167361Y172648D01*
X1167220Y172506D01*
X1166866Y172860D01*
X1167007Y173001D01*
G37*
G36*
G01X1168846Y171163D02*
X1169412Y171658D01*
X1169694Y171375D01*
X1169199Y170809D01*
X1169058Y170668D01*
X1168704Y171022D01*
X1168846Y171163D01*
G37*
G36*
G01X1166159Y173284D02*
X1165593Y172789D01*
X1165310Y173072D01*
X1165805Y173638D01*
X1165947Y173779D01*
X1166300Y173426D01*
X1166159Y173284D01*
G37*
G36*
G01X1167997Y171446D02*
X1167432Y170951D01*
X1167149Y171234D01*
X1167644Y171799D01*
X1167785Y171941D01*
X1168139Y171587D01*
X1167997Y171446D01*
G37*
G36*
G01X1169836Y169608D02*
X1169271Y169113D01*
X1168988Y169396D01*
X1169483Y169961D01*
X1169624Y170103D01*
X1169978Y169749D01*
X1169836Y169608D01*
G37*
G36*
G01X1165169Y174840D02*
X1165735Y175335D01*
X1166017Y175052D01*
X1165522Y174486D01*
X1165381Y174345D01*
X1165027Y174699D01*
X1165169Y174840D01*
G37*
G36*
G01X1163330Y176678D02*
X1163896Y177173D01*
X1164179Y176891D01*
X1163684Y176325D01*
X1163543Y176183D01*
X1163189Y176537D01*
X1163330Y176678D01*
G37*
G36*
G01X1164320Y175123D02*
X1163755Y174628D01*
X1163472Y174911D01*
X1163967Y175476D01*
X1164108Y175618D01*
X1164462Y175264D01*
X1164320Y175123D01*
G37*
G36*
G01X1157243Y185456D02*
X1157193Y184706D01*
X1156793D01*
X1156743Y185456D01*
Y185656D01*
X1157243D01*
Y185456D01*
G37*
G36*
G01X1159843D02*
X1159793Y184706D01*
X1159393D01*
X1159343Y185456D01*
Y185656D01*
X1159843D01*
Y185456D01*
G37*
G36*
G01X1158043Y185856D02*
X1158093Y186606D01*
X1158493D01*
X1158543Y185856D01*
Y185656D01*
X1158043D01*
Y185856D01*
G37*
G36*
G01X1161104Y185483D02*
X1161670Y185978D01*
X1161953Y185695D01*
X1161458Y185130D01*
X1161317Y184988D01*
X1160963Y185342D01*
X1161104Y185483D01*
G37*
G36*
G01X1162094Y183928D02*
X1161529Y183433D01*
X1161246Y183716D01*
X1161741Y184281D01*
X1161882Y184423D01*
X1162236Y184069D01*
X1162094Y183928D01*
G37*
G36*
G01X1173974Y172614D02*
X1174540Y173109D01*
X1174822Y172826D01*
X1174327Y172260D01*
X1174186Y172119D01*
X1173832Y172473D01*
X1173974Y172614D01*
G37*
G36*
G01X1173125Y172897D02*
X1172560Y172402D01*
X1172277Y172685D01*
X1172772Y173250D01*
X1172913Y173392D01*
X1173267Y173038D01*
X1173125Y172897D01*
G37*
G36*
G01X1174964Y171058D02*
X1174398Y170563D01*
X1174115Y170846D01*
X1174610Y171412D01*
X1174752Y171553D01*
X1175105Y171200D01*
X1174964Y171058D01*
G37*
G36*
G01X1170297Y176291D02*
X1170863Y176786D01*
X1171145Y176503D01*
X1170650Y175937D01*
X1170509Y175796D01*
X1170155Y176150D01*
X1170297Y176291D01*
G37*
G36*
G01X1172135Y174452D02*
X1172701Y174947D01*
X1172984Y174665D01*
X1172489Y174099D01*
X1172347Y173958D01*
X1171994Y174311D01*
X1172135Y174452D01*
G37*
G36*
G01X1168458Y178129D02*
X1169024Y178624D01*
X1169307Y178342D01*
X1168812Y177776D01*
X1168671Y177634D01*
X1168317Y177988D01*
X1168458Y178129D01*
G37*
G36*
G01X1166620Y179968D02*
X1167186Y180463D01*
X1167468Y180180D01*
X1166973Y179614D01*
X1166832Y179473D01*
X1166479Y179826D01*
X1166620Y179968D01*
G37*
G36*
G01X1164781Y181806D02*
X1165347Y182301D01*
X1165630Y182019D01*
X1165135Y181453D01*
X1164994Y181311D01*
X1164640Y181665D01*
X1164781Y181806D01*
G37*
G36*
G01X1162943Y183645D02*
X1163509Y184140D01*
X1163792Y183857D01*
X1163297Y183291D01*
X1163155Y183150D01*
X1162802Y183503D01*
X1162943Y183645D01*
G37*
G36*
G01X1171287Y174735D02*
X1170721Y174240D01*
X1170438Y174523D01*
X1170933Y175089D01*
X1171075Y175230D01*
X1171428Y174877D01*
X1171287Y174735D01*
G37*
G36*
G01X1169448Y176574D02*
X1168883Y176079D01*
X1168600Y176362D01*
X1169095Y176927D01*
X1169236Y177069D01*
X1169590Y176715D01*
X1169448Y176574D01*
G37*
G36*
G01X1165771Y180251D02*
X1165206Y179756D01*
X1164923Y180039D01*
X1165418Y180604D01*
X1165559Y180746D01*
X1165913Y180392D01*
X1165771Y180251D01*
G37*
G36*
G01X1163933Y182089D02*
X1163367Y181594D01*
X1163084Y181877D01*
X1163579Y182443D01*
X1163721Y182584D01*
X1164074Y182231D01*
X1163933Y182089D01*
G37*
G36*
G01X1167610Y178412D02*
X1167044Y177917D01*
X1166761Y178200D01*
X1167256Y178766D01*
X1167398Y178907D01*
X1167751Y178554D01*
X1167610Y178412D01*
G37*
G36*
G01X1188247Y203442D02*
G03X1188979Y202902I1122J754D01*
G01X1189028Y202887D01*
X1189318Y202597D01*
Y201625D01*
X1188689Y200996D01*
X1172503D01*
X1171597Y201902D01*
Y202514D01*
X1171614Y202525D01*
X1171615Y202595D01*
X1171617Y202635D01*
X1171622Y202663D01*
X1171624Y202669D01*
G03X1171625Y202681I-71J12D01*
G01Y202682D01*
G02X1171665Y202833I883J-153D01*
G02X1171757Y203020I890J-322D01*
G02X1171917Y203199I841J-590D01*
G02X1172092Y203311I542J-654D01*
G02X1172337Y203388I436J-959D01*
G02X1172469Y203397I179J-1653D01*
G02X1172651Y203377I23J-631D01*
G02X1172885Y203285I-236J-945D01*
G03X1172985Y203216I564J711D01*
G02X1173091Y203118I-2100J-2378D01*
G02X1173143Y203055I-740J-664D01*
G02X1173243Y202885I-562J-445D01*
G01X1173264Y202828D01*
G02X1173306Y202651I-660J-250D01*
G02X1173313Y202546I-879J-111D01*
G02X1173371Y202547I37J-438D01*
G03X1173462Y202546I57J1067D01*
G01X1173510D01*
X1173523Y202549D01*
G03X1173549Y202555I-27J178D01*
G01X1173592Y202571D01*
X1173598Y202575D01*
X1173602Y202577D01*
X1173608Y202582D01*
X1173618Y202589D01*
G03X1173622Y202592I-8J15D01*
G03X1173643Y202614I-115J131D01*
G03X1173653Y202625I-62J66D01*
G03X1173674Y202657I-88J80D01*
G01X1173675Y202658D01*
X1173685Y202680D01*
G03X1173688Y202695I-175J43D01*
G03X1173694Y202713I-158J63D01*
G01X1173697Y202750D01*
G03X1172574Y203796I-1233J-198D01*
G02X1172326Y204477I35J398D01*
G01X1172941Y205092D01*
X1174196D01*
X1174229Y205080D01*
G03X1175921Y205633I490J1367D01*
G01X1178150D01*
G03X1179206Y205095I1080J814D01*
G01X1179250Y205094D01*
X1179255Y205092D01*
X1179790D01*
X1181218Y203664D01*
X1181543D01*
G03X1182310Y203177I1066J832D01*
G01X1182366Y203165D01*
X1182409Y203122D01*
X1184388D01*
X1184418Y203113D01*
G03X1184604Y203067I441J1383D01*
G02X1184768Y202847I-35J-197D01*
G03X1184750Y202758I1215J-292D01*
G03X1184779Y202646I187J-11D01*
G03X1184797Y202619I255J150D01*
G03X1184902Y202553I152J126D01*
G03X1184969Y202546I61J258D01*
G01X1185098D01*
G03X1185135I19J180D01*
G01X1185136Y202595D01*
X1185138Y202635D01*
X1185143Y202664D01*
G03X1185146Y202682I-70J21D01*
G02X1185186Y202833I882J-153D01*
G02X1185278Y203020I889J-321D01*
G02X1185377Y203140I839J-591D01*
G03X1185773Y203368I-517J1356D01*
G02X1185856Y203387I276J-1015D01*
G02X1185989Y203396I179J-1652D01*
G02X1186170Y203376I22J-630D01*
G02X1186405Y203284I-234J-944D01*
G03X1186505Y203215I565J712D01*
G02X1186610Y203117I-2111J-2367D01*
G02X1186661Y203054I-745J-656D01*
G02X1186762Y202885I-558J-448D01*
G01X1186783Y202828D01*
G02X1186825Y202651I-659J-250D01*
G02X1186832Y202545I-878J-111D01*
G02X1186890Y202546I37J-437D01*
G03X1186986I48J1068D01*
G01X1187030D01*
Y202545D01*
X1187043Y202548D01*
G03X1187069Y202554I-28J179D01*
G01X1187088Y202561D01*
X1187096Y202563D01*
X1187097D01*
Y202564D01*
X1187099D01*
X1187103Y202566D01*
X1187104D01*
X1187108Y202569D01*
G03X1187115Y202572I-1J12D01*
G01X1187122Y202576D01*
X1187123D01*
G02X1187134Y202586I318J-338D01*
G03X1187142Y202591I-6J18D01*
G03X1187164Y202613I-113J135D01*
G03X1187174Y202624I-63J67D01*
G03X1187195Y202657I-90J80D01*
G02X1187202Y202673I168J-64D01*
G03X1187208Y202694I-170J60D01*
G03X1187213Y202707I-157J68D01*
G02X1187214Y202710I126J-40D01*
G01Y202716D01*
G02X1187215Y202723I136J-16D01*
G01X1187218Y202750D01*
G03X1187169Y202948I-1234J-200D01*
G02X1187558Y203442I389J94D01*
G01X1188247D01*
G37*
G36*
G01X1162946Y426785D02*
X1162451Y427350D01*
X1162734Y427633D01*
X1163299Y427138D01*
X1163441Y426997D01*
X1163087Y426643D01*
X1162946Y426785D01*
G37*
G36*
G01X1162663Y425936D02*
X1163158Y425370D01*
X1162875Y425088D01*
X1162309Y425583D01*
X1162168Y425724D01*
X1162522Y426078D01*
X1162663Y425936D01*
G37*
G36*
G01X1159190Y424351D02*
X1159140Y423601D01*
X1158740D01*
X1158690Y424351D01*
Y424551D01*
X1159190D01*
Y424351D01*
G37*
G36*
G01X1159990Y424751D02*
X1160040Y425501D01*
X1160440D01*
X1160490Y424751D01*
Y424551D01*
X1159990D01*
Y424751D01*
G37*
G36*
G01X1157390D02*
X1157440Y425501D01*
X1157840D01*
X1157890Y424751D01*
Y424551D01*
X1157390D01*
Y424751D01*
G37*
G36*
G01X1164784Y428623D02*
X1164289Y429189D01*
X1164572Y429472D01*
X1165138Y428977D01*
X1165279Y428835D01*
X1164926Y428482D01*
X1164784Y428623D01*
G37*
G36*
G01X1166340Y429613D02*
X1166835Y429047D01*
X1166552Y428765D01*
X1165986Y429260D01*
X1165845Y429401D01*
X1166198Y429754D01*
X1166340Y429613D01*
G37*
G36*
G01X1164501Y427775D02*
X1164996Y427209D01*
X1164714Y426926D01*
X1164148Y427421D01*
X1164006Y427562D01*
X1164360Y427916D01*
X1164501Y427775D01*
G37*
G36*
G01X1166623Y430462D02*
X1166128Y431027D01*
X1166411Y431310D01*
X1166976Y430815D01*
X1167118Y430674D01*
X1166764Y430320D01*
X1166623Y430462D01*
G37*
G36*
G01X1168178Y431452D02*
X1168673Y430886D01*
X1168391Y430603D01*
X1167825Y431098D01*
X1167683Y431239D01*
X1168037Y431593D01*
X1168178Y431452D01*
G37*
G36*
G01X1168461Y432300D02*
X1167966Y432866D01*
X1168249Y433149D01*
X1168815Y432654D01*
X1168956Y432512D01*
X1168603Y432159D01*
X1168461Y432300D01*
G37*
G36*
G01X1159190Y422801D02*
X1159140Y422051D01*
X1158740D01*
X1158690Y422801D01*
Y423001D01*
X1159190D01*
Y422801D01*
G37*
G36*
G01X1162204Y423850D02*
X1161709Y424415D01*
X1161992Y424698D01*
X1162557Y424203D01*
X1162699Y424062D01*
X1162345Y423708D01*
X1162204Y423850D01*
G37*
G36*
G01X1163759Y424840D02*
X1164254Y424274D01*
X1163972Y423991D01*
X1163406Y424486D01*
X1163264Y424627D01*
X1163618Y424981D01*
X1163759Y424840D01*
G37*
G36*
G01X1159990Y423201D02*
X1160040Y423951D01*
X1160440D01*
X1160490Y423201D01*
Y423001D01*
X1159990D01*
Y423201D01*
G37*
G36*
G01X1157390D02*
X1157440Y423951D01*
X1157840D01*
X1157890Y423201D01*
Y423001D01*
X1157390D01*
Y423201D01*
G37*
G36*
G01X1167719Y429365D02*
X1167224Y429931D01*
X1167507Y430214D01*
X1168073Y429719D01*
X1168214Y429577D01*
X1167861Y429224D01*
X1167719Y429365D01*
G37*
G36*
G01X1165881Y427527D02*
X1165386Y428092D01*
X1165669Y428375D01*
X1166234Y427880D01*
X1166376Y427739D01*
X1166022Y427385D01*
X1165881Y427527D01*
G37*
G36*
G01X1164042Y425688D02*
X1163547Y426254D01*
X1163830Y426537D01*
X1164396Y426042D01*
X1164537Y425900D01*
X1164184Y425547D01*
X1164042Y425688D01*
G37*
G36*
G01X1167436Y428517D02*
X1167931Y427951D01*
X1167649Y427668D01*
X1167083Y428163D01*
X1166941Y428304D01*
X1167295Y428658D01*
X1167436Y428517D01*
G37*
G36*
G01X1165598Y426678D02*
X1166093Y426112D01*
X1165810Y425830D01*
X1165244Y426325D01*
X1165103Y426466D01*
X1165457Y426820D01*
X1165598Y426678D01*
G37*
G36*
G01X1169558Y431204D02*
X1169063Y431769D01*
X1169346Y432052D01*
X1169911Y431557D01*
X1170053Y431416D01*
X1169699Y431062D01*
X1169558Y431204D01*
G37*
G36*
G01X1171113Y432194D02*
X1171608Y431628D01*
X1171326Y431345D01*
X1170760Y431840D01*
X1170618Y431981D01*
X1170972Y432335D01*
X1171113Y432194D01*
G37*
G36*
G01X1169275Y430355D02*
X1169770Y429789D01*
X1169487Y429507D01*
X1168921Y430001D01*
X1168780Y430143D01*
X1169133Y430496D01*
X1169275Y430355D01*
G37*
G36*
G01X1164390Y411951D02*
X1164340Y411201D01*
X1163940D01*
X1163890Y411951D01*
Y412151D01*
X1164390D01*
Y411951D01*
G37*
G36*
G01X1161790D02*
X1161740Y411201D01*
X1161340D01*
X1161290Y411951D01*
Y412151D01*
X1161790D01*
Y411951D01*
G37*
G36*
G01X1159190D02*
X1159140Y411201D01*
X1158740D01*
X1158690Y411951D01*
Y412151D01*
X1159190D01*
Y411951D01*
G37*
G36*
G01X1165190Y412351D02*
X1165240Y413101D01*
X1165640D01*
X1165690Y412351D01*
Y412151D01*
X1165190D01*
Y412351D01*
G37*
G36*
G01X1162590D02*
X1162640Y413101D01*
X1163040D01*
X1163090Y412351D01*
Y412151D01*
X1162590D01*
Y412351D01*
G37*
G36*
G01X1159990D02*
X1160040Y413101D01*
X1160440D01*
X1160490Y412351D01*
Y412151D01*
X1159990D01*
Y412351D01*
G37*
G36*
G01X1157390D02*
X1157440Y413101D01*
X1157840D01*
X1157890Y412351D01*
Y412151D01*
X1157390D01*
Y412351D01*
G37*
G36*
G01X1168042Y414335D02*
X1167547Y414900D01*
X1167830Y415183D01*
X1168395Y414688D01*
X1168537Y414547D01*
X1168183Y414193D01*
X1168042Y414335D01*
G37*
G36*
G01X1167759Y413486D02*
X1168254Y412920D01*
X1167971Y412638D01*
X1167405Y413133D01*
X1167264Y413274D01*
X1167618Y413628D01*
X1167759Y413486D01*
G37*
G36*
G01X1169597Y415325D02*
X1170092Y414759D01*
X1169810Y414476D01*
X1169244Y414971D01*
X1169103Y415113D01*
X1169456Y415466D01*
X1169597Y415325D01*
G37*
G36*
G01X1169880Y416173D02*
X1169385Y416739D01*
X1169668Y417022D01*
X1170234Y416527D01*
X1170375Y416385D01*
X1170022Y416032D01*
X1169880Y416173D01*
G37*
G36*
G01X1171719Y418012D02*
X1171224Y418577D01*
X1171507Y418860D01*
X1172072Y418365D01*
X1172214Y418224D01*
X1171860Y417870D01*
X1171719Y418012D01*
G37*
G36*
G01X1173557Y419850D02*
X1173062Y420416D01*
X1173345Y420699D01*
X1173911Y420204D01*
X1174052Y420062D01*
X1173699Y419709D01*
X1173557Y419850D01*
G37*
G36*
G01X1171436Y417163D02*
X1171931Y416597D01*
X1171648Y416315D01*
X1171082Y416810D01*
X1170941Y416951D01*
X1171295Y417305D01*
X1171436Y417163D01*
G37*
G36*
G01X1173274Y419002D02*
X1173769Y418436D01*
X1173487Y418153D01*
X1172921Y418648D01*
X1172779Y418789D01*
X1173133Y419143D01*
X1173274Y419002D01*
G37*
G36*
G01X1175113Y420840D02*
X1175608Y420274D01*
X1175325Y419992D01*
X1174759Y420487D01*
X1174618Y420628D01*
X1174971Y420981D01*
X1175113Y420840D01*
G37*
G36*
G01X1177234Y423527D02*
X1176739Y424093D01*
X1177022Y424376D01*
X1177588Y423881D01*
X1177729Y423739D01*
X1177376Y423386D01*
X1177234Y423527D01*
G37*
G36*
G01X1175396Y421689D02*
X1174901Y422254D01*
X1175184Y422537D01*
X1175749Y422042D01*
X1175891Y421901D01*
X1175537Y421547D01*
X1175396Y421689D01*
G37*
G36*
G01X1176951Y422679D02*
X1177446Y422113D01*
X1177164Y421830D01*
X1176598Y422325D01*
X1176456Y422466D01*
X1176810Y422820D01*
X1176951Y422679D01*
G37*
G36*
G01X1167300Y411400D02*
X1166805Y411965D01*
X1167088Y412248D01*
X1167653Y411753D01*
X1167795Y411612D01*
X1167441Y411258D01*
X1167300Y411400D01*
G37*
G36*
G01X1169138Y413238D02*
X1168643Y413804D01*
X1168926Y414087D01*
X1169492Y413592D01*
X1169633Y413450D01*
X1169280Y413097D01*
X1169138Y413238D01*
G37*
G36*
G01X1170977Y415077D02*
X1170482Y415642D01*
X1170765Y415925D01*
X1171330Y415430D01*
X1171472Y415289D01*
X1171118Y414935D01*
X1170977Y415077D01*
G37*
G36*
G01X1168856Y412390D02*
X1169350Y411824D01*
X1169068Y411541D01*
X1168502Y412036D01*
X1168361Y412178D01*
X1168714Y412531D01*
X1168856Y412390D01*
G37*
G36*
G01X1170694Y414228D02*
X1171189Y413662D01*
X1170906Y413380D01*
X1170340Y413875D01*
X1170199Y414016D01*
X1170553Y414370D01*
X1170694Y414228D01*
G37*
G36*
G01X1165190Y410801D02*
X1165240Y411551D01*
X1165640D01*
X1165690Y410801D01*
Y410601D01*
X1165190D01*
Y410801D01*
G37*
G36*
G01X1162590D02*
X1162640Y411551D01*
X1163040D01*
X1163090Y410801D01*
Y410601D01*
X1162590D01*
Y410801D01*
G37*
G36*
G01X1159990D02*
X1160040Y411551D01*
X1160440D01*
X1160490Y410801D01*
Y410601D01*
X1159990D01*
Y410801D01*
G37*
G36*
G01X1164390Y410401D02*
X1164340Y409651D01*
X1163940D01*
X1163890Y410401D01*
Y410601D01*
X1164390D01*
Y410401D01*
G37*
G36*
G01X1161790D02*
X1161740Y409651D01*
X1161340D01*
X1161290Y410401D01*
Y410601D01*
X1161790D01*
Y410401D01*
G37*
G36*
G01X1159190D02*
X1159140Y409651D01*
X1158740D01*
X1158690Y410401D01*
Y410601D01*
X1159190D01*
Y410401D01*
G37*
G36*
G01X1157390Y410801D02*
X1157440Y411551D01*
X1157840D01*
X1157890Y410801D01*
Y410601D01*
X1157390D01*
Y410801D01*
G37*
G36*
G01X1172532Y416067D02*
X1173027Y415501D01*
X1172745Y415218D01*
X1172179Y415713D01*
X1172037Y415854D01*
X1172391Y416208D01*
X1172532Y416067D01*
G37*
G36*
G01X1176492Y420592D02*
X1175997Y421158D01*
X1176280Y421441D01*
X1176846Y420946D01*
X1176987Y420804D01*
X1176634Y420451D01*
X1176492Y420592D01*
G37*
G36*
G01X1174654Y418754D02*
X1174159Y419319D01*
X1174442Y419602D01*
X1175007Y419107D01*
X1175149Y418966D01*
X1174795Y418612D01*
X1174654Y418754D01*
G37*
G36*
G01X1172815Y416915D02*
X1172320Y417481D01*
X1172603Y417764D01*
X1173169Y417269D01*
X1173310Y417127D01*
X1172957Y416774D01*
X1172815Y416915D01*
G37*
G36*
G01X1176209Y419744D02*
X1176704Y419178D01*
X1176422Y418895D01*
X1175856Y419390D01*
X1175714Y419531D01*
X1176068Y419885D01*
X1176209Y419744D01*
G37*
G36*
G01X1174371Y417905D02*
X1174866Y417339D01*
X1174583Y417057D01*
X1174017Y417552D01*
X1173876Y417693D01*
X1174230Y418047D01*
X1174371Y417905D01*
G37*
G36*
G01X1178331Y422431D02*
X1177836Y422996D01*
X1178119Y423279D01*
X1178684Y422784D01*
X1178826Y422643D01*
X1178472Y422289D01*
X1178331Y422431D01*
G37*
G36*
G01X1178048Y421582D02*
X1178543Y421016D01*
X1178260Y420734D01*
X1177694Y421228D01*
X1177553Y421370D01*
X1177906Y421723D01*
X1178048Y421582D01*
G37*
G36*
G01X1160470Y428129D02*
X1160965Y427563D01*
X1160682Y427281D01*
X1160116Y427776D01*
X1159975Y427917D01*
X1160329Y428271D01*
X1160470Y428129D01*
G37*
G36*
G01X1159190Y427451D02*
X1159140Y426701D01*
X1158740D01*
X1158690Y427451D01*
Y427651D01*
X1159190D01*
Y427451D01*
G37*
G36*
G01X1157390Y427851D02*
X1157440Y428601D01*
X1157840D01*
X1157890Y427851D01*
Y427651D01*
X1157390D01*
Y427851D01*
G37*
G36*
G01X1162308Y429968D02*
X1162803Y429402D01*
X1162521Y429119D01*
X1161955Y429614D01*
X1161813Y429755D01*
X1162167Y430109D01*
X1162308Y429968D01*
G37*
G36*
G01X1160753Y428978D02*
X1160258Y429543D01*
X1160541Y429826D01*
X1161106Y429331D01*
X1161248Y429190D01*
X1160894Y428836D01*
X1160753Y428978D01*
G37*
G36*
G01X1164147Y431806D02*
X1164642Y431240D01*
X1164359Y430958D01*
X1163793Y431453D01*
X1163652Y431594D01*
X1164005Y431947D01*
X1164147Y431806D01*
G37*
G36*
G01X1162591Y430816D02*
X1162096Y431382D01*
X1162379Y431665D01*
X1162945Y431170D01*
X1163086Y431028D01*
X1162733Y430675D01*
X1162591Y430816D01*
G37*
G36*
G01X1164430Y432655D02*
X1163935Y433220D01*
X1164218Y433503D01*
X1164783Y433008D01*
X1164925Y432867D01*
X1164571Y432513D01*
X1164430Y432655D01*
G37*
G36*
G01X1161849Y427881D02*
X1161354Y428447D01*
X1161637Y428730D01*
X1162203Y428235D01*
X1162344Y428093D01*
X1161991Y427740D01*
X1161849Y427881D01*
G37*
G36*
G01X1161566Y427033D02*
X1162061Y426467D01*
X1161779Y426184D01*
X1161213Y426679D01*
X1161071Y426820D01*
X1161425Y427174D01*
X1161566Y427033D01*
G37*
G36*
G01X1163405Y428871D02*
X1163900Y428305D01*
X1163617Y428023D01*
X1163051Y428518D01*
X1162910Y428659D01*
X1163264Y429013D01*
X1163405Y428871D01*
G37*
G36*
G01X1159190Y425901D02*
X1159140Y425151D01*
X1158740D01*
X1158690Y425901D01*
Y426101D01*
X1159190D01*
Y425901D01*
G37*
G36*
G01X1157390Y426301D02*
X1157440Y427051D01*
X1157840D01*
X1157890Y426301D01*
Y426101D01*
X1157390D01*
Y426301D01*
G37*
G36*
G01X1165526Y431558D02*
X1165031Y432124D01*
X1165314Y432407D01*
X1165880Y431912D01*
X1166021Y431770D01*
X1165668Y431417D01*
X1165526Y431558D01*
G37*
G36*
G01X1163688Y429720D02*
X1163193Y430285D01*
X1163476Y430568D01*
X1164041Y430073D01*
X1164183Y429932D01*
X1163829Y429578D01*
X1163688Y429720D01*
G37*
G36*
G01X1165243Y430710D02*
X1165738Y430144D01*
X1165456Y429861D01*
X1164890Y430356D01*
X1164748Y430497D01*
X1165102Y430851D01*
X1165243Y430710D01*
G37*
G36*
G01X1167082Y432548D02*
X1167577Y431982D01*
X1167294Y431700D01*
X1166728Y432194D01*
X1166587Y432336D01*
X1166940Y432689D01*
X1167082Y432548D01*
G37*
G36*
G01X1165566Y415679D02*
X1166061Y415113D01*
X1165778Y414831D01*
X1165212Y415326D01*
X1165071Y415467D01*
X1165425Y415821D01*
X1165566Y415679D01*
G37*
G36*
G01X1164390Y415051D02*
X1164340Y414301D01*
X1163940D01*
X1163890Y415051D01*
Y415251D01*
X1164390D01*
Y415051D01*
G37*
G36*
G01X1161790D02*
X1161740Y414301D01*
X1161340D01*
X1161290Y415051D01*
Y415251D01*
X1161790D01*
Y415051D01*
G37*
G36*
G01X1159190D02*
X1159140Y414301D01*
X1158740D01*
X1158690Y415051D01*
Y415251D01*
X1159190D01*
Y415051D01*
G37*
G36*
G01X1162590Y415451D02*
X1162640Y416201D01*
X1163040D01*
X1163090Y415451D01*
Y415251D01*
X1162590D01*
Y415451D01*
G37*
G36*
G01X1159990D02*
X1160040Y416201D01*
X1160440D01*
X1160490Y415451D01*
Y415251D01*
X1159990D01*
Y415451D01*
G37*
G36*
G01X1157390D02*
X1157440Y416201D01*
X1157840D01*
X1157890Y415451D01*
Y415251D01*
X1157390D01*
Y415451D01*
G37*
G36*
G01X1165849Y416528D02*
X1165354Y417093D01*
X1165637Y417376D01*
X1166202Y416881D01*
X1166344Y416740D01*
X1165990Y416386D01*
X1165849Y416528D01*
G37*
G36*
G01X1169526Y420205D02*
X1169031Y420770D01*
X1169314Y421053D01*
X1169879Y420558D01*
X1170021Y420417D01*
X1169667Y420063D01*
X1169526Y420205D01*
G37*
G36*
G01X1167687Y418366D02*
X1167192Y418932D01*
X1167475Y419215D01*
X1168041Y418720D01*
X1168182Y418578D01*
X1167829Y418225D01*
X1167687Y418366D01*
G37*
G36*
G01X1171081Y421195D02*
X1171576Y420629D01*
X1171294Y420346D01*
X1170728Y420841D01*
X1170586Y420982D01*
X1170940Y421336D01*
X1171081Y421195D01*
G37*
G36*
G01X1167404Y417518D02*
X1167899Y416952D01*
X1167617Y416669D01*
X1167051Y417164D01*
X1166910Y417306D01*
X1167263Y417659D01*
X1167404Y417518D01*
G37*
G36*
G01X1169243Y419356D02*
X1169738Y418790D01*
X1169455Y418508D01*
X1168889Y419003D01*
X1168748Y419144D01*
X1169102Y419498D01*
X1169243Y419356D01*
G37*
G36*
G01X1175041Y425720D02*
X1174546Y426286D01*
X1174829Y426569D01*
X1175395Y426074D01*
X1175536Y425932D01*
X1175183Y425579D01*
X1175041Y425720D01*
G37*
G36*
G01X1173203Y423882D02*
X1172708Y424447D01*
X1172991Y424730D01*
X1173556Y424235D01*
X1173698Y424094D01*
X1173344Y423740D01*
X1173203Y423882D01*
G37*
G36*
G01X1171364Y422043D02*
X1170869Y422609D01*
X1171152Y422892D01*
X1171718Y422397D01*
X1171859Y422255D01*
X1171506Y421902D01*
X1171364Y422043D01*
G37*
G36*
G01X1176597Y426710D02*
X1177092Y426144D01*
X1176809Y425861D01*
X1176243Y426356D01*
X1176102Y426498D01*
X1176455Y426851D01*
X1176597Y426710D01*
G37*
G36*
G01X1174758Y424872D02*
X1175253Y424306D01*
X1174971Y424023D01*
X1174405Y424518D01*
X1174263Y424659D01*
X1174617Y425013D01*
X1174758Y424872D01*
G37*
G36*
G01X1172920Y423033D02*
X1173415Y422467D01*
X1173132Y422185D01*
X1172566Y422680D01*
X1172425Y422821D01*
X1172778Y423174D01*
X1172920Y423033D01*
G37*
G36*
G01X1164390Y413501D02*
X1164340Y412751D01*
X1163940D01*
X1163890Y413501D01*
Y413701D01*
X1164390D01*
Y413501D01*
G37*
G36*
G01X1161790D02*
X1161740Y412751D01*
X1161340D01*
X1161290Y413501D01*
Y413701D01*
X1161790D01*
Y413501D01*
G37*
G36*
G01X1159190D02*
X1159140Y412751D01*
X1158740D01*
X1158690Y413501D01*
Y413701D01*
X1159190D01*
Y413501D01*
G37*
G36*
G01X1162590Y413901D02*
X1162640Y414651D01*
X1163040D01*
X1163090Y413901D01*
Y413701D01*
X1162590D01*
Y413901D01*
G37*
G36*
G01X1159990D02*
X1160040Y414651D01*
X1160440D01*
X1160490Y413901D01*
Y413701D01*
X1159990D01*
Y413901D01*
G37*
G36*
G01X1157390D02*
X1157440Y414651D01*
X1157840D01*
X1157890Y413901D01*
Y413701D01*
X1157390D01*
Y413901D01*
G37*
G36*
G01X1166945Y415431D02*
X1166450Y415997D01*
X1166733Y416280D01*
X1167299Y415785D01*
X1167440Y415643D01*
X1167087Y415290D01*
X1166945Y415431D01*
G37*
G36*
G01X1166663Y414583D02*
X1167157Y414017D01*
X1166875Y413734D01*
X1166309Y414229D01*
X1166168Y414371D01*
X1166521Y414724D01*
X1166663Y414583D01*
G37*
G36*
G01X1168501Y416421D02*
X1168996Y415855D01*
X1168713Y415573D01*
X1168147Y416068D01*
X1168006Y416209D01*
X1168360Y416563D01*
X1168501Y416421D01*
G37*
G36*
G01X1170622Y419108D02*
X1170127Y419674D01*
X1170410Y419957D01*
X1170976Y419462D01*
X1171117Y419320D01*
X1170764Y418967D01*
X1170622Y419108D01*
G37*
G36*
G01X1168784Y417270D02*
X1168289Y417835D01*
X1168572Y418118D01*
X1169137Y417623D01*
X1169279Y417482D01*
X1168925Y417128D01*
X1168784Y417270D01*
G37*
G36*
G01X1170339Y418260D02*
X1170834Y417694D01*
X1170552Y417411D01*
X1169986Y417906D01*
X1169844Y418047D01*
X1170198Y418401D01*
X1170339Y418260D01*
G37*
G36*
G01X1172178Y420098D02*
X1172673Y419532D01*
X1172390Y419250D01*
X1171824Y419745D01*
X1171683Y419886D01*
X1172037Y420240D01*
X1172178Y420098D01*
G37*
G36*
G01X1176138Y424624D02*
X1175643Y425189D01*
X1175926Y425472D01*
X1176491Y424977D01*
X1176633Y424836D01*
X1176279Y424482D01*
X1176138Y424624D01*
G37*
G36*
G01X1174299Y422785D02*
X1173804Y423351D01*
X1174087Y423634D01*
X1174653Y423139D01*
X1174794Y422997D01*
X1174441Y422644D01*
X1174299Y422785D01*
G37*
G36*
G01X1172461Y420947D02*
X1171966Y421512D01*
X1172249Y421795D01*
X1172814Y421300D01*
X1172956Y421159D01*
X1172602Y420805D01*
X1172461Y420947D01*
G37*
G36*
G01X1175855Y423775D02*
X1176350Y423209D01*
X1176067Y422927D01*
X1175501Y423421D01*
X1175360Y423563D01*
X1175713Y423916D01*
X1175855Y423775D01*
G37*
G36*
G01X1174016Y421937D02*
X1174511Y421371D01*
X1174229Y421088D01*
X1173663Y421583D01*
X1173521Y421724D01*
X1173875Y422078D01*
X1174016Y421937D01*
G37*
G36*
G01X1177693Y425614D02*
X1178188Y425048D01*
X1177906Y424765D01*
X1177340Y425260D01*
X1177198Y425401D01*
X1177552Y425755D01*
X1177693Y425614D01*
G37*
G36*
G01X1164114Y420808D02*
X1164609Y420242D01*
X1164326Y419960D01*
X1163760Y420455D01*
X1163619Y420596D01*
X1163973Y420950D01*
X1164114Y420808D01*
G37*
G36*
G01X1161790Y419701D02*
X1161740Y418951D01*
X1161340D01*
X1161290Y419701D01*
Y419901D01*
X1161790D01*
Y419701D01*
G37*
G36*
G01X1159190D02*
X1159140Y418951D01*
X1158740D01*
X1158690Y419701D01*
Y419901D01*
X1159190D01*
Y419701D01*
G37*
G36*
G01X1159990Y420101D02*
X1160040Y420851D01*
X1160440D01*
X1160490Y420101D01*
Y419901D01*
X1159990D01*
Y420101D01*
G37*
G36*
G01X1157390D02*
X1157440Y420851D01*
X1157840D01*
X1157890Y420101D01*
Y419901D01*
X1157390D01*
Y420101D01*
G37*
G36*
G01X1164397Y421657D02*
X1163902Y422222D01*
X1164185Y422505D01*
X1164750Y422010D01*
X1164892Y421869D01*
X1164538Y421515D01*
X1164397Y421657D01*
G37*
G36*
G01X1165952Y422647D02*
X1166447Y422081D01*
X1166165Y421798D01*
X1165599Y422293D01*
X1165457Y422434D01*
X1165811Y422788D01*
X1165952Y422647D01*
G37*
G36*
G01X1166235Y423495D02*
X1165740Y424061D01*
X1166023Y424344D01*
X1166589Y423849D01*
X1166730Y423707D01*
X1166377Y423354D01*
X1166235Y423495D01*
G37*
G36*
G01X1168074Y425334D02*
X1167579Y425899D01*
X1167862Y426182D01*
X1168427Y425687D01*
X1168569Y425546D01*
X1168215Y425192D01*
X1168074Y425334D01*
G37*
G36*
G01X1169912Y427172D02*
X1169417Y427738D01*
X1169700Y428021D01*
X1170266Y427526D01*
X1170407Y427384D01*
X1170054Y427031D01*
X1169912Y427172D01*
G37*
G36*
G01X1167791Y424485D02*
X1168286Y423919D01*
X1168003Y423637D01*
X1167437Y424132D01*
X1167296Y424273D01*
X1167650Y424627D01*
X1167791Y424485D01*
G37*
G36*
G01X1169629Y426324D02*
X1170124Y425758D01*
X1169842Y425475D01*
X1169276Y425970D01*
X1169134Y426111D01*
X1169488Y426465D01*
X1169629Y426324D01*
G37*
G36*
G01X1173589Y430849D02*
X1173094Y431415D01*
X1173377Y431698D01*
X1173943Y431203D01*
X1174084Y431061D01*
X1173731Y430708D01*
X1173589Y430849D01*
G37*
G36*
G01X1171751Y429011D02*
X1171256Y429576D01*
X1171539Y429859D01*
X1172104Y429364D01*
X1172246Y429223D01*
X1171892Y428869D01*
X1171751Y429011D01*
G37*
G36*
G01X1173306Y430001D02*
X1173801Y429435D01*
X1173519Y429152D01*
X1172953Y429647D01*
X1172811Y429788D01*
X1173165Y430142D01*
X1173306Y430001D01*
G37*
G36*
G01X1171468Y428162D02*
X1171963Y427596D01*
X1171680Y427314D01*
X1171114Y427808D01*
X1170973Y427950D01*
X1171326Y428303D01*
X1171468Y428162D01*
G37*
G36*
G01X1165494Y420560D02*
X1164999Y421125D01*
X1165282Y421408D01*
X1165847Y420913D01*
X1165989Y420772D01*
X1165635Y420418D01*
X1165494Y420560D01*
G37*
G36*
G01X1165211Y419711D02*
X1165706Y419145D01*
X1165423Y418863D01*
X1164857Y419358D01*
X1164716Y419499D01*
X1165070Y419853D01*
X1165211Y419711D01*
G37*
G36*
G01X1161790Y418151D02*
X1161740Y417401D01*
X1161340D01*
X1161290Y418151D01*
Y418351D01*
X1161790D01*
Y418151D01*
G37*
G36*
G01X1159190D02*
X1159140Y417401D01*
X1158740D01*
X1158690Y418151D01*
Y418351D01*
X1159190D01*
Y418151D01*
G37*
G36*
G01X1162590Y418551D02*
X1162640Y419301D01*
X1163040D01*
X1163090Y418551D01*
Y418351D01*
X1162590D01*
Y418551D01*
G37*
G36*
G01X1159990D02*
X1160040Y419301D01*
X1160440D01*
X1160490Y418551D01*
Y418351D01*
X1159990D01*
Y418551D01*
G37*
G36*
G01X1157390D02*
X1157440Y419301D01*
X1157840D01*
X1157890Y418551D01*
Y418351D01*
X1157390D01*
Y418551D01*
G37*
G36*
G01X1167332Y422398D02*
X1166837Y422964D01*
X1167120Y423247D01*
X1167686Y422752D01*
X1167827Y422610D01*
X1167474Y422257D01*
X1167332Y422398D01*
G37*
G36*
G01X1169171Y424237D02*
X1168676Y424802D01*
X1168959Y425085D01*
X1169524Y424590D01*
X1169666Y424449D01*
X1169312Y424095D01*
X1169171Y424237D01*
G37*
G36*
G01X1171009Y426075D02*
X1170514Y426641D01*
X1170797Y426924D01*
X1171363Y426429D01*
X1171504Y426287D01*
X1171151Y425934D01*
X1171009Y426075D01*
G37*
G36*
G01X1167049Y421550D02*
X1167544Y420984D01*
X1167262Y420701D01*
X1166696Y421196D01*
X1166554Y421337D01*
X1166908Y421691D01*
X1167049Y421550D01*
G37*
G36*
G01X1168888Y423388D02*
X1169383Y422822D01*
X1169100Y422540D01*
X1168534Y423035D01*
X1168393Y423176D01*
X1168747Y423530D01*
X1168888Y423388D01*
G37*
G36*
G01X1170726Y425227D02*
X1171221Y424661D01*
X1170939Y424378D01*
X1170373Y424873D01*
X1170231Y425014D01*
X1170585Y425368D01*
X1170726Y425227D01*
G37*
G36*
G01X1174686Y429752D02*
X1174191Y430318D01*
X1174474Y430601D01*
X1175040Y430106D01*
X1175181Y429964D01*
X1174828Y429611D01*
X1174686Y429752D01*
G37*
G36*
G01X1172848Y427914D02*
X1172353Y428479D01*
X1172636Y428762D01*
X1173201Y428267D01*
X1173343Y428126D01*
X1172989Y427772D01*
X1172848Y427914D01*
G37*
G36*
G01X1174403Y428904D02*
X1174898Y428338D01*
X1174616Y428055D01*
X1174050Y428550D01*
X1173908Y428691D01*
X1174262Y429045D01*
X1174403Y428904D01*
G37*
G36*
G01X1172565Y427065D02*
X1173060Y426499D01*
X1172777Y426217D01*
X1172211Y426711D01*
X1172070Y426853D01*
X1172423Y427206D01*
X1172565Y427065D01*
G37*
G36*
G01X1161790Y421251D02*
X1161740Y420501D01*
X1161340D01*
X1161290Y421251D01*
Y421451D01*
X1161790D01*
Y421251D01*
G37*
G36*
G01X1159190D02*
X1159140Y420501D01*
X1158740D01*
X1158690Y421251D01*
Y421451D01*
X1159190D01*
Y421251D01*
G37*
G36*
G01X1163017Y421905D02*
X1163512Y421339D01*
X1163230Y421056D01*
X1162664Y421551D01*
X1162523Y421693D01*
X1162876Y422046D01*
X1163017Y421905D01*
G37*
G36*
G01X1159990Y421651D02*
X1160040Y422401D01*
X1160440D01*
X1160490Y421651D01*
Y421451D01*
X1159990D01*
Y421651D01*
G37*
G36*
G01X1157390D02*
X1157440Y422401D01*
X1157840D01*
X1157890Y421651D01*
Y421451D01*
X1157390D01*
Y421651D01*
G37*
G36*
G01X1163300Y422753D02*
X1162805Y423319D01*
X1163088Y423602D01*
X1163654Y423107D01*
X1163795Y422965D01*
X1163442Y422612D01*
X1163300Y422753D01*
G37*
G36*
G01X1165139Y424592D02*
X1164644Y425157D01*
X1164927Y425440D01*
X1165492Y424945D01*
X1165634Y424804D01*
X1165280Y424450D01*
X1165139Y424592D01*
G37*
G36*
G01X1166977Y426430D02*
X1166482Y426996D01*
X1166765Y427279D01*
X1167331Y426784D01*
X1167472Y426642D01*
X1167119Y426289D01*
X1166977Y426430D01*
G37*
G36*
G01X1168816Y428269D02*
X1168321Y428834D01*
X1168604Y429117D01*
X1169169Y428622D01*
X1169311Y428481D01*
X1168957Y428127D01*
X1168816Y428269D01*
G37*
G36*
G01X1164856Y423743D02*
X1165351Y423177D01*
X1165068Y422895D01*
X1164502Y423390D01*
X1164361Y423531D01*
X1164715Y423885D01*
X1164856Y423743D01*
G37*
G36*
G01X1166694Y425582D02*
X1167189Y425016D01*
X1166907Y424733D01*
X1166341Y425228D01*
X1166199Y425369D01*
X1166553Y425723D01*
X1166694Y425582D01*
G37*
G36*
G01X1168533Y427420D02*
X1169028Y426854D01*
X1168745Y426572D01*
X1168179Y427067D01*
X1168038Y427208D01*
X1168391Y427561D01*
X1168533Y427420D01*
G37*
G36*
G01X1170371Y429259D02*
X1170866Y428693D01*
X1170584Y428410D01*
X1170018Y428905D01*
X1169876Y429046D01*
X1170230Y429400D01*
X1170371Y429259D01*
G37*
G36*
G01X1170654Y430107D02*
X1170159Y430673D01*
X1170442Y430956D01*
X1171008Y430461D01*
X1171149Y430319D01*
X1170796Y429966D01*
X1170654Y430107D01*
G37*
G36*
G01X1172210Y431097D02*
X1172705Y430531D01*
X1172422Y430248D01*
X1171856Y430743D01*
X1171715Y430885D01*
X1172068Y431238D01*
X1172210Y431097D01*
G37*
G36*
G01X1172493Y431946D02*
X1171998Y432511D01*
X1172281Y432794D01*
X1172846Y432299D01*
X1172988Y432158D01*
X1172634Y431804D01*
X1172493Y431946D01*
G37*
G36*
G01X1164752Y417625D02*
X1164257Y418190D01*
X1164540Y418473D01*
X1165105Y417978D01*
X1165247Y417837D01*
X1164893Y417483D01*
X1164752Y417625D01*
G37*
G36*
G01X1166307Y418615D02*
X1166802Y418049D01*
X1166520Y417766D01*
X1165954Y418261D01*
X1165813Y418403D01*
X1166166Y418756D01*
X1166307Y418615D01*
G37*
G36*
G01X1161790Y416601D02*
X1161740Y415851D01*
X1161340D01*
X1161290Y416601D01*
Y416801D01*
X1161790D01*
Y416601D01*
G37*
G36*
G01X1159190D02*
X1159140Y415851D01*
X1158740D01*
X1158690Y416601D01*
Y416801D01*
X1159190D01*
Y416601D01*
G37*
G36*
G01X1162590Y417001D02*
X1162640Y417751D01*
X1163040D01*
X1163090Y417001D01*
Y416801D01*
X1162590D01*
Y417001D01*
G37*
G36*
G01X1159990D02*
X1160040Y417751D01*
X1160440D01*
X1160490Y417001D01*
Y416801D01*
X1159990D01*
Y417001D01*
G37*
G36*
G01X1157390D02*
X1157440Y417751D01*
X1157840D01*
X1157890Y417001D01*
Y416801D01*
X1157390D01*
Y417001D01*
G37*
G36*
G01X1166590Y419463D02*
X1166095Y420029D01*
X1166378Y420312D01*
X1166944Y419817D01*
X1167085Y419675D01*
X1166732Y419322D01*
X1166590Y419463D01*
G37*
G36*
G01X1168146Y420453D02*
X1168641Y419887D01*
X1168358Y419605D01*
X1167792Y420100D01*
X1167651Y420241D01*
X1168005Y420595D01*
X1168146Y420453D01*
G37*
G36*
G01X1168429Y421302D02*
X1167934Y421867D01*
X1168217Y422150D01*
X1168782Y421655D01*
X1168924Y421514D01*
X1168570Y421160D01*
X1168429Y421302D01*
G37*
G36*
G01X1170267Y423140D02*
X1169772Y423706D01*
X1170055Y423989D01*
X1170621Y423494D01*
X1170762Y423352D01*
X1170409Y422999D01*
X1170267Y423140D01*
G37*
G36*
G01X1169984Y422292D02*
X1170479Y421726D01*
X1170197Y421443D01*
X1169631Y421938D01*
X1169489Y422079D01*
X1169843Y422433D01*
X1169984Y422292D01*
G37*
G36*
G01X1175783Y428656D02*
X1175288Y429221D01*
X1175571Y429504D01*
X1176136Y429009D01*
X1176278Y428868D01*
X1175924Y428514D01*
X1175783Y428656D01*
G37*
G36*
G01X1173944Y426817D02*
X1173449Y427383D01*
X1173732Y427666D01*
X1174298Y427171D01*
X1174439Y427029D01*
X1174086Y426676D01*
X1173944Y426817D01*
G37*
G36*
G01X1172106Y424979D02*
X1171611Y425544D01*
X1171894Y425827D01*
X1172459Y425332D01*
X1172601Y425191D01*
X1172247Y424837D01*
X1172106Y424979D01*
G37*
G36*
G01X1175500Y427807D02*
X1175995Y427241D01*
X1175712Y426958D01*
X1175146Y427453D01*
X1175005Y427595D01*
X1175358Y427948D01*
X1175500Y427807D01*
G37*
G36*
G01X1173661Y425969D02*
X1174156Y425403D01*
X1173874Y425120D01*
X1173308Y425615D01*
X1173166Y425756D01*
X1173520Y426110D01*
X1173661Y425969D01*
G37*
G36*
G01X1171823Y424130D02*
X1172318Y423564D01*
X1172035Y423282D01*
X1171469Y423777D01*
X1171328Y423918D01*
X1171681Y424271D01*
X1171823Y424130D01*
G37*
G36*
G01X1218700Y494000D02*
X1216800Y495900D01*
Y510346D01*
X1217854Y511400D01*
X1224022D01*
G03X1225526I752J1300D01*
G01X1235900D01*
X1236400Y510900D01*
Y499300D01*
X1231100Y494000D01*
X1218700D01*
G37*
G36*
G01X1266723Y-14876D02*
X1266722Y-10240D01*
Y-9901D01*
G03X1263592I-1565J0D01*
G01Y-10240D01*
X1263595Y-14878D01*
G03X1263650Y-15291I1564J-2D01*
G01X1263658Y-15317D01*
Y-18500D01*
X1257212D01*
X1257000Y-18288D01*
Y-9500D01*
X1250500Y-3000D01*
Y9598D01*
X1252399Y11497D01*
Y14466D01*
X1251821Y15044D01*
X1247676D01*
X1247000Y15720D01*
Y17817D01*
X1247683Y18500D01*
X1249653D01*
X1250000Y18847D01*
Y44000D01*
X1250747Y44747D01*
Y47793D01*
X1252373Y49419D01*
Y52518D01*
X1251852Y53039D01*
X1247927D01*
X1247500Y53466D01*
Y55428D01*
X1248095Y56023D01*
X1253459D01*
G02X1253818Y55445I1J-400D01*
G03X1256129Y55841I1300J-646D01*
G01X1256128Y55843D01*
X1255985Y55985D01*
X1257000Y57000D01*
Y67000D01*
X1255500Y68500D01*
X1254000D01*
X1250500Y72000D01*
Y86000D01*
X1252387Y87887D01*
Y91284D01*
G03X1250378Y92189I-616J1315D01*
G02X1249994Y91676I-384J-113D01*
G01X1247671D01*
X1247500Y91847D01*
Y100500D01*
X1250352Y103352D01*
X1256658D01*
X1260206Y106900D01*
X1261224D01*
X1261248Y106894D01*
G03X1261865Y106838I487J1942D01*
G01X1261956Y106844D01*
X1263600Y105200D01*
X1266638D01*
G02X1267038Y104780I0J-400D01*
G03X1267448Y103642I1562J-80D01*
G02X1267444Y103097I-295J-270D01*
G03X1269676Y101248I1057J-996D01*
G02X1270324I324J-234D01*
G03X1272590Y103059I1176J852D01*
G02X1272606Y103603I301J263D01*
G03X1273054Y104700I-1116J1096D01*
G01Y105200D01*
X1276547D01*
G03X1278598Y105145I1053J1000D01*
G01X1278656Y105200D01*
X1278700D01*
X1282000Y108500D01*
Y113100D01*
X1281969D01*
X1280880Y114189D01*
X1278514D01*
X1275100Y110775D01*
Y106300D01*
X1274900Y106100D01*
X1273300D01*
X1273100Y106300D01*
Y115700D01*
X1274600Y117200D01*
X1275819D01*
X1275867Y117069D01*
G03X1278477Y116827I1363J501D01*
G01X1278490Y116848D01*
X1278842Y117200D01*
X1281700D01*
X1289000Y124500D01*
X1300439D01*
X1300451Y124312D01*
G03X1303349I1449J88D01*
G01X1303361Y124500D01*
X1319900D01*
X1320598Y123802D01*
Y103998D01*
X1319600Y103000D01*
X1317490D01*
X1315441Y100951D01*
Y97938D01*
X1316500Y96879D01*
Y96002D01*
X1316498D01*
Y94498D01*
X1316400Y94400D01*
Y91952D01*
X1313626D01*
X1313546Y91872D01*
G02X1312896Y91999I-282J283D01*
G03X1312620Y92423I-1337J-568D01*
G02X1312618Y92967I292J273D01*
G03X1310488Y94941I-1067J985D01*
G02X1309934Y94912I-292J273D01*
G03X1309868Y94965I-942J-1105D01*
G02X1309866Y95598I244J317D01*
G03X1308087Y95591I-894J1144D01*
G02X1308089Y94958I-244J-317D01*
G03X1310046Y92825I894J-1144D01*
G02X1310600Y92854I292J-273D01*
G03X1310616Y92841I924J1121D01*
G02X1310617Y92536I-129J-153D01*
G03X1311360Y89993I942J-1105D01*
G01X1311532Y89969D01*
Y84474D01*
G02X1310823Y84220I-400J0D01*
G03X1310069Y81896I-1123J-920D01*
G01X1310180Y81925D01*
X1310402Y81702D01*
X1309864Y81164D01*
X1308400D01*
G03X1307245Y78545I0J-1564D01*
G01X1298000Y69300D01*
Y66000D01*
X1288774Y56774D01*
X1288667Y56796D01*
G03X1284000Y45873I-1264J-5918D01*
G01Y36983D01*
G03Y26973I3403J-5005D01*
G01Y18083D01*
G03Y8073I3403J-5005D01*
G01Y-817D01*
G03Y-10827I3403J-5005D01*
G01Y-12043D01*
X1283017Y-13026D01*
X1278242D01*
X1277189Y-14079D01*
Y-15962D01*
X1274651Y-18500D01*
X1266660D01*
Y-15317D01*
X1266668Y-15291D01*
G03X1266723Y-14876I-1509J411D01*
G37*
G36*
G01X1257800Y111200D02*
G02X1258100Y110900I0J-300D01*
G02X1257800Y110600I-300J0D01*
G02X1257500Y110900I0J300D01*
G02X1257800Y111200I300J0D01*
G37*
G36*
G01X1260500Y117793D02*
G02X1260800Y117493I0J-300D01*
G02X1260500Y117193I-300J0D01*
G02X1260200Y117493I0J300D01*
G02X1260500Y117793I300J0D01*
G37*
G36*
G01X1247326Y123102D02*
G02X1247626Y122802I0J-300D01*
G02X1247326Y122502I-300J0D01*
G02X1247026Y122802I0J300D01*
G02X1247326Y123102I300J0D01*
G37*
G36*
G01X1382116Y161300D02*
X1381415Y162002D01*
X1378885D01*
X1378485Y161602D01*
X1311707D01*
X1311606Y161500D01*
X1309000D01*
X1308902Y161402D01*
X1300058D01*
G03X1299756I-151J-1594D01*
G01X1296219D01*
X1296179Y161420D01*
G03X1294821I-679J-1450D01*
G01X1294781Y161402D01*
X1273249D01*
G02X1272850Y161823I0J400D01*
G03X1269950I-1450J77D01*
G02X1269551Y161402I-399J-21D01*
G01X1269240D01*
Y161614D01*
X1269241Y161626D01*
G03X1267118Y163082I-1441J174D01*
G01X1266988Y163012D01*
X1255871Y174129D01*
G02X1255947Y174755I282J283D01*
G03X1254259Y177106I-747J1245D01*
G02X1253741I-259J305D01*
G03X1252658Y177445I-941J-1106D01*
G01X1252564Y177436D01*
X1242991Y187009D01*
X1243045Y187134D01*
G03X1241136Y189043I-1333J576D01*
G01X1241011Y188989D01*
X1229920Y200080D01*
Y233280D01*
X1233740Y237100D01*
X1244600D01*
X1268163Y213537D01*
X1270570Y210038D01*
X1275552Y206148D01*
X1304088Y177612D01*
X1325853D01*
X1327295Y177140D01*
X1329653Y177612D01*
X1340349D01*
X1343700Y176942D01*
X1347051Y177612D01*
X1358649D01*
X1368900Y175562D01*
X1376874Y177157D01*
X1383998Y175731D01*
Y171715D01*
X1383198Y170915D01*
Y170898D01*
X1382800Y170500D01*
Y169300D01*
X1383198Y168902D01*
Y168885D01*
X1383998Y168085D01*
Y166915D01*
X1382998Y165915D01*
Y163985D01*
X1383000Y163984D01*
Y163800D01*
X1383900Y162900D01*
Y162000D01*
X1383200Y161300D01*
X1382116D01*
G37*
G36*
G01X1246687Y494840D02*
X1246400Y495127D01*
Y504800D01*
X1250500Y508900D01*
Y510324D01*
X1251340Y511164D01*
X1252236D01*
X1252761Y511689D01*
Y514911D01*
X1253828Y515978D01*
X1255478D01*
X1257300Y517800D01*
Y529600D01*
X1256100Y530800D01*
X1253100D01*
X1250600Y533300D01*
Y548800D01*
X1251600Y549800D01*
X1252600D01*
X1253400Y550600D01*
Y553700D01*
X1253100Y554000D01*
X1250860D01*
Y554002D01*
X1247498D01*
X1246760Y554740D01*
Y556840D01*
X1247221Y557300D01*
X1249800D01*
X1250500Y558000D01*
Y586400D01*
X1252378Y588278D01*
Y591371D01*
X1252604Y591597D01*
X1255407D01*
X1257300Y593490D01*
Y605000D01*
X1255800Y606500D01*
X1251700D01*
X1250600Y607600D01*
Y621600D01*
X1251400Y622400D01*
X1280377D01*
X1281599Y621178D01*
Y610270D01*
G03Y606840I5804J-1715D01*
G01Y594511D01*
G03X1281503Y584967I5803J-4831D01*
G02X1281489Y584701I-156J-125D01*
G03X1281494Y582494I1111J-1101D01*
G01X1281599Y582388D01*
Y582212D01*
X1281494Y582106D01*
G03X1281599Y579798I1106J-1106D01*
G01Y572470D01*
G03Y569040I5804J-1715D01*
G01Y553594D01*
G03X1281591Y550191I5804J-1715D01*
G01X1281599Y550164D01*
Y547001D01*
X1283500Y545100D01*
X1312900D01*
X1314647Y543353D01*
X1314653Y543280D01*
G03X1315836Y541972I1447J120D01*
G01X1316000Y541942D01*
Y521000D01*
X1321889Y515111D01*
Y511602D01*
X1322263Y511228D01*
X1324693D01*
X1324990Y510932D01*
Y507340D01*
X1324906Y507256D01*
X1322744D01*
X1321980Y508020D01*
X1318356D01*
X1316873Y509502D01*
X1294763D01*
X1293751Y510514D01*
Y518014D01*
X1290490Y521275D01*
X1283910D01*
X1281005Y524180D01*
X1274210D01*
X1270177Y520147D01*
Y517921D01*
X1268522Y516266D01*
X1268494D01*
X1267516Y515288D01*
X1262294D01*
X1261721Y514715D01*
Y511646D01*
X1262221Y511146D01*
X1266930D01*
X1267260Y510816D01*
Y509187D01*
X1267258Y509172D01*
G03Y508708I1547J-232D01*
G01X1267260Y508693D01*
Y505687D01*
X1267258Y505672D01*
G03Y505208I1547J-232D01*
G01X1267260Y505193D01*
Y502483D01*
X1263586Y498809D01*
X1263459Y498868D01*
G03X1261528Y496937I-616J-1315D01*
G01X1261587Y496810D01*
X1259617Y494840D01*
X1246687D01*
G37*
G36*
G01X1307500Y51500D02*
X1322500D01*
X1322737Y51263D01*
X1322712Y51154D01*
G03X1324454Y49412I1415J-327D01*
G01X1324563Y49437D01*
X1325000Y49000D01*
X1331135D01*
X1332487Y47648D01*
X1332500D01*
Y42900D01*
X1332102Y42502D01*
X1328198D01*
Y38898D01*
X1328498D01*
Y32878D01*
X1330200Y31177D01*
Y-14300D01*
X1324000Y-20500D01*
X1307634D01*
X1301109Y-13975D01*
X1297136D01*
X1294000Y-10839D01*
Y376D01*
X1294017Y415D01*
G03Y1601I-1325J593D01*
G01X1294000Y1640D01*
Y51500D01*
X1294955Y52455D01*
X1295229D01*
G02X1295597Y51900I0J-400D01*
G03X1295912Y50305I1338J-564D01*
G02X1295910Y49736I-282J-284D01*
G03X1297951Y49730I1017J-1036D01*
G02X1297953Y50299I282J284D01*
G03X1298273Y51900I-1018J1036D01*
G02X1298641Y52455I368J155D01*
G01X1299998D01*
Y52398D01*
X1305002D01*
Y52455D01*
X1306545D01*
X1307500Y51500D01*
G37*
G36*
G01X1331500Y31400D02*
X1333700Y33600D01*
X1353600D01*
X1353900Y33300D01*
Y14000D01*
X1353600Y13700D01*
X1333800D01*
X1331500Y16000D01*
Y31400D01*
G37*
G36*
G01X1350993Y5493D02*
X1351000Y5500D01*
X1353574Y2926D01*
Y-15391D01*
X1353381Y-15584D01*
X1351303D01*
X1349799Y-14080D01*
X1332850D01*
X1332004Y-13234D01*
Y4004D01*
X1333493Y5493D01*
X1350993D01*
G37*
G36*
G01X1305000Y56000D02*
X1304500Y55500D01*
X1300500D01*
X1300000Y56000D01*
Y62500D01*
X1300500Y63000D01*
X1304500D01*
X1305000Y62500D01*
Y56000D01*
G37*
G36*
G01X1312000Y55500D02*
X1310000Y57500D01*
Y76500D01*
X1311000Y77500D01*
X1324000D01*
X1325000Y76500D01*
Y74513D01*
X1324136Y73648D01*
Y62303D01*
X1325000Y61438D01*
Y57000D01*
X1323500Y55500D01*
X1312000D01*
G37*
G36*
G01X1385788Y176474D02*
X1388386Y175954D01*
X1394800Y171611D01*
Y144600D01*
X1394680Y144480D01*
Y139833D01*
X1392701Y137854D01*
X1314187D01*
X1312344Y139697D01*
Y145883D01*
X1311385Y146842D01*
Y149348D01*
X1311552Y149515D01*
Y150612D01*
X1311342Y150822D01*
Y152957D01*
X1312098Y153713D01*
Y155741D01*
X1311385Y156454D01*
Y159863D01*
X1312122Y160600D01*
X1378900D01*
X1379300Y161000D01*
X1381000D01*
X1381800Y160200D01*
X1383700D01*
X1384100Y160600D01*
X1384200D01*
X1385000Y161400D01*
Y163400D01*
X1384000Y164400D01*
Y165500D01*
X1385000Y166500D01*
Y168500D01*
X1384200Y169300D01*
Y170500D01*
X1385000Y171300D01*
Y175686D01*
X1385788Y176474D01*
G37*
G36*
G01X1322300Y103000D02*
X1321600Y103700D01*
Y129620D01*
X1322710Y130730D01*
X1327010D01*
X1331280Y135000D01*
X1386500D01*
X1387700Y133800D01*
Y125000D01*
X1385100Y122400D01*
Y118000D01*
X1384600Y117500D01*
X1384302D01*
Y117502D01*
X1379498D01*
Y117500D01*
X1379250D01*
X1377600Y115850D01*
Y112602D01*
X1375548D01*
Y112547D01*
X1375245D01*
X1374842Y112950D01*
X1369700D01*
X1369200Y113450D01*
Y121450D01*
X1368700Y121950D01*
X1354700D01*
X1354200Y122450D01*
Y125950D01*
X1356698Y128448D01*
X1356702D01*
Y130452D01*
X1356700D01*
Y131300D01*
X1356000Y132000D01*
X1334500D01*
X1327900Y125400D01*
Y103300D01*
X1327600Y103000D01*
X1322300D01*
G37*
G36*
G01X1286500Y126000D02*
X1282500Y130000D01*
Y140000D01*
X1285000Y142500D01*
X1302500D01*
X1306000Y139000D01*
Y132883D01*
G03Y130605I900J-1139D01*
G01Y127500D01*
X1304500Y126000D01*
X1286500D01*
G37*
G36*
G01X1329649Y97858D02*
X1329300Y98207D01*
Y124400D01*
X1335275Y130375D01*
X1347000D01*
X1347198Y130177D01*
Y128448D01*
X1347700D01*
Y126950D01*
X1348700Y125950D01*
X1352700D01*
X1353198Y125452D01*
Y122035D01*
X1353200Y122034D01*
Y121450D01*
X1353700Y120950D01*
X1354284D01*
X1354285Y120948D01*
X1367702D01*
X1368198Y120452D01*
Y113035D01*
X1368200Y113034D01*
Y111950D01*
X1367700Y111450D01*
X1351200D01*
X1349700Y112950D01*
X1345700D01*
X1344345Y111595D01*
X1344280Y111585D01*
G03X1343438Y111162I219J-1485D01*
G01X1341902Y109625D01*
X1339126D01*
X1333380Y103879D01*
Y97963D01*
X1333275Y97858D01*
X1329649D01*
G37*
G36*
G01X1314900Y235259D02*
G02X1315200Y234959I0J-300D01*
G02X1314900Y234659I-300J0D01*
G02X1314600Y234959I0J300D01*
G02X1314900Y235259I300J0D01*
G37*
G36*
G01X1320400D02*
G02X1320700Y234959I0J-300D01*
G02X1320400Y234659I-300J0D01*
G02X1320100Y234959I0J300D01*
G02X1320400Y235259I300J0D01*
G37*
G36*
G01X1325900D02*
G02X1326200Y234959I0J-300D01*
G02X1325900Y234659I-300J0D01*
G02X1325600Y234959I0J300D01*
G02X1325900Y235259I300J0D01*
G37*
G36*
G01X1331400D02*
G02X1331700Y234959I0J-300D01*
G02X1331400Y234659I-300J0D01*
G02X1331100Y234959I0J300D01*
G02X1331400Y235259I300J0D01*
G37*
G36*
G01X1336900D02*
G02X1337200Y234959I0J-300D01*
G02X1336900Y234659I-300J0D01*
G02X1336600Y234959I0J300D01*
G02X1336900Y235259I300J0D01*
G37*
G36*
G01X1340866Y269095D02*
G02X1341166Y268795I0J-300D01*
G02X1340866Y268495I-300J0D01*
G02X1340566Y268795I0J300D01*
G02X1340866Y269095I300J0D01*
G37*
G36*
G01X1334113Y273415D02*
G02X1334413Y273115I0J-300D01*
G02X1334113Y272815I-300J0D01*
G02X1333813Y273115I0J300D01*
G02X1334113Y273415I300J0D01*
G37*
G36*
G01X1316300Y282300D02*
G02X1316600Y282000I0J-300D01*
G02X1316300Y281700I-300J0D01*
G02X1316000Y282000I0J300D01*
G02X1316300Y282300I300J0D01*
G37*
G36*
G01X1325300Y282900D02*
G02X1325600Y282600I0J-300D01*
G02X1325300Y282300I-300J0D01*
G02X1325000Y282600I0J300D01*
G02X1325300Y282900I300J0D01*
G37*
G36*
G01X1336793Y304084D02*
G02X1337093Y303784I0J-300D01*
G02X1336793Y303484I-300J0D01*
G02X1336493Y303784I0J300D01*
G02X1336793Y304084I300J0D01*
G37*
G36*
G01X1336480Y310055D02*
G02X1336780Y309755I0J-300D01*
G02X1336480Y309455I-300J0D01*
G02X1336180Y309755I0J300D01*
G02X1336480Y310055I300J0D01*
G37*
G36*
G01X1341920D02*
G02X1342220Y309755I0J-300D01*
G02X1341920Y309455I-300J0D01*
G02X1341620Y309755I0J300D01*
G02X1341920Y310055I300J0D01*
G37*
G36*
G01X1338500Y319900D02*
G02X1338800Y319600I0J-300D01*
G02X1338500Y319300I-300J0D01*
G02X1338200Y319600I0J300D01*
G02X1338500Y319900I300J0D01*
G37*
G36*
G01X1359400Y365500D02*
X1357600Y367300D01*
Y395300D01*
X1354100Y398800D01*
X1341500D01*
X1340000Y400300D01*
Y415000D01*
X1342000Y417000D01*
X1344500D01*
X1345000Y417500D01*
Y417998D01*
X1345002D01*
Y420002D01*
X1345000D01*
Y420400D01*
X1347358Y422758D01*
X1390945D01*
X1391215Y422488D01*
Y410367D01*
X1390455Y409607D01*
X1385804D01*
X1385365Y410046D01*
X1360945D01*
X1359971Y409072D01*
Y404027D01*
X1361292Y402706D01*
X1365833D01*
X1366686Y401853D01*
Y397308D01*
X1367697Y396297D01*
Y396203D01*
X1368600Y395300D01*
Y391100D01*
X1368900Y390800D01*
X1372900D01*
X1373100Y391000D01*
Y394600D01*
X1373200Y394700D01*
X1373800D01*
X1373900Y394600D01*
Y390900D01*
X1374000Y390800D01*
X1375000D01*
X1375100Y390700D01*
Y384200D01*
X1375000Y384100D01*
X1367100D01*
X1366043Y383043D01*
Y370140D01*
X1365998D01*
Y368138D01*
X1366043D01*
Y366043D01*
X1365500Y365500D01*
X1359400D01*
G37*
G36*
G01X1310000Y373500D02*
X1304100Y379400D01*
Y419400D01*
X1296300Y427200D01*
Y430700D01*
X1296500Y430900D01*
X1299300D01*
X1301043Y429157D01*
X1301057Y429129D01*
G03X1301822Y428364I1561J796D01*
G01X1301850Y428350D01*
X1307300Y422900D01*
X1315330D01*
G02X1315652Y422262I0J-400D01*
G03X1315749Y420420I1168J-862D01*
G02Y419880I-295J-270D01*
G03X1317800Y417829I1071J-980D01*
G02X1318340I270J-295D01*
G03X1318221Y419849I980J1071D01*
G02X1317919I-151J131D01*
G03X1317891Y419880I-1091J-958D01*
G02Y420420I295J270D01*
G03X1317988Y422262I-1071J980D01*
G02X1318310Y422900I322J238D01*
G01X1336800D01*
X1337900Y421800D01*
Y398600D01*
X1334900Y395600D01*
Y374900D01*
X1333500Y373500D01*
X1310000D01*
G37*
G36*
G01X1356100Y392900D02*
Y375800D01*
X1354900Y374600D01*
X1341600D01*
X1338130Y378070D01*
Y378078D01*
X1336163Y380045D01*
Y392963D01*
X1336700Y393500D01*
X1355500D01*
X1356100Y392900D01*
G37*
G36*
G01X1305228Y426400D02*
X1302027Y429601D01*
Y433663D01*
X1299442Y436248D01*
Y440927D01*
X1295990Y444379D01*
Y445290D01*
X1297000Y446300D01*
X1332324D01*
X1334888Y448864D01*
Y451019D01*
X1334123Y451784D01*
Y452995D01*
X1334883Y453755D01*
Y456333D01*
X1334858Y456358D01*
X1334089Y457127D01*
Y458186D01*
X1334503Y458600D01*
X1341100D01*
X1344090Y455610D01*
Y444911D01*
X1346400Y442600D01*
X1348900D01*
X1351316Y444999D01*
Y445751D01*
X1352113Y446548D01*
Y448348D01*
X1351328Y449134D01*
Y450834D01*
X1352117Y451624D01*
Y453480D01*
X1351335Y454262D01*
Y455727D01*
X1352038Y456430D01*
X1353001D01*
X1355296Y454135D01*
Y444039D01*
X1356645Y442690D01*
X1359310D01*
X1361278Y444658D01*
Y445844D01*
X1362108Y446674D01*
Y448655D01*
X1361365Y449398D01*
Y450903D01*
X1362104Y451642D01*
Y453684D01*
X1361385Y454403D01*
Y455655D01*
X1362178Y456448D01*
X1363551D01*
X1366113Y453886D01*
Y451243D01*
X1365829Y450959D01*
Y449203D01*
X1366799Y448233D01*
X1367109D01*
X1369427Y445915D01*
X1370809D01*
X1370867Y445973D01*
Y445986D01*
X1371341Y446460D01*
X1373566D01*
X1375180Y444846D01*
Y443825D01*
X1376126Y442879D01*
Y441710D01*
X1373086Y438670D01*
X1372000D01*
X1371038Y439632D01*
X1369048D01*
X1368117Y438701D01*
X1367122D01*
X1366073Y439750D01*
X1364301D01*
X1363526Y438976D01*
Y429379D01*
X1362446Y428299D01*
Y427283D01*
X1361564Y426400D01*
X1344415D01*
X1344164Y426650D01*
Y429102D01*
G03X1342480Y431672I-1546J823D01*
G02X1342166Y432353I-31J398D01*
G01X1343035Y433223D01*
X1343086Y433237D01*
G03X1341026Y435656I-468J1688D01*
G01X1341011Y435623D01*
X1338994Y433606D01*
G03X1340476Y430981I1106J-1106D01*
G02X1340953Y430469I97J-388D01*
G03X1341018Y429211I1665J-545D01*
G01X1341036Y429172D01*
Y426754D01*
X1340681Y426400D01*
X1337700D01*
X1336733Y427367D01*
Y433401D01*
X1333403Y436731D01*
X1331851D01*
X1330827Y435707D01*
Y434060D01*
X1331749Y433138D01*
Y431446D01*
G03Y428404I869J-1521D01*
G01Y426749D01*
X1331400Y426400D01*
X1305228D01*
G37*
G36*
G01X1296200Y449300D02*
Y455900D01*
X1299000Y458700D01*
X1331100D01*
X1333857Y455943D01*
Y454261D01*
X1333601Y454005D01*
X1333596D01*
X1333068Y453477D01*
Y451391D01*
X1333867Y450592D01*
Y449303D01*
X1333064Y448500D01*
X1297000D01*
X1296200Y449300D01*
G37*
G36*
G01X1311508Y499692D02*
X1308647Y502553D01*
X1305263D01*
X1304900Y502916D01*
Y506200D01*
X1305198Y506498D01*
X1316968D01*
X1317450Y506016D01*
X1318548D01*
Y506014D01*
X1321561D01*
X1321785Y505790D01*
Y503389D01*
G03X1321340Y502186I1407J-1204D01*
G01Y501214D01*
X1319818Y499692D01*
X1311508D01*
G37*
G36*
G01X1323308Y511811D02*
X1323145Y511974D01*
X1323143D01*
X1322995Y512122D01*
Y516404D01*
X1323500Y516909D01*
Y536536D01*
X1326740Y539776D01*
X1326844Y539757D01*
G03X1331970Y541193I1112J5898D01*
G01X1341786D01*
X1341988Y540991D01*
Y537641D01*
X1343723Y535906D01*
X1347804D01*
X1347998Y535712D01*
Y532635D01*
X1348000Y532634D01*
Y532050D01*
X1348500Y531550D01*
X1349084D01*
X1349085Y531548D01*
X1362502D01*
X1362998Y531052D01*
Y523635D01*
X1363000Y523634D01*
Y522550D01*
X1362500Y522050D01*
X1346000D01*
X1344500Y523550D01*
X1337082D01*
X1336045Y522513D01*
X1333552D01*
X1326598Y515559D01*
Y515104D01*
X1326590D01*
Y512095D01*
X1326306Y511811D01*
X1323308D01*
G37*
G36*
G01X1333200Y498300D02*
X1332591Y498909D01*
Y501806D01*
X1333501Y502716D01*
X1334098D01*
Y502698D01*
X1336102D01*
Y502716D01*
X1342723D01*
X1342925Y502514D01*
Y500725D01*
X1341927Y499727D01*
X1340447D01*
X1339020Y498300D01*
X1333200D01*
G37*
G36*
G01X1334713Y567400D02*
X1344000D01*
X1346750Y564650D01*
Y556800D01*
X1348800Y554750D01*
Y550700D01*
X1348000Y549900D01*
X1330750D01*
X1329450Y551200D01*
Y562650D01*
X1331997Y565197D01*
X1332137Y565089D01*
G03X1334349Y566835I889J1148D01*
G02X1334713Y567400I364J165D01*
G37*
G36*
G01X1297300Y547400D02*
X1294000Y550700D01*
Y576199D01*
X1300147Y582346D01*
Y586147D01*
X1300498Y586498D01*
X1305502D01*
Y586500D01*
X1305700D01*
X1306800Y587600D01*
Y601300D01*
X1305500Y602600D01*
X1298900D01*
X1297700Y603800D01*
Y610496D01*
X1300754Y613550D01*
X1306489D01*
X1308168Y615229D01*
X1326871D01*
X1328925Y613175D01*
Y566925D01*
X1325250Y563250D01*
Y550550D01*
X1322100Y547400D01*
X1297300D01*
G37*
G36*
G01X1349807Y563098D02*
X1348948Y563957D01*
Y566765D01*
X1346557Y569156D01*
X1337888D01*
X1336500Y570544D01*
Y586000D01*
X1338000Y587500D01*
X1353578D01*
X1357870Y583208D01*
Y563523D01*
X1357445Y563098D01*
X1353002D01*
Y563102D01*
X1350998D01*
Y563098D01*
X1349807D01*
G37*
G36*
G01X1305200Y589600D02*
X1300500D01*
X1299400Y588500D01*
X1298089D01*
X1297664Y588925D01*
Y599271D01*
X1297887Y599494D01*
X1305471D01*
X1305500Y599465D01*
Y589900D01*
X1305200Y589600D01*
G37*
G36*
G01X1337135Y616135D02*
X1347535D01*
X1348882Y617482D01*
X1354092D01*
X1358000Y613574D01*
Y595000D01*
X1357700Y594700D01*
X1336600D01*
X1335500Y595800D01*
Y614500D01*
X1337135Y616135D01*
G37*
G36*
G01X1344645Y-21573D02*
X1343932Y-20860D01*
Y-16449D01*
X1345300Y-15082D01*
X1349170D01*
X1349712Y-15623D01*
Y-16460D01*
X1350057Y-16805D01*
X1354740D01*
X1354892Y-16653D01*
Y4975D01*
X1355200Y5283D01*
Y5300D01*
X1355800Y5900D01*
Y13500D01*
X1355200Y14100D01*
Y34700D01*
X1354650Y35250D01*
X1350242D01*
X1349820Y35672D01*
Y38672D01*
X1350269Y39121D01*
X1350945D01*
X1350996Y39085D01*
G03X1352869Y39121I912J1317D01*
G01X1359831D01*
X1361492Y40782D01*
X1362082D01*
X1362500Y41200D01*
X1364221D01*
X1364398Y41023D01*
Y39198D01*
X1364473D01*
Y38524D01*
X1365398Y37598D01*
Y37378D01*
X1366038Y36738D01*
G03X1366300Y36529I1062J1062D01*
G01Y32200D01*
X1366400Y32100D01*
X1371800D01*
X1372100Y31800D01*
X1372400D01*
X1372800Y31400D01*
Y26000D01*
X1372000Y25200D01*
X1365100D01*
X1363600Y23700D01*
Y13219D01*
X1363976Y12843D01*
Y10560D01*
X1364101Y10435D01*
Y9378D01*
X1364088D01*
Y7374D01*
X1364101D01*
Y7221D01*
X1365348Y5974D01*
X1365341Y5883D01*
G03X1366158Y4468I1448J-107D01*
G01Y625D01*
X1366587Y196D01*
X1371966D01*
X1371971Y191D01*
X1372751D01*
X1372800Y142D01*
Y-6683D01*
X1372349Y-7134D01*
X1364335D01*
X1363500Y-7969D01*
Y-18840D01*
X1363257Y-19083D01*
Y-21346D01*
X1363030Y-21573D01*
X1344645D01*
G37*
G36*
G01X1381502Y6547D02*
X1379950Y8099D01*
Y10626D01*
X1379177Y11399D01*
X1377150D01*
X1376719Y10968D01*
X1368203D01*
X1367843Y10608D01*
X1365642D01*
X1365502Y10748D01*
Y12740D01*
X1364900Y13342D01*
Y23353D01*
X1365239Y23692D01*
X1372308D01*
X1372900Y23100D01*
Y17611D01*
X1373343Y17168D01*
X1376898D01*
X1377862Y16204D01*
Y15087D01*
X1378301Y14648D01*
X1385781D01*
X1388095Y16962D01*
Y29414D01*
X1390580Y31899D01*
Y35620D01*
X1389600Y36600D01*
X1387500D01*
X1387000Y37100D01*
Y38618D01*
X1390014Y41633D01*
Y48717D01*
X1386161Y52570D01*
X1386150Y52630D01*
G03X1384894Y54415I-2650J-530D01*
G01Y55091D01*
G03Y60007I-1723J2458D01*
G01Y63000D01*
X1388500Y66606D01*
Y71341D01*
X1390631Y73472D01*
Y81798D01*
X1388500Y83929D01*
Y90246D01*
X1390254Y92000D01*
X1398000D01*
X1399000Y91000D01*
Y81000D01*
X1404500Y75500D01*
Y52312D01*
G02X1403798Y52050I-400J0D01*
G03Y50150I-1098J-950D01*
G02X1404500Y49888I302J-262D01*
G01Y48759D01*
G03X1400951Y45289I2046J-5643D01*
G01X1400936Y45250D01*
X1400902Y45216D01*
Y45158D01*
X1400890Y45126D01*
G03X1400902Y41074I5656J-2009D01*
G01Y29222D01*
X1397519Y25839D01*
Y15953D01*
X1394076Y12510D01*
Y6800D01*
X1393823Y6547D01*
X1381502D01*
G37*
G36*
G01X1365521Y-21706D02*
X1364900Y-21085D01*
Y-8200D01*
X1372374D01*
X1372508Y-8334D01*
Y-13500D01*
X1373146Y-14138D01*
Y-14158D01*
X1373166D01*
X1373308Y-14300D01*
X1376850D01*
X1377770Y-15220D01*
X1379275D01*
X1379457Y-15402D01*
X1379902D01*
X1380427Y-15927D01*
Y-20901D01*
X1379622Y-21706D01*
X1365521D01*
G37*
G36*
G01X1350000Y53500D02*
Y67500D01*
X1364000D01*
Y53500D01*
X1350000D01*
G37*
G36*
G01X1402700Y51400D02*
G02X1403000Y51100I0J-300D01*
G02X1402700Y50800I-300J0D01*
G02X1402400Y51100I0J300D01*
G02X1402700Y51400I300J0D01*
G37*
G36*
G01X1411700Y76100D02*
X1406900D01*
X1402000Y81000D01*
Y93800D01*
X1402900Y94700D01*
X1409300D01*
X1412900Y91100D01*
Y77300D01*
X1411700Y76100D01*
G37*
G36*
G01X1368552Y66948D02*
Y68488D01*
X1368500D01*
Y68878D01*
X1370622Y71000D01*
X1373498D01*
Y70998D01*
X1375502D01*
Y71000D01*
X1376998D01*
Y70998D01*
X1379002D01*
X1379150Y70850D01*
Y68450D01*
X1378800Y68100D01*
X1373300D01*
X1372184Y66984D01*
X1371992D01*
X1371610Y66602D01*
X1369400D01*
G03X1369046Y66559I3J-1502D01*
G02X1368552Y66948I-94J389D01*
G37*
G36*
G01X1400145Y105649D02*
Y95600D01*
X1398992Y94447D01*
X1388080D01*
X1387894Y94633D01*
Y104839D01*
X1389100Y106045D01*
Y106188D01*
X1399606D01*
X1400145Y105649D01*
G37*
G36*
G01X1351490Y103600D02*
X1350840Y104250D01*
Y108300D01*
X1350340Y108800D01*
X1347100D01*
X1346900Y109000D01*
Y109900D01*
X1347100Y110100D01*
X1358610D01*
X1359100Y109610D01*
Y104090D01*
X1358962Y103952D01*
X1358285D01*
X1357934Y103600D01*
X1351490D01*
G37*
G36*
G01X1397193Y112902D02*
G02X1397493Y112602I0J-300D01*
G02X1397193Y112302I-300J0D01*
G02X1396893Y112602I0J300D01*
G02X1397193Y112902I300J0D01*
G37*
G36*
G01X1387198Y117502D02*
X1386700Y118000D01*
Y121800D01*
X1389700Y124800D01*
Y130387D01*
X1390662Y131349D01*
X1395695D01*
X1396700Y130344D01*
Y122000D01*
X1392202Y117502D01*
X1387198D01*
G37*
G36*
G01X1361000Y94250D02*
X1360658Y94591D01*
Y97034D01*
X1360408Y97284D01*
Y97548D01*
X1360145D01*
X1358200Y99492D01*
Y102450D01*
X1358700Y102950D01*
X1360700D01*
X1361200Y102450D01*
Y99550D01*
X1363000Y97750D01*
Y94850D01*
X1362400Y94250D01*
X1361000D01*
G37*
G36*
G01X1379596Y114493D02*
X1393400D01*
X1395246Y112646D01*
Y108146D01*
X1394563Y107463D01*
X1387663D01*
X1386000Y105800D01*
Y95750D01*
X1385524Y95274D01*
X1372226D01*
X1368500Y99000D01*
X1364700D01*
X1364200Y99500D01*
Y103450D01*
X1363700Y103950D01*
X1361116D01*
X1361115Y103952D01*
X1360200D01*
Y109950D01*
X1372706D01*
X1373892Y111136D01*
X1375548D01*
Y111098D01*
X1377552D01*
Y111136D01*
X1378478D01*
Y111141D01*
X1379458Y112121D01*
Y114355D01*
X1379596Y114493D01*
G37*
G36*
G01X1383753Y265848D02*
G02X1384053Y265548I0J-300D01*
G02X1383753Y265248I-300J0D01*
G02X1383453Y265548I0J300D01*
G02X1383753Y265848I300J0D01*
G37*
G36*
G01X1397400Y235259D02*
G02X1397700Y234959I0J-300D01*
G02X1397400Y234659I-300J0D01*
G02X1397100Y234959I0J300D01*
G02X1397400Y235259I300J0D01*
G37*
G36*
G01X1391900D02*
G02X1392200Y234959I0J-300D01*
G02X1391900Y234659I-300J0D01*
G02X1391600Y234959I0J300D01*
G02X1391900Y235259I300J0D01*
G37*
G36*
G01X1386400D02*
G02X1386700Y234959I0J-300D01*
G02X1386400Y234659I-300J0D01*
G02X1386100Y234959I0J300D01*
G02X1386400Y235259I300J0D01*
G37*
G36*
G01X1342400D02*
G02X1342700Y234959I0J-300D01*
G02X1342400Y234659I-300J0D01*
G02X1342100Y234959I0J300D01*
G02X1342400Y235259I300J0D01*
G37*
G36*
G01X1347900D02*
G02X1348200Y234959I0J-300D01*
G02X1347900Y234659I-300J0D01*
G02X1347600Y234959I0J300D01*
G02X1347900Y235259I300J0D01*
G37*
G36*
G01X1353400D02*
G02X1353700Y234959I0J-300D01*
G02X1353400Y234659I-300J0D01*
G02X1353100Y234959I0J300D01*
G02X1353400Y235259I300J0D01*
G37*
G36*
G01X1358900D02*
G02X1359200Y234959I0J-300D01*
G02X1358900Y234659I-300J0D01*
G02X1358600Y234959I0J300D01*
G02X1358900Y235259I300J0D01*
G37*
G36*
G01X1359100Y265900D02*
G02X1359400Y265600I0J-300D01*
G02X1359100Y265300I-300J0D01*
G02X1358800Y265600I0J300D01*
G02X1359100Y265900I300J0D01*
G37*
G36*
G01X1349500Y265800D02*
G02X1349800Y265500I0J-300D01*
G02X1349500Y265200I-300J0D01*
G02X1349200Y265500I0J300D01*
G02X1349500Y265800I300J0D01*
G37*
G36*
G01X1364400Y235259D02*
G02X1364700Y234959I0J-300D01*
G02X1364400Y234659I-300J0D01*
G02X1364100Y234959I0J300D01*
G02X1364400Y235259I300J0D01*
G37*
G36*
G01X1369900D02*
G02X1370200Y234959I0J-300D01*
G02X1369900Y234659I-300J0D01*
G02X1369600Y234959I0J300D01*
G02X1369900Y235259I300J0D01*
G37*
G36*
G01X1375400Y235400D02*
G02X1375700Y235100I0J-300D01*
G02X1375400Y234800I-300J0D01*
G02X1375100Y235100I0J300D01*
G02X1375400Y235400I300J0D01*
G37*
G36*
G01X1380900Y235259D02*
G02X1381200Y234959I0J-300D01*
G02X1380900Y234659I-300J0D01*
G02X1380600Y234959I0J300D01*
G02X1380900Y235259I300J0D01*
G37*
G36*
G01X1374864Y265929D02*
G02X1375164Y265629I0J-300D01*
G02X1374864Y265329I-300J0D01*
G02X1374564Y265629I0J300D01*
G02X1374864Y265929I300J0D01*
G37*
G36*
G01X1369100Y265800D02*
G02X1369400Y265500I0J-300D01*
G02X1369100Y265200I-300J0D01*
G02X1368800Y265500I0J300D01*
G02X1369100Y265800I300J0D01*
G37*
G36*
G01X1389600Y320400D02*
G02X1389900Y320100I0J-300D01*
G02X1389600Y319800I-300J0D01*
G02X1389300Y320100I0J300D01*
G02X1389600Y320400I300J0D01*
G37*
G36*
G01X1383639Y315574D02*
G02X1383939Y315274I0J-300D01*
G02X1383639Y314974I-300J0D01*
G02X1383339Y315274I0J300D01*
G02X1383639Y315574I300J0D01*
G37*
G36*
G01X1384024Y320525D02*
G02X1384324Y320225I0J-300D01*
G02X1384024Y319925I-300J0D01*
G02X1383724Y320225I0J300D01*
G02X1384024Y320525I300J0D01*
G37*
G36*
G01X1389600Y315500D02*
G02X1389900Y315200I0J-300D01*
G02X1389600Y314900I-300J0D01*
G02X1389300Y315200I0J300D01*
G02X1389600Y315500I300J0D01*
G37*
G36*
G01X1398062Y316043D02*
G02X1398362Y315743I0J-300D01*
G02X1398062Y315443I-300J0D01*
G02X1397762Y315743I0J300D01*
G02X1398062Y316043I300J0D01*
G37*
G36*
G01X1403100Y321650D02*
G02X1403400Y321350I0J-300D01*
G02X1403100Y321050I-300J0D01*
G02X1402800Y321350I0J300D01*
G02X1403100Y321650I300J0D01*
G37*
G36*
G01X1386265Y304610D02*
G02X1386565Y304310I0J-300D01*
G02X1386265Y304010I-300J0D01*
G02X1385965Y304310I0J300D01*
G02X1386265Y304610I300J0D01*
G37*
G36*
G01X1392380Y304940D02*
G02X1392680Y304640I0J-300D01*
G02X1392380Y304340I-300J0D01*
G02X1392080Y304640I0J300D01*
G02X1392380Y304940I300J0D01*
G37*
G36*
G01X1397880D02*
G02X1398180Y304640I0J-300D01*
G02X1397880Y304340I-300J0D01*
G02X1397580Y304640I0J300D01*
G02X1397880Y304940I300J0D01*
G37*
G36*
G01X1403300D02*
G02X1403600Y304640I0J-300D01*
G02X1403300Y304340I-300J0D01*
G02X1403000Y304640I0J300D01*
G02X1403300Y304940I300J0D01*
G37*
G36*
G01X1403260Y310923D02*
G02X1403560Y310623I0J-300D01*
G02X1403260Y310323I-300J0D01*
G02X1402960Y310623I0J300D01*
G02X1403260Y310923I300J0D01*
G37*
G36*
G01X1397640Y310931D02*
G02X1397940Y310631I0J-300D01*
G02X1397640Y310331I-300J0D01*
G02X1397340Y310631I0J300D01*
G02X1397640Y310931I300J0D01*
G37*
G36*
G01X1392340Y310925D02*
G02X1392640Y310625I0J-300D01*
G02X1392340Y310325I-300J0D01*
G02X1392040Y310625I0J300D01*
G02X1392340Y310925I300J0D01*
G37*
G36*
G01X1386048Y310610D02*
G02X1386348Y310310I0J-300D01*
G02X1386048Y310010I-300J0D01*
G02X1385748Y310310I0J300D01*
G02X1386048Y310610I300J0D01*
G37*
G36*
G01X1358800Y304000D02*
G02X1359100Y303700I0J-300D01*
G02X1358800Y303400I-300J0D01*
G02X1358500Y303700I0J300D01*
G02X1358800Y304000I300J0D01*
G37*
G36*
G01X1353359Y304067D02*
G02X1353659Y303767I0J-300D01*
G02X1353359Y303467I-300J0D01*
G02X1353059Y303767I0J300D01*
G02X1353359Y304067I300J0D01*
G37*
G36*
G01X1348190Y304110D02*
G02X1348490Y303810I0J-300D01*
G02X1348190Y303510I-300J0D01*
G02X1347890Y303810I0J300D01*
G02X1348190Y304110I300J0D01*
G37*
G36*
G01X1342480Y304152D02*
G02X1342780Y303852I0J-300D01*
G02X1342480Y303552I-300J0D01*
G02X1342180Y303852I0J300D01*
G02X1342480Y304152I300J0D01*
G37*
G36*
G01X1348080Y310125D02*
G02X1348380Y309825I0J-300D01*
G02X1348080Y309525I-300J0D01*
G02X1347780Y309825I0J300D01*
G02X1348080Y310125I300J0D01*
G37*
G36*
G01X1353142Y310061D02*
G02X1353442Y309761I0J-300D01*
G02X1353142Y309461I-300J0D01*
G02X1352842Y309761I0J300D01*
G02X1353142Y310061I300J0D01*
G37*
G36*
G01X1358792Y310060D02*
G02X1359092Y309760I0J-300D01*
G02X1358792Y309460I-300J0D01*
G02X1358492Y309760I0J300D01*
G02X1358792Y310060I300J0D01*
G37*
G36*
G01X1357452Y319695D02*
G02X1357752Y319395I0J-300D01*
G02X1357452Y319095I-300J0D01*
G02X1357152Y319395I0J300D01*
G02X1357452Y319695I300J0D01*
G37*
G36*
G01X1350650Y315350D02*
G02X1350950Y315050I0J-300D01*
G02X1350650Y314750I-300J0D01*
G02X1350350Y315050I0J300D01*
G02X1350650Y315350I300J0D01*
G37*
G36*
G01X1346550Y322650D02*
G02X1346850Y322350I0J-300D01*
G02X1346550Y322050I-300J0D01*
G02X1346250Y322350I0J300D01*
G02X1346550Y322650I300J0D01*
G37*
G36*
G01X1342500Y312400D02*
G02X1342800Y312100I0J-300D01*
G02X1342500Y311800I-300J0D01*
G02X1342200Y312100I0J300D01*
G02X1342500Y312400I300J0D01*
G37*
G36*
G01X1375040Y304435D02*
G02X1375340Y304135I0J-300D01*
G02X1375040Y303835I-300J0D01*
G02X1374740Y304135I0J300D01*
G02X1375040Y304435I300J0D01*
G37*
G36*
G01X1369540D02*
G02X1369840Y304135I0J-300D01*
G02X1369540Y303835I-300J0D01*
G02X1369240Y304135I0J300D01*
G02X1369540Y304435I300J0D01*
G37*
G36*
G01X1364213Y303994D02*
G02X1364513Y303694I0J-300D01*
G02X1364213Y303394I-300J0D01*
G02X1363913Y303694I0J300D01*
G02X1364213Y303994I300J0D01*
G37*
G36*
G01X1364044Y309991D02*
G02X1364344Y309691I0J-300D01*
G02X1364044Y309391I-300J0D01*
G02X1363744Y309691I0J300D01*
G02X1364044Y309991I300J0D01*
G37*
G36*
G01X1369540Y310425D02*
G02X1369840Y310125I0J-300D01*
G02X1369540Y309825I-300J0D01*
G02X1369240Y310125I0J300D01*
G02X1369540Y310425I300J0D01*
G37*
G36*
G01X1374900Y310430D02*
G02X1375200Y310130I0J-300D01*
G02X1374900Y309830I-300J0D01*
G02X1374600Y310130I0J300D01*
G02X1374900Y310430I300J0D01*
G37*
G36*
G01X1380910Y310600D02*
G02X1381210Y310300I0J-300D01*
G02X1380910Y310000I-300J0D01*
G02X1380610Y310300I0J300D01*
G02X1380910Y310600I300J0D01*
G37*
G36*
G01X1381100Y304660D02*
G02X1381400Y304360I0J-300D01*
G02X1381100Y304060I-300J0D01*
G02X1380800Y304360I0J300D01*
G02X1381100Y304660I300J0D01*
G37*
G36*
G01X1371000Y322700D02*
G02X1371300Y322400I0J-300D01*
G02X1371000Y322100I-300J0D01*
G02X1370700Y322400I0J300D01*
G02X1371000Y322700I300J0D01*
G37*
G36*
G01X1368947Y314293D02*
G02X1369247Y313993I0J-300D01*
G02X1368947Y313693I-300J0D01*
G02X1368647Y313993I0J300D01*
G02X1368947Y314293I300J0D01*
G37*
G36*
G01X1363059Y314814D02*
G02X1363359Y314514I0J-300D01*
G02X1363059Y314214I-300J0D01*
G02X1362759Y314514I0J300D01*
G02X1363059Y314814I300J0D01*
G37*
G36*
G01X1392500Y344900D02*
G02X1392800Y344600I0J-300D01*
G02X1392500Y344300I-300J0D01*
G02X1392200Y344600I0J300D01*
G02X1392500Y344900I300J0D01*
G37*
G36*
G01X1370848Y365477D02*
X1367600Y368725D01*
Y382100D01*
X1368000Y382500D01*
X1374900D01*
X1375200Y382200D01*
Y376800D01*
X1375600Y376400D01*
X1379550D01*
X1381432Y374518D01*
Y374474D01*
X1381476D01*
X1381850Y374100D01*
X1383300D01*
X1383598Y373802D01*
Y371774D01*
X1383600D01*
Y371450D01*
X1384270Y370780D01*
X1394261D01*
X1395499Y372018D01*
Y373299D01*
X1396700Y374500D01*
Y382279D01*
X1399864Y385443D01*
Y391883D01*
X1395047Y396700D01*
X1383300D01*
X1382300Y397700D01*
X1379800D01*
X1378500Y399000D01*
Y400500D01*
X1378000Y401000D01*
X1373900D01*
X1372688Y402212D01*
Y402763D01*
X1371576Y403875D01*
X1361565D01*
X1361074Y404366D01*
Y408733D01*
X1361341Y409000D01*
X1377877D01*
G03X1377979I51J1451D01*
G01X1384968D01*
X1385401Y408567D01*
X1390737D01*
X1391350Y407954D01*
Y402172D01*
X1391988Y401534D01*
X1405796D01*
X1406780Y400550D01*
Y371470D01*
X1402395Y367085D01*
X1402373D01*
X1400765Y365477D01*
X1393314D01*
G03X1390974I-1170J-860D01*
G01X1370848D01*
G37*
G36*
G01X1398275Y453861D02*
G02X1398575Y453561I0J-300D01*
G02X1398275Y453261I-300J0D01*
G02X1397975Y453561I0J300D01*
G02X1398275Y453861I300J0D01*
G37*
G36*
G01X1397975Y457861D02*
G02X1398275Y457561I0J-300D01*
G02X1397975Y457261I-300J0D01*
G02X1397675Y457561I0J300D01*
G02X1397975Y457861I300J0D01*
G37*
G36*
G01X1379857Y458408D02*
G02X1380157Y458108I0J-300D01*
G02X1379857Y457808I-300J0D01*
G02X1379557Y458108I0J300D01*
G02X1379857Y458408I300J0D01*
G37*
G36*
G01X1369034Y458375D02*
G02X1369334Y458075I0J-300D01*
G02X1369034Y457775I-300J0D01*
G02X1368734Y458075I0J300D01*
G02X1369034Y458375I300J0D01*
G37*
G36*
G01X1393800Y404200D02*
X1392230Y405770D01*
Y421487D01*
X1392555Y421812D01*
X1393283D01*
X1393289Y421806D01*
X1400841D01*
X1401259Y421388D01*
Y413968D01*
X1401236Y413924D01*
G03X1401107Y412913I1284J-678D01*
G01X1401112Y412891D01*
Y404427D01*
X1400885Y404200D01*
X1393800D01*
G37*
G36*
G01X1358900Y443700D02*
X1357100D01*
X1356300Y444500D01*
Y455622D01*
X1359104Y458426D01*
X1360969D01*
X1361100Y458295D01*
Y456817D01*
X1360366Y456083D01*
Y453811D01*
X1361100Y453077D01*
Y452070D01*
X1360340Y451310D01*
Y448681D01*
X1361100Y447921D01*
Y447101D01*
X1360075Y446076D01*
Y444875D01*
X1358900Y443700D01*
G37*
G36*
G01X1348503D02*
X1347100D01*
X1346300Y444500D01*
Y455622D01*
X1349326Y458648D01*
X1350748D01*
X1351100Y458295D01*
Y457011D01*
X1350326Y456237D01*
Y453682D01*
X1351115Y452893D01*
Y452075D01*
X1350326Y451286D01*
Y448706D01*
X1351101Y447931D01*
Y447047D01*
X1350238Y446184D01*
Y445435D01*
X1348503Y443700D01*
G37*
G36*
G01X1389136Y428452D02*
X1390624Y426964D01*
X1390160Y426500D01*
X1363658D01*
X1363448Y426710D01*
Y427884D01*
X1364528Y428964D01*
Y438561D01*
X1364716Y438749D01*
X1365658D01*
X1366724Y437683D01*
X1368527D01*
X1369473Y438629D01*
X1370448D01*
X1371430Y437647D01*
X1373479D01*
X1377169Y441337D01*
Y443301D01*
X1376200Y444270D01*
Y445600D01*
X1376900Y446300D01*
X1379259D01*
X1379519Y446040D01*
X1380686D01*
X1380946Y446300D01*
X1384083D01*
X1384456Y445927D01*
X1385760D01*
X1386133Y446300D01*
X1388150D01*
X1388536Y445915D01*
Y437902D01*
X1388800Y437637D01*
Y437500D01*
X1390922Y435378D01*
X1390901Y435273D01*
G03X1391076Y434093I1717J-348D01*
G01X1391100Y434049D01*
Y433325D01*
X1389136Y431360D01*
Y428452D01*
G37*
G36*
G01X1364758Y497192D02*
Y498746D01*
X1365538Y499526D01*
Y501488D01*
X1365627Y501577D01*
X1367541D01*
X1367620Y501498D01*
Y498721D01*
G03X1366990Y497577I821J-1198D01*
G02X1366590Y497192I-400J15D01*
G01X1364758D01*
G37*
G36*
G01X1346210Y514360D02*
X1345630Y514940D01*
Y519395D01*
X1341733D01*
Y520770D01*
X1353500D01*
X1353960Y520310D01*
Y514800D01*
X1353712Y514552D01*
X1353085D01*
X1352894Y514360D01*
X1346210D01*
G37*
G36*
G01X1383035Y514753D02*
Y514755D01*
X1381555Y516235D01*
Y517562D01*
X1381900Y517907D01*
X1388259D01*
X1388837Y517329D01*
Y509573D01*
X1388238Y508974D01*
X1383811D01*
X1383489Y509296D01*
Y514299D01*
X1383035Y514753D01*
G37*
G36*
G01X1364500Y523550D02*
X1364000Y524050D01*
Y532050D01*
X1363500Y532550D01*
X1349500D01*
X1349000Y533050D01*
Y536550D01*
X1351498Y539048D01*
X1351502D01*
Y541052D01*
X1351500D01*
Y541550D01*
X1352396Y542446D01*
X1380604D01*
X1381898Y541152D01*
Y534998D01*
X1380700Y533800D01*
Y530400D01*
X1379800Y529500D01*
X1379002D01*
Y529502D01*
X1373998D01*
Y529498D01*
X1373000Y528500D01*
X1372502D01*
Y528502D01*
X1370498D01*
Y528500D01*
X1370000D01*
X1368500Y527000D01*
Y524300D01*
X1367750Y523550D01*
X1364500D01*
G37*
G36*
G01X1383600Y482804D02*
G02X1383900Y482504I0J-300D01*
G02X1383600Y482204I-300J0D01*
G02X1383300Y482504I0J300D01*
G02X1383600Y482804I300J0D01*
G37*
G36*
G01X1383519Y487745D02*
G02X1383819Y487445I0J-300D01*
G02X1383519Y487145I-300J0D01*
G02X1383219Y487445I0J300D01*
G02X1383519Y487745I300J0D01*
G37*
G36*
G01X1386033Y499111D02*
G02X1386333Y498811I0J-300D01*
G02X1386033Y498511I-300J0D01*
G02X1385733Y498811I0J300D01*
G02X1386033Y499111I300J0D01*
G37*
G36*
G01X1386041Y494023D02*
G02X1386341Y493723I0J-300D01*
G02X1386041Y493423I-300J0D01*
G02X1385741Y493723I0J300D01*
G02X1386041Y494023I300J0D01*
G37*
G36*
G01X1365741Y493023D02*
G02X1366041Y492723I0J-300D01*
G02X1365741Y492423I-300J0D01*
G02X1365441Y492723I0J300D01*
G02X1365741Y493023I300J0D01*
G37*
G36*
G01X1363662Y486936D02*
G02X1363962Y486636I0J-300D01*
G02X1363662Y486336I-300J0D01*
G02X1363362Y486636I0J300D01*
G02X1363662Y486936I300J0D01*
G37*
G36*
G01X1363800Y481900D02*
G02X1364100Y481600I0J-300D01*
G02X1363800Y481300I-300J0D01*
G02X1363500Y481600I0J300D01*
G02X1363800Y481900I300J0D01*
G37*
G36*
G01X1357080Y505390D02*
X1355630D01*
X1355256Y505764D01*
Y506461D01*
X1355200Y506516D01*
Y507850D01*
X1354702Y508348D01*
Y508611D01*
X1353000Y510312D01*
Y513050D01*
X1353500Y513550D01*
X1355500D01*
X1356000Y513050D01*
Y510150D01*
X1357272Y508878D01*
Y505582D01*
X1357080Y505390D01*
G37*
G36*
G01X1367564Y509736D02*
X1366900Y510400D01*
X1359100D01*
X1359000Y510500D01*
Y514050D01*
X1358500Y514550D01*
X1355916D01*
X1355915Y514552D01*
X1355000D01*
Y520550D01*
X1367450D01*
X1370000Y523100D01*
Y526500D01*
X1370498Y526998D01*
X1372750D01*
X1373266Y526483D01*
X1387258D01*
X1387400Y526341D01*
Y522337D01*
G03Y522195I1450J-71D01*
G01Y519314D01*
X1387013Y518928D01*
X1381735D01*
X1381729Y518922D01*
X1381494D01*
X1380504Y517932D01*
Y511357D01*
X1380268Y511121D01*
X1376525D01*
X1375140Y509736D01*
X1367564D01*
G37*
G36*
G01X1411292Y569450D02*
X1413375Y567367D01*
Y557093D01*
X1412312Y556030D01*
X1401883D01*
X1400964Y556949D01*
Y558200D01*
X1402100Y559336D01*
Y560900D01*
X1397800Y565200D01*
X1397783D01*
Y576754D01*
X1398449Y577420D01*
X1410219D01*
X1411292Y576347D01*
Y569450D01*
G37*
G36*
G01X1356904Y552421D02*
X1355427Y553898D01*
Y557733D01*
X1357122Y559428D01*
Y560822D01*
X1359200Y562900D01*
Y583400D01*
X1356300Y586300D01*
Y591300D01*
X1359200Y594200D01*
Y615174D01*
X1360762Y616736D01*
Y620621D01*
X1361441Y621300D01*
X1368159D01*
X1369258Y620202D01*
X1369198D01*
Y618198D01*
X1369303D01*
Y615596D01*
X1369810Y615089D01*
X1369824Y615064D01*
G03X1370300Y614544I1277J691D01*
G01Y610600D01*
X1370750Y610150D01*
X1376350D01*
X1376900Y609600D01*
Y603900D01*
X1376100Y603100D01*
X1369000D01*
X1367800Y601900D01*
Y591314D01*
X1367790D01*
Y589312D01*
X1367800D01*
Y588593D01*
X1368398Y587994D01*
Y586054D01*
X1368433D01*
Y585612D01*
X1369398Y584646D01*
Y584234D01*
X1370038Y583594D01*
G03X1370300Y583385I1062J1062D01*
G01Y579200D01*
X1370500Y579000D01*
X1376727D01*
X1376935Y578792D01*
Y572096D01*
X1376839Y572000D01*
X1368500D01*
X1367700Y571200D01*
Y558403D01*
X1367528Y558231D01*
Y554886D01*
X1367481Y554839D01*
Y552518D01*
X1367384Y552421D01*
X1356904D01*
G37*
G36*
G01X1366459Y550889D02*
G02X1366759Y550589I0J-300D01*
G02X1366459Y550289I-300J0D01*
G02X1366159Y550589I0J300D01*
G02X1366459Y550889I300J0D01*
G37*
G36*
G01X1363568D02*
G02X1363868Y550589I0J-300D01*
G02X1363568Y550289I-300J0D01*
G02X1363268Y550589I0J300D01*
G02X1363568Y550889I300J0D01*
G37*
G36*
G01X1382139Y529530D02*
X1382000Y529669D01*
Y533400D01*
X1382900Y534300D01*
Y541751D01*
X1383712Y542563D01*
X1387638D01*
X1388200Y542001D01*
Y537616D01*
X1387698Y537115D01*
Y531385D01*
X1388200Y530884D01*
Y529800D01*
X1387930Y529530D01*
X1382139D01*
G37*
G36*
G01X1406099Y538030D02*
X1403264D01*
X1402600Y537367D01*
Y535000D01*
X1401042Y533442D01*
X1393842D01*
X1392750Y532350D01*
Y531250D01*
X1392450Y530950D01*
X1389550D01*
X1388700Y531800D01*
Y536700D01*
X1388800Y536800D01*
X1392400D01*
X1393700Y535500D01*
X1400700D01*
X1401404Y536204D01*
Y537967D01*
X1402337Y538900D01*
X1406066D01*
X1406308Y538658D01*
Y538240D01*
X1406099Y538030D01*
G37*
G36*
G01X1369390Y552172D02*
X1368986Y552576D01*
Y554448D01*
X1368906D01*
Y555888D01*
X1368924Y555906D01*
X1369036D01*
Y557908D01*
X1369000D01*
Y570100D01*
X1369400Y570500D01*
X1376600D01*
X1376800Y570300D01*
Y565300D01*
X1377600Y564500D01*
X1381804D01*
X1382911Y563392D01*
X1383208D01*
X1383300Y563300D01*
X1387316D01*
Y563009D01*
X1390196Y560128D01*
X1391143D01*
G03X1392248Y563577I1247J1502D01*
G02X1391936Y564259I-30J399D01*
G01X1393750Y566073D01*
Y576611D01*
X1390997Y579364D01*
Y583923D01*
X1388907Y586013D01*
X1386686D01*
Y586724D01*
X1383684D01*
X1383438Y586622D01*
X1381488Y588572D01*
X1370098D01*
X1369307Y589362D01*
Y592158D01*
X1369100Y592365D01*
Y601200D01*
X1369500Y601600D01*
X1376223D01*
X1376672Y601151D01*
Y595293D01*
X1376773Y595192D01*
X1382161D01*
X1383353Y594000D01*
X1383386D01*
X1383387Y593998D01*
X1386302D01*
X1387248Y593052D01*
Y590820D01*
X1387580Y590488D01*
X1393540D01*
X1395352Y592300D01*
X1426300D01*
X1437220Y603220D01*
Y612901D01*
X1438051Y613732D01*
X1462500D01*
X1463600Y612632D01*
Y609390D01*
X1461300Y607090D01*
Y603760D01*
X1459066Y601526D01*
Y595841D01*
X1455024Y591799D01*
X1446099D01*
X1444800Y590500D01*
Y586500D01*
X1444796Y586496D01*
Y584307D01*
X1444286Y583797D01*
X1438219D01*
X1436912Y582490D01*
Y580207D01*
X1435605Y578900D01*
X1424283D01*
G02X1423898Y579408I0J400D01*
G03X1421102I-1398J392D01*
G02X1420717Y578900I-385J-108D01*
G01X1416583D01*
G02X1416198Y579408I0J400D01*
G03X1413402I-1398J392D01*
G02X1413017Y578900I-385J-108D01*
G01X1398114D01*
X1396749Y577535D01*
Y570287D01*
X1396782Y570254D01*
Y564198D01*
X1396818D01*
Y560359D01*
X1394525Y558066D01*
Y555275D01*
X1394250Y555000D01*
X1374841D01*
X1372013Y552172D01*
X1369390D01*
G37*
G36*
G01X1407734Y47508D02*
X1406000Y49242D01*
Y71600D01*
X1406900Y72500D01*
X1416340D01*
X1417470Y71370D01*
Y66103D01*
X1419303Y64270D01*
X1420033Y62637D01*
Y48410D01*
X1419143Y47520D01*
X1412599D01*
X1412587Y47508D01*
X1407734D01*
G37*
G36*
G01X1419343Y310952D02*
G02X1419643Y310652I0J-300D01*
G02X1419343Y310352I-300J0D01*
G02X1419043Y310652I0J300D01*
G02X1419343Y310952I300J0D01*
G37*
G36*
G01X1413983Y304945D02*
G02X1414283Y304645I0J-300D01*
G02X1413983Y304345I-300J0D01*
G02X1413683Y304645I0J300D01*
G02X1413983Y304945I300J0D01*
G37*
G36*
G01X1419283Y304870D02*
G02X1419583Y304570I0J-300D01*
G02X1419283Y304270I-300J0D01*
G02X1418983Y304570I0J300D01*
G02X1419283Y304870I300J0D01*
G37*
G36*
G01X1413943Y310928D02*
G02X1414243Y310628I0J-300D01*
G02X1413943Y310328I-300J0D01*
G02X1413643Y310628I0J300D01*
G02X1413943Y310928I300J0D01*
G37*
G36*
G01D02*
G02X1414243Y310628I0J-300D01*
G02X1413943Y310328I-300J0D01*
G02X1413643Y310628I0J300D01*
G02X1413943Y310928I300J0D01*
G37*
G36*
G01X1410550Y321100D02*
G02X1410850Y320800I0J-300D01*
G02X1410550Y320500I-300J0D01*
G02X1410250Y320800I0J300D01*
G02X1410550Y321100I300J0D01*
G37*
G36*
G01X1410800Y316400D02*
G02X1411100Y316100I0J-300D01*
G02X1410800Y315800I-300J0D01*
G02X1410500Y316100I0J300D01*
G02X1410800Y316400I300J0D01*
G37*
G36*
G01X1408760Y304937D02*
G02X1409060Y304637I0J-300D01*
G02X1408760Y304337I-300J0D01*
G02X1408460Y304637I0J300D01*
G02X1408760Y304937I300J0D01*
G37*
G36*
G01X1408580Y310932D02*
G02X1408880Y310632I0J-300D01*
G02X1408580Y310332I-300J0D01*
G02X1408280Y310632I0J300D01*
G02X1408580Y310932I300J0D01*
G37*
G36*
G01X1467485Y338189D02*
G03I-12800J0D01*
G37*
G36*
G01X1437887Y407816D02*
X1440936D01*
X1441507Y407245D01*
X1441447Y407118D01*
G03X1442830Y404946I1383J-646D01*
G01X1445800D01*
Y404286D01*
X1445796D01*
Y401996D01*
X1444900Y401100D01*
X1438000D01*
X1437764Y401335D01*
Y407693D01*
X1437887Y407816D01*
G37*
G36*
G01X1448155Y400858D02*
X1447778Y401235D01*
X1447798Y401284D01*
Y404286D01*
X1447700D01*
Y404946D01*
X1454000D01*
Y401432D01*
X1453426Y400858D01*
X1448155D01*
G37*
G36*
G01X1448360Y426629D02*
X1447900Y427089D01*
Y429084D01*
X1448318Y429502D01*
X1452406D01*
X1452868Y429040D01*
Y427581D01*
X1452568Y427280D01*
X1450558D01*
Y426629D01*
X1448360D01*
G37*
G36*
G01X1411900Y435075D02*
G02X1412200Y434775I0J-300D01*
G02X1411900Y434475I-300J0D01*
G02X1411600Y434775I0J300D01*
G02X1411900Y435075I300J0D01*
G37*
G36*
G01X1413075Y457861D02*
G02X1413375Y457561I0J-300D01*
G02X1413075Y457261I-300J0D01*
G02X1412775Y457561I0J300D01*
G02X1413075Y457861I300J0D01*
G37*
G36*
G01X1413300Y454700D02*
G02X1413600Y454400I0J-300D01*
G02X1413300Y454100I-300J0D01*
G02X1413000Y454400I0J300D01*
G02X1413300Y454700I300J0D01*
G37*
G36*
G01X1459200Y460100D02*
G02X1459500Y459800I0J-300D01*
G02X1459200Y459500I-300J0D01*
G02X1458900Y459800I0J300D01*
G02X1459200Y460100I300J0D01*
G37*
G36*
G01X1451400D02*
G02X1451700Y459800I0J-300D01*
G02X1451400Y459500I-300J0D01*
G02X1451100Y459800I0J300D01*
G02X1451400Y460100I300J0D01*
G37*
G36*
G01Y454400D02*
G02X1451700Y454100I0J-300D01*
G02X1451400Y453800I-300J0D01*
G02X1451100Y454100I0J300D01*
G02X1451400Y454400I300J0D01*
G37*
G36*
G01X1459200D02*
G02X1459500Y454100I0J-300D01*
G02X1459200Y453800I-300J0D01*
G02X1458900Y454100I0J300D01*
G02X1459200Y454400I300J0D01*
G37*
G36*
G01X1459000Y450297D02*
G02X1459300Y449997I0J-300D01*
G02X1459000Y449697I-300J0D01*
G02X1458700Y449997I0J300D01*
G02X1459000Y450297I300J0D01*
G37*
G36*
G01X1429100Y453700D02*
G02X1429400Y453400I0J-300D01*
G02X1429100Y453100I-300J0D01*
G02X1428800Y453400I0J300D01*
G02X1429100Y453700I300J0D01*
G37*
G36*
G01X1429000Y448300D02*
G02X1429300Y448000I0J-300D01*
G02X1429000Y447700I-300J0D01*
G02X1428700Y448000I0J300D01*
G02X1429000Y448300I300J0D01*
G37*
G36*
G01Y442900D02*
G02X1429300Y442600I0J-300D01*
G02X1429000Y442300I-300J0D01*
G02X1428700Y442600I0J300D01*
G02X1429000Y442900I300J0D01*
G37*
G36*
G01Y437359D02*
G02X1429300Y437059I0J-300D01*
G02X1429000Y436759I-300J0D01*
G02X1428700Y437059I0J300D01*
G02X1429000Y437359I300J0D01*
G37*
G36*
G01X1445000Y437300D02*
G02X1445300Y437000I0J-300D01*
G02X1445000Y436700I-300J0D01*
G02X1444700Y437000I0J300D01*
G02X1445000Y437300I300J0D01*
G37*
G36*
G01X1444800Y442800D02*
G02X1445100Y442500I0J-300D01*
G02X1444800Y442200I-300J0D01*
G02X1444500Y442500I0J300D01*
G02X1444800Y442800I300J0D01*
G37*
G36*
G01X1444500Y448300D02*
G02X1444800Y448000I0J-300D01*
G02X1444500Y447700I-300J0D01*
G02X1444200Y448000I0J300D01*
G02X1444500Y448300I300J0D01*
G37*
G36*
G01X1411900Y430075D02*
G02X1412200Y429775I0J-300D01*
G02X1411900Y429475I-300J0D01*
G02X1411600Y429775I0J300D01*
G02X1411900Y430075I300J0D01*
G37*
G36*
G01X1403998D02*
G02X1404298Y429775I0J-300D01*
G02X1403998Y429475I-300J0D01*
G02X1403698Y429775I0J300D01*
G02X1403998Y430075I300J0D01*
G37*
G36*
G01Y435075D02*
G02X1404298Y434775I0J-300D01*
G02X1403998Y434475I-300J0D01*
G02X1403698Y434775I0J300D01*
G02X1403998Y435075I300J0D01*
G37*
G36*
G01X1405375Y453861D02*
G02X1405675Y453561I0J-300D01*
G02X1405375Y453261I-300J0D01*
G02X1405075Y453561I0J300D01*
G02X1405375Y453861I300J0D01*
G37*
G36*
G01X1405608Y457061D02*
G02X1405908Y456761I0J-300D01*
G02X1405608Y456461I-300J0D01*
G02X1405308Y456761I0J300D01*
G02X1405608Y457061I300J0D01*
G37*
G36*
G01X1448639Y517261D02*
X1448400Y517500D01*
Y522260D01*
X1452405Y526266D01*
X1452681D01*
X1455770Y529354D01*
X1463004D01*
X1463950Y530300D01*
Y534350D01*
X1464100Y534500D01*
X1471261D01*
X1471411Y534350D01*
X1471848D01*
Y534348D01*
X1476852D01*
Y534352D01*
X1476932Y534432D01*
Y535714D01*
X1477268Y536050D01*
X1485948D01*
Y536048D01*
X1488952D01*
Y536050D01*
X1497650D01*
X1497675Y536025D01*
X1503325D01*
X1506183Y538883D01*
Y543949D01*
X1506768Y544534D01*
Y544756D01*
X1506767Y544757D01*
Y550181D01*
X1505550Y551398D01*
X1505552D01*
Y554402D01*
X1505550D01*
Y556548D01*
X1505552D01*
Y561148D01*
X1500274Y566426D01*
X1441040D01*
X1438461Y569005D01*
Y581759D01*
X1438771Y582069D01*
X1445083D01*
X1446500Y583486D01*
Y588022D01*
X1448696Y590218D01*
X1455387D01*
X1461157Y595988D01*
Y602037D01*
X1464870Y605750D01*
X1465498D01*
Y605748D01*
X1467502D01*
Y605750D01*
X1468753D01*
X1469252Y606248D01*
X1474348D01*
X1474600Y606500D01*
Y609900D01*
X1474200Y610300D01*
X1471100D01*
X1470900Y610500D01*
Y611400D01*
X1471000Y611500D01*
X1474500D01*
X1474700Y611700D01*
Y612700D01*
X1474781Y612781D01*
X1481630D01*
X1481800Y612611D01*
Y605112D01*
X1482670Y604242D01*
X1482673D01*
X1483324Y603591D01*
X1492923D01*
X1493825Y604493D01*
X1500303D01*
X1501247Y605438D01*
X1503270D01*
X1503978D01*
X1505840Y607300D01*
X1510300D01*
X1510400Y607400D01*
Y611700D01*
X1510300Y611800D01*
X1506600D01*
X1506500Y611900D01*
Y612500D01*
X1506600Y612600D01*
X1510100D01*
X1510400Y612900D01*
Y613700D01*
X1510600Y613900D01*
X1517200D01*
X1517300Y613800D01*
Y605900D01*
X1518600Y604600D01*
X1531750D01*
X1533500Y602850D01*
Y598396D01*
G03X1533252Y597964I1467J-1129D01*
G03X1533123Y597429I1716J-697D01*
G03X1533416Y596258I1845J-161D01*
G01Y582142D01*
G03X1533822Y581096I1550J0D01*
G01Y565938D01*
X1533085Y565202D01*
X1523865D01*
X1523857Y565193D01*
X1522660D01*
X1517567Y560100D01*
Y555348D01*
X1517620Y555295D01*
Y547680D01*
X1521003Y544297D01*
X1529933D01*
X1529960Y544270D01*
Y533119D01*
X1528920Y532079D01*
X1523262D01*
X1513683Y522500D01*
X1499300D01*
X1497530Y524270D01*
X1488650D01*
X1487555Y523175D01*
X1481085D01*
X1480460Y523800D01*
X1476900D01*
X1475700Y522600D01*
X1462600D01*
X1457261Y517261D01*
X1448639D01*
G37*
G36*
G01X1415800Y477800D02*
G02X1416100Y477500I0J-300D01*
G02X1415800Y477200I-300J0D01*
G02X1415500Y477500I0J300D01*
G02X1415800Y477800I300J0D01*
G37*
G36*
G01X1415541Y489823D02*
G02X1415841Y489523I0J-300D01*
G02X1415541Y489223I-300J0D01*
G02X1415241Y489523I0J300D01*
G02X1415541Y489823I300J0D01*
G37*
G36*
G01X1416100Y483800D02*
G02X1416400Y483500I0J-300D01*
G02X1416100Y483200I-300J0D01*
G02X1415800Y483500I0J300D01*
G02X1416100Y483800I300J0D01*
G37*
G36*
G01X1415800Y495500D02*
G02X1416100Y495200I0J-300D01*
G02X1415800Y494900I-300J0D01*
G02X1415500Y495200I0J300D01*
G02X1415800Y495500I300J0D01*
G37*
G36*
G01X1451400Y465800D02*
G02X1451700Y465500I0J-300D01*
G02X1451400Y465200I-300J0D01*
G02X1451100Y465500I0J300D01*
G02X1451400Y465800I300J0D01*
G37*
G36*
G01X1459200D02*
G02X1459500Y465500I0J-300D01*
G02X1459200Y465200I-300J0D01*
G02X1458900Y465500I0J300D01*
G02X1459200Y465800I300J0D01*
G37*
G36*
G01X1439314Y478023D02*
G02X1439614Y477723I0J-300D01*
G02X1439314Y477423I-300J0D01*
G02X1439014Y477723I0J300D01*
G02X1439314Y478023I300J0D01*
G37*
G36*
G01X1439341Y489623D02*
G02X1439641Y489323I0J-300D01*
G02X1439341Y489023I-300J0D01*
G02X1439041Y489323I0J300D01*
G02X1439341Y489623I300J0D01*
G37*
G36*
G01X1439400Y495000D02*
G02X1439700Y494700I0J-300D01*
G02X1439400Y494400I-300J0D01*
G02X1439100Y494700I0J300D01*
G02X1439400Y495000I300J0D01*
G37*
G36*
G01X1457144Y511600D02*
X1449423D01*
X1448572Y512451D01*
Y514872D01*
X1448900Y515200D01*
X1457100D01*
X1462349Y520449D01*
X1463098D01*
Y520448D01*
X1466102D01*
Y520449D01*
X1468098D01*
Y520448D01*
X1471102D01*
Y520449D01*
X1475582D01*
X1476865Y521732D01*
X1481368D01*
X1485600Y517500D01*
Y514800D01*
X1481930Y511130D01*
X1473106D01*
X1473069Y511146D01*
G03X1471931I-569J-1336D01*
G01X1471894Y511130D01*
X1460531D01*
G02X1460186Y511733I0J400D01*
G03X1457531Y512101I-1251J737D01*
G02X1457144Y511600I-387J-101D01*
G37*
G36*
G01X1421560Y550955D02*
Y536955D01*
X1407560D01*
Y550955D01*
X1421560D01*
G37*
G36*
G01X1414800Y580100D02*
G02X1415100Y579800I0J-300D01*
G02X1414800Y579500I-300J0D01*
G02X1414500Y579800I0J300D01*
G02X1414800Y580100I300J0D01*
G37*
G36*
G01X1422500D02*
G02X1422800Y579800I0J-300D01*
G02X1422500Y579500I-300J0D01*
G02X1422200Y579800I0J300D01*
G02X1422500Y580100I300J0D01*
G37*
G36*
G01X1435200Y577000D02*
Y568800D01*
X1434400Y568000D01*
X1414940D01*
X1413582Y569358D01*
Y576535D01*
X1414747Y577700D01*
X1434500D01*
X1435200Y577000D01*
G37*
G36*
G01X1457980Y543830D02*
X1451908D01*
X1451586Y544152D01*
Y547446D01*
X1450673Y548359D01*
X1446339D01*
X1445365Y547385D01*
Y547186D01*
X1444578Y546399D01*
Y544915D01*
G03Y542485I1592J-1215D01*
G01Y540846D01*
X1445036Y540388D01*
X1444273Y539625D01*
Y538321D01*
X1447060Y535534D01*
X1450450D01*
X1450895Y535979D01*
Y537979D01*
X1451004Y538088D01*
X1452922D01*
X1453050Y537960D01*
Y535090D01*
X1453072Y535068D01*
Y534550D01*
X1452233Y533711D01*
X1443079D01*
X1442226Y534564D01*
Y547554D01*
G03Y549708I-974J1077D01*
G01Y550274D01*
X1441890Y550610D01*
Y559741D01*
X1442008Y559794D01*
G03X1442593Y561957I-599J1323D01*
G01X1442495Y562095D01*
X1445700Y565300D01*
X1460686D01*
X1462178Y563808D01*
X1500182D01*
X1503529Y560461D01*
Y556508D01*
X1503378Y556357D01*
Y551331D01*
X1503664Y551045D01*
Y540164D01*
X1502702Y539202D01*
X1498348D01*
Y539200D01*
X1495852D01*
Y539202D01*
X1490806D01*
X1489659Y538055D01*
X1485933D01*
X1485234Y537356D01*
X1469720D01*
X1469522Y537554D01*
X1464444D01*
X1464435Y537563D01*
X1463631D01*
X1463049Y538145D01*
Y540724D01*
X1462086Y541687D01*
X1460116D01*
X1459650Y542153D01*
Y542160D01*
X1457980Y543830D01*
G37*
G36*
G01X1465267Y614447D02*
X1463667Y616047D01*
X1440400D01*
X1440383Y616064D01*
X1438203D01*
X1437490Y616777D01*
Y622968D01*
X1439011Y624489D01*
X1465781D01*
X1466371Y623899D01*
Y617438D01*
X1467303Y616506D01*
X1467661D01*
X1467979Y616188D01*
Y614718D01*
X1467708Y614447D01*
X1465267D01*
G37*
G36*
G01X1504600Y77059D02*
X1503100Y78559D01*
Y85800D01*
X1503404Y86104D01*
X1507076D01*
G03X1508120Y86500I-1J1577D01*
G01X1515368D01*
X1515630Y86238D01*
Y78290D01*
X1514443Y77103D01*
X1513107D01*
X1513063Y77059D01*
X1504600D01*
G37*
G36*
G01X1513068Y158548D02*
X1512494D01*
X1511665Y157719D01*
Y156392D01*
X1512012Y156045D01*
Y152254D01*
X1511899Y152141D01*
X1507618D01*
X1507586Y152152D01*
G03X1507076Y152238I-512J-1479D01*
G01X1504190D01*
Y155980D01*
X1502143Y158027D01*
X1502151Y158119D01*
G03X1499418Y158908I-1448J114D01*
G02X1498781Y158812I-354J187D01*
G01X1498166Y159426D01*
Y160792D01*
G03X1496466Y163104I-672J1287D01*
G02X1495900I-283J283D01*
G01X1494739Y164264D01*
X1493308D01*
Y165656D01*
X1494307Y166655D01*
X1503071D01*
X1503231Y166495D01*
Y163723D01*
X1503988Y162966D01*
X1504338D01*
X1504340Y162963D01*
X1512489D01*
X1513416Y162036D01*
Y158896D01*
X1513068Y158548D01*
G37*
G36*
G01X1500775Y98401D02*
G02X1501075Y98101I0J-300D01*
G02X1500775Y97801I-300J0D01*
G02X1500475Y98101I0J300D01*
G02X1500775Y98401I300J0D01*
G37*
G36*
G01X1501700Y103600D02*
G02X1502000Y103300I0J-300D01*
G02X1501700Y103000I-300J0D01*
G02X1501400Y103300I0J300D01*
G02X1501700Y103600I300J0D01*
G37*
G36*
G01X1501603Y108800D02*
G02X1501903Y108500I0J-300D01*
G02X1501603Y108200I-300J0D01*
G02X1501303Y108500I0J300D01*
G02X1501603Y108800I300J0D01*
G37*
G36*
G01X1497699Y112440D02*
G02X1497999Y112140I0J-300D01*
G02X1497699Y111840I-300J0D01*
G02X1497399Y112140I0J300D01*
G02X1497699Y112440I300J0D01*
G37*
G36*
G01X1499618Y124820D02*
G02X1499918Y124520I0J-300D01*
G02X1499618Y124220I-300J0D01*
G02X1499318Y124520I0J300D01*
G02X1499618Y124820I300J0D01*
G37*
G36*
G01X1482300Y118700D02*
G02X1482600Y118400I0J-300D01*
G02X1482300Y118100I-300J0D01*
G02X1482000Y118400I0J300D01*
G02X1482300Y118700I300J0D01*
G37*
G36*
G01X1483093Y131096D02*
G02X1483393Y130796I0J-300D01*
G02X1483093Y130496I-300J0D01*
G02X1482793Y130796I0J300D01*
G02X1483093Y131096I300J0D01*
G37*
G36*
G01X1523719Y149788D02*
G02X1524019Y149488I0J-300D01*
G02X1523719Y149188I-300J0D01*
G02X1523419Y149488I0J300D01*
G02X1523719Y149788I300J0D01*
G37*
G36*
G01X1526914Y244150D02*
X1524937Y246128D01*
X1520414D01*
G03X1517939Y244690I-1114J-931D01*
G02X1517564Y244150I-375J-140D01*
G01X1517049D01*
X1516800Y244400D01*
Y255300D01*
X1517500Y256000D01*
X1529376D01*
X1529638Y255738D01*
X1530262D01*
X1530500Y255500D01*
Y252937D01*
X1531468Y251968D01*
X1532761D01*
X1532898Y251831D01*
Y251748D01*
X1532980D01*
X1532982Y251747D01*
X1535084D01*
X1535140Y251691D01*
Y246240D01*
X1533050Y244150D01*
X1526914D01*
G37*
G36*
G01X1542680Y258010D02*
X1542602Y258088D01*
Y261715D01*
X1542530Y261786D01*
Y262448D01*
X1542486Y262492D01*
X1540168D01*
X1540002Y262658D01*
Y263443D01*
X1540000Y263444D01*
Y263794D01*
X1540002Y263795D01*
Y267313D01*
X1540000Y267314D01*
Y267700D01*
X1539854Y267846D01*
X1539853D01*
X1539778Y267921D01*
X1539393D01*
X1539315Y268000D01*
X1534440D01*
X1531470Y270970D01*
X1531344D01*
X1531313Y271002D01*
X1511498D01*
X1509800Y272700D01*
Y280600D01*
X1511100Y281900D01*
X1517600D01*
X1518785Y280715D01*
X1535000D01*
X1535100Y280615D01*
Y275400D01*
X1539950Y270550D01*
X1542504D01*
X1542515Y270561D01*
Y271199D01*
X1542602Y271285D01*
Y274917D01*
X1545398D01*
Y271285D01*
X1545492Y271192D01*
Y270550D01*
X1545501Y270541D01*
X1547824D01*
X1548000Y270365D01*
Y262500D01*
X1547969Y262469D01*
X1545500D01*
X1545476Y262445D01*
Y261792D01*
X1545394Y261711D01*
Y258141D01*
X1545264Y258010D01*
X1542680D01*
G37*
G36*
G01X1514454Y243162D02*
X1514290D01*
X1513798Y243654D01*
X1511545D01*
G02X1511168Y244189I0J400D01*
G03X1510863Y245665I-1368J487D01*
G02X1510866Y246214I292J273D01*
G03X1509246Y248551I-1052J1001D01*
G02X1508690Y248920I-156J368D01*
G01Y254516D01*
X1509270Y255096D01*
X1514504D01*
X1515650Y253950D01*
Y244150D01*
X1515442D01*
X1514454Y243162D01*
G37*
G36*
G01X1533089Y260122D02*
X1530992D01*
X1528870Y258000D01*
X1514502D01*
Y258102D01*
X1511132D01*
G02X1510735Y258547I0J400D01*
G03X1509478Y262954I-5963J682D01*
G01Y266781D01*
G03X1512568Y270000I-2475J5468D01*
G01X1530898D01*
X1533900Y266998D01*
X1538900D01*
X1539000Y266898D01*
Y264210D01*
X1538913Y264123D01*
X1534855D01*
X1534427Y263695D01*
Y260558D01*
X1533977Y260108D01*
X1533103D01*
X1533089Y260122D01*
G37*
G36*
G01X1526722Y295700D02*
G02X1527022Y295400I0J-300D01*
G02X1526722Y295100I-300J0D01*
G02X1526422Y295400I0J300D01*
G02X1526722Y295700I300J0D01*
G37*
G36*
G01X1511900Y287800D02*
G02X1512200Y287500I0J-300D01*
G02X1511900Y287200I-300J0D01*
G02X1511600Y287500I0J300D01*
G02X1511900Y287800I300J0D01*
G37*
G36*
G01X1519369Y338060D02*
X1517578Y339852D01*
X1516848D01*
X1515200Y341500D01*
X1511282D01*
X1511254Y341508D01*
G03X1510448I-403J-1395D01*
G01X1510420Y341500D01*
X1509000D01*
X1508492Y340992D01*
X1505464D01*
X1505057Y340585D01*
X1504810Y340687D01*
Y340742D01*
X1503923Y341630D01*
Y344670D01*
X1504002Y344748D01*
X1506002D01*
Y344749D01*
X1506998D01*
Y344748D01*
X1509002D01*
Y344749D01*
X1509998D01*
Y344748D01*
X1512002D01*
Y344749D01*
X1512998D01*
Y344748D01*
X1515002D01*
Y344749D01*
X1515998D01*
Y344748D01*
X1518002D01*
Y344749D01*
X1518998D01*
Y344748D01*
X1520998D01*
X1521127Y344619D01*
Y340127D01*
X1520746Y339746D01*
Y338291D01*
X1520516Y338060D01*
X1519369D01*
G37*
G36*
G01X1541923Y450918D02*
G03X1541145Y450030I352J-1093D01*
G02X1540741Y449701I-394J71D01*
G03X1540659I-41J-1451D01*
G02X1540255Y450030I-10J400D01*
G03X1537995I-1130J-205D01*
G02X1537591Y449701I-394J71D01*
G03X1537509I-41J-1451D01*
G02X1537105Y450030I-10J400D01*
G03X1534845I-1130J-205D01*
G02X1534441Y449701I-394J71D01*
G03X1534359I-41J-1451D01*
G02X1533955Y450030I-10J400D01*
G03X1531695I-1130J-205D01*
G02X1531291Y449701I-394J71D01*
G03X1531209I-41J-1451D01*
G02X1530805Y450030I-10J400D01*
G03X1528528Y449882I-1130J-204D01*
G02X1528129Y449502I-399J20D01*
G01X1528071D01*
G02X1527672Y449882I0J400D01*
G03X1525395Y450030I-1147J-56D01*
G02X1524991Y449701I-394J71D01*
G03X1524840Y449698I-47J-1451D01*
G02X1524625Y449887I-15J200D01*
G03X1524533Y450301I-1250J-61D01*
G01X1524518Y450337D01*
Y451332D01*
X1524566Y451381D01*
Y452376D01*
X1524672Y452481D01*
Y453492D01*
X1524778Y453598D01*
X1525197D01*
X1525437Y453358D01*
X1525410Y453249D01*
G03X1527364Y452191I1115J-274D01*
G02X1527939Y452201I292J-273D01*
G01X1528298Y451842D01*
X1528350Y451790D01*
X1529255D01*
X1529323Y451722D01*
X1530156D01*
X1530344Y451910D01*
X1532165D01*
X1532210Y451884D01*
G03X1532369Y451809I612J1092D01*
G01X1532408Y451794D01*
X1532482Y451720D01*
X1533313D01*
X1533530Y451937D01*
X1535264D01*
X1535479Y451722D01*
X1535625D01*
X1535626Y451721D01*
X1536459D01*
X1536651Y451913D01*
X1538460D01*
X1538506Y451887D01*
G03X1538671Y451808I622J1087D01*
G01X1538710Y451793D01*
X1538784Y451719D01*
X1539597D01*
X1539786Y451908D01*
X1541604D01*
X1541748Y451764D01*
X1541901D01*
X1542084Y451581D01*
G02X1541923Y450918I-283J-282D01*
G37*
G36*
G01X1524000Y409500D02*
X1523500Y410000D01*
X1523164D01*
X1523000Y410164D01*
Y410477D01*
G02X1523394Y410877I400J0D01*
G03X1524505Y411820I-19J1148D01*
G02X1524909Y412149I394J-71D01*
G03X1524991I41J1451D01*
G02X1525395Y411820I10J-400D01*
G03X1527666Y411894I1130J204D01*
G02X1528071Y412248I397J-46D01*
G03X1528129I29J1452D01*
G02X1528534Y411894I8J-400D01*
G03X1530822Y412081I1141J131D01*
G02X1531221Y412500I399J19D01*
G01X1531279D01*
G02X1531678Y412081I0J-400D01*
G03X1533939Y411747I1147J-57D01*
G02X1534343Y412049I388J-98D01*
G03X1534457I57J1451D01*
G02X1534861Y411747I16J-400D01*
G03X1537105Y411820I1114J278D01*
G02X1537509Y412149I394J-71D01*
G03X1537591I41J1451D01*
G02X1537995Y411820I10J-400D01*
G03X1540255I1130J205D01*
G02X1540659Y412149I394J-71D01*
G03X1540741I41J1451D01*
G02X1541145Y411820I10J-400D01*
G03X1541826Y410969I1129J206D01*
G02X1541952Y410318I-157J-368D01*
G01X1541728Y410094D01*
X1541614D01*
X1541455Y409935D01*
X1538856D01*
X1538791Y410000D01*
X1538790D01*
X1538655Y410135D01*
X1537788D01*
X1537653Y410000D01*
X1534871D01*
X1534751Y410120D01*
X1533889D01*
X1533769Y410000D01*
X1531013D01*
X1530892Y410121D01*
X1529949D01*
X1529828Y410000D01*
X1527135D01*
X1527014Y410121D01*
X1525133D01*
X1525012Y410000D01*
X1525000D01*
X1524500Y409500D01*
X1524000D01*
G37*
G36*
G01X1507538Y455000D02*
X1512500D01*
X1513131Y454369D01*
G02X1513126Y453799I-283J-283D01*
G03X1513638Y451863I799J-824D01*
G02X1513938Y451460I-99J-387D01*
G03Y451340I1451J-60D01*
G02X1513638Y450937I-399J-16D01*
G03X1513720Y448695I286J-1112D01*
G02X1514049Y448291I-71J-394D01*
G03Y448209I1451J-41D01*
G02X1513720Y447805I-400J-10D01*
G03X1514980Y446223I205J-1130D01*
G02X1515631Y446349I368J-157D01*
G01X1516167Y445813D01*
X1516169Y445811D01*
G03X1516211Y445769I906J864D01*
G01X1516213Y445767D01*
X1516608Y445372D01*
X1519628D01*
X1519810Y445190D01*
G02X1519708Y444550I-283J-283D01*
G03X1521102Y442784I517J-1025D01*
G02X1521691Y442809I306J-258D01*
G01X1522000Y442500D01*
X1522084D01*
X1522085Y442498D01*
X1522658D01*
G03X1524092I717J1027D01*
G01X1525808D01*
G03X1527242I717J1027D01*
G01X1528958D01*
G03X1530392I717J1027D01*
G01X1532108D01*
G03X1533542I717J1027D01*
G01X1535258D01*
G03X1536692I717J1027D01*
G01X1538408D01*
G03X1539842I717J1027D01*
G01X1541558D01*
G03X1542066Y442291I715J1028D01*
G02X1542399Y441908I-67J-395D01*
G03X1542412Y441749I1451J39D01*
G02X1542223Y441522I-198J-27D01*
G03X1541145Y440580I52J-1147D01*
G02X1540741Y440251I-394J71D01*
G03X1540659I-41J-1451D01*
G02X1540255Y440580I-10J400D01*
G03X1537995I-1130J-205D01*
G02X1537591Y440251I-394J71D01*
G03X1537509I-41J-1451D01*
G02X1537105Y440580I-10J400D01*
G03X1534845I-1130J-205D01*
G02X1534441Y440251I-394J71D01*
G03X1534359I-41J-1451D01*
G02X1533955Y440580I-10J400D01*
G03X1531695I-1130J-205D01*
G02X1531291Y440251I-394J71D01*
G03X1531209I-41J-1451D01*
G02X1530805Y440580I-10J400D01*
G03X1528527Y440395I-1130J-204D01*
G02X1528127Y440002I-400J7D01*
G01X1528073D01*
G02X1527673Y440395I0J400D01*
G03X1525395Y440580I-1148J-19D01*
G02X1524991Y440251I-394J71D01*
G03X1524909I-41J-1451D01*
G02X1524505Y440580I-10J400D01*
G03X1523301Y439229I-1130J-205D01*
G02X1523488Y439030I-13J-199D01*
G01Y438570D01*
G02X1523301Y438371I-200J0D01*
G03Y436079I74J-1146D01*
G02X1523488Y435880I-13J-199D01*
G01Y435420D01*
G02X1523301Y435221I-200J0D01*
G03Y432929I74J-1146D01*
G02X1523488Y432730I-13J-199D01*
G01Y432270D01*
G02X1523301Y432071I-200J0D01*
G03Y429779I74J-1146D01*
G02X1523488Y429580I-13J-199D01*
G01Y429120D01*
G02X1523301Y428921I-200J0D01*
G03Y426629I74J-1146D01*
G02X1523488Y426430I-13J-199D01*
G01Y425970D01*
G02X1523301Y425771I-200J0D01*
G03Y423479I74J-1146D01*
G02X1523488Y423280I-13J-199D01*
G01Y422820D01*
G02X1523301Y422621I-200J0D01*
G03X1522245Y421680I74J-1146D01*
G02X1521841Y421351I-394J71D01*
G03X1521759I-41J-1451D01*
G02X1521355Y421680I-10J400D01*
G03X1520966Y422352I-1130J-205D01*
G02X1520941Y422941I258J306D01*
G01X1521500Y423500D01*
Y423584D01*
X1521502Y423585D01*
Y438154D01*
X1521500Y438155D01*
Y438500D01*
X1521019Y438981D01*
G02X1521024Y439551I283J283D01*
G03X1519401Y441174I-799J824D01*
G02X1518831Y441169I-287J278D01*
G01X1517869Y442131D01*
G02X1517874Y442701I283J283D01*
G03X1515945Y443730I-799J824D01*
G02X1515541Y443401I-394J71D01*
G03X1515459I-41J-1451D01*
G02X1515055Y443730I-10J400D01*
G03X1512795I-1130J-205D01*
G02X1512391Y443401I-394J71D01*
G03X1512309I-41J-1451D01*
G02X1511905Y443730I-10J400D01*
G03X1509645I-1130J-205D01*
G02X1509241Y443401I-394J71D01*
G03X1509159I-41J-1451D01*
G02X1508755Y443730I-10J400D01*
G03X1508364Y444403I-1129J-206D01*
G02X1508339Y444992I258J306D01*
G01X1508991Y445644D01*
X1509570D01*
X1509684Y445530D01*
X1510267D01*
X1510303Y445515D01*
G03X1511247I472J1160D01*
G01X1511283Y445530D01*
X1511775D01*
X1512232Y445987D01*
Y447768D01*
X1512036Y447964D01*
Y450964D01*
X1511491Y451509D01*
G02X1511516Y452098I283J283D01*
G03X1509662Y453258I-741J877D01*
G01X1509624Y453107D01*
X1508776D01*
X1508738Y453258D01*
G03X1506629Y453547I-1113J-283D01*
G02X1505970Y453496I-347J199D01*
G03X1505128Y453927I-898J-716D01*
G01X1505051Y453930D01*
X1504297Y454684D01*
Y454991D01*
X1504379Y455073D01*
X1506375D01*
X1506547Y454901D01*
X1507439D01*
X1507538Y455000D01*
G37*
G36*
G01X1506110Y409533D02*
G02X1505508Y409492I-319J242D01*
G01X1504900Y410100D01*
X1501900D01*
X1500677Y411323D01*
Y412177D01*
X1502032Y413532D01*
X1502766D01*
X1502813Y413578D01*
X1503858D01*
G02X1504172Y412931I0J-400D01*
G03X1505917Y411442I901J-711D01*
G02X1506553Y411378I294J-271D01*
G03X1506586Y411326I1073J645D01*
G01X1506620Y411276D01*
Y411247D01*
X1507095Y410772D01*
X1507462D01*
X1507748Y410486D01*
Y410354D01*
G02X1507265Y409963I-400J0D01*
G03X1506110Y409533I-240J-1123D01*
G37*
G36*
G01X1508795Y412488D02*
X1508739Y412597D01*
G03X1506664Y412828I-1114J-572D01*
G02X1506025Y412861I-307J256D01*
G03X1505230Y413357I-952J-641D01*
G02X1505002Y414036I55J396D01*
G01X1505889Y414923D01*
G02X1506548Y414778I283J-283D01*
G03X1508771Y415110I1077J397D01*
G01X1508782Y415298D01*
X1509164D01*
G03X1509236I36J1452D01*
G01X1509618D01*
X1509629Y415110D01*
G03X1511848Y414767I1146J65D01*
G02X1512489Y414923I374J-142D01*
G01X1512796D01*
X1512843Y414790D01*
G03X1513408Y414150I1082J385D01*
G02X1513510Y413510I-181J-357D01*
G01X1512500Y412500D01*
X1511826D01*
X1511769Y412600D01*
G03X1509775Y412590I-994J-575D01*
G01X1509718Y412488D01*
X1508795D01*
G37*
G36*
G01X1467000Y460100D02*
G02X1467300Y459800I0J-300D01*
G02X1467000Y459500I-300J0D01*
G02X1466700Y459800I0J300D01*
G02X1467000Y460100I300J0D01*
G37*
G36*
G01X1466800Y450297D02*
G02X1467100Y449997I0J-300D01*
G02X1466800Y449697I-300J0D01*
G02X1466500Y449997I0J300D01*
G02X1466800Y450297I300J0D01*
G37*
G36*
G01X1467000Y454400D02*
G02X1467300Y454100I0J-300D01*
G02X1467000Y453800I-300J0D01*
G02X1466700Y454100I0J300D01*
G02X1467000Y454400I300J0D01*
G37*
G36*
G01X1498964Y441998D02*
X1498718Y442244D01*
Y443384D01*
X1498719Y443395D01*
G03Y443697I-1444J151D01*
G01X1498718Y443708D01*
Y445077D01*
G02X1499141Y445476I400J0D01*
G03Y448376I84J1450D01*
G02X1498718Y448775I-23J399D01*
G01Y450152D01*
X1500071Y451505D01*
X1508005D01*
X1508500Y452000D01*
X1509500D01*
X1510143Y451357D01*
G02X1510097Y450751I-282J-283D01*
G03X1510645Y448684I678J-926D01*
G02X1511000Y448287I-45J-397D01*
G01Y448213D01*
G02X1510645Y447816I-400J0D01*
G03X1509636Y446821I130J-1141D01*
G01X1509614Y446646D01*
X1508786D01*
X1508764Y446821D01*
G03X1506529Y447017I-1139J-146D01*
G02X1505870Y446848I-382J119D01*
G03X1503959Y445749I-795J-828D01*
G01X1503986Y445640D01*
X1500344Y441998D01*
X1498964D01*
G37*
G36*
G01X1524536Y443500D02*
X1524513Y443674D01*
G03X1523748Y444611I-1138J-149D01*
G01X1523613Y444657D01*
Y445000D01*
X1524000D01*
X1525000Y446000D01*
Y446627D01*
X1525366D01*
X1525397Y446464D01*
G03Y446886I1128J211D01*
G01X1525366Y446723D01*
X1525000D01*
Y447000D01*
X1524000Y448000D01*
Y448500D01*
X1542498D01*
Y448023D01*
G02X1542295Y447823I-200J0D01*
G03X1542070Y445545I-21J-1148D01*
G02X1542399Y445141I-71J-394D01*
G03Y445059I1451J-41D01*
G02X1542070Y444655I-400J-10D01*
G03X1541137Y443674I205J-1130D01*
G01X1541114Y443500D01*
X1540286D01*
X1540263Y443674D01*
G03X1537987I-1138J-149D01*
G01X1537964Y443500D01*
X1537136D01*
X1537113Y443674D01*
G03X1534837I-1138J-149D01*
G01X1534814Y443500D01*
X1533986D01*
X1533963Y443674D01*
G03X1531687I-1138J-149D01*
G01X1531664Y443500D01*
X1530836D01*
X1530813Y443674D01*
G03X1528537I-1138J-149D01*
G01X1528514Y443500D01*
X1527686D01*
X1527663Y443674D01*
G03X1525387I-1138J-149D01*
G01X1525364Y443500D01*
X1524536D01*
G37*
G36*
G01X1525000Y422500D02*
X1524500Y423000D01*
Y424074D01*
X1524517Y424113D01*
G03Y425137I-1142J512D01*
G01X1524500Y425176D01*
Y427224D01*
X1524517Y427263D01*
G03X1524609Y427566I-1142J512D01*
G02X1524992Y427899I395J-67D01*
G03X1525151Y427912I-39J1451D01*
G02X1525378Y427723I27J-198D01*
G03X1526730Y428905I1147J52D01*
G02X1526401Y429309I71J394D01*
G03X1526398Y429460I-1451J47D01*
G02X1526587Y429675I200J15D01*
G03X1525291Y431134I-62J1250D01*
G02X1524908Y430801I-395J67D01*
G03X1524840Y430798I30J-1452D01*
G02X1524625Y430987I-15J200D01*
G03X1524517Y431437I-1250J-62D01*
G01X1524500Y431476D01*
Y433524D01*
X1524517Y433563D01*
G03Y434587I-1142J512D01*
G01X1524500Y434626D01*
Y436674D01*
X1524517Y436713D01*
G03Y437737I-1142J512D01*
G01X1524500Y437776D01*
Y438500D01*
X1525000Y439000D01*
X1534908D01*
Y438085D01*
X1534717Y437894D01*
Y436464D01*
X1535079Y436102D01*
Y435127D01*
X1534627Y434675D01*
Y432393D01*
X1535215Y431805D01*
X1535097Y431664D01*
G03X1536986Y431469I878J-739D01*
G01X1536916Y431600D01*
X1537226Y431910D01*
X1537692D01*
G02X1538062Y431359I0J-400D01*
G03X1540207Y431307I1063J-434D01*
G02X1540585Y431840I377J133D01*
G01X1540690D01*
X1541000Y431530D01*
Y423000D01*
X1540500Y422500D01*
X1539844D01*
G03X1538406I-719J-1025D01*
G01X1536694D01*
G03X1535256I-719J-1025D01*
G01X1533544D01*
G03X1532106I-719J-1025D01*
G01X1530394D01*
G03X1528956I-719J-1025D01*
G01X1527244D01*
G03X1525806I-719J-1025D01*
G01X1525000D01*
G37*
G36*
G01X1504953Y415403D02*
G02X1504271Y415664I-283J283D01*
G03X1503024Y416744I-1146J-64D01*
G02X1502606Y417024I-36J398D01*
G03X1502176Y417688I-1388J-427D01*
G01Y418176D01*
X1502500Y418500D01*
Y420859D01*
X1502515Y420896D01*
G03X1502585Y421105I-1338J564D01*
G02X1502830Y421251I194J-47D01*
G03X1503983Y423122I295J1109D01*
G02X1504032Y423700I299J266D01*
G03X1504535Y424485I-907J1135D01*
G02X1504780Y424631I194J-47D01*
G03X1504037Y426230I295J1109D01*
G02X1503768Y426136I-181J85D01*
G03X1502949Y426275I-642J-1302D01*
G02X1502500Y426672I-49J397D01*
G01Y427619D01*
X1502515Y427656D01*
G03X1502585Y427865I-1338J564D01*
G02X1502830Y428011I194J-47D01*
G03X1502958Y430256I295J1109D01*
G02X1502500Y430652I-58J396D01*
G01Y430769D01*
X1502765Y431034D01*
X1505515D01*
X1506904Y432423D01*
Y432561D01*
G02X1507387Y432952I400J0D01*
G03X1507181Y435134I238J1123D01*
G01X1507144Y435118D01*
X1506904D01*
Y435392D01*
X1506333Y435963D01*
X1506039D01*
X1506003Y435977D01*
G03X1504921I-541J-1347D01*
G01X1504885Y435963D01*
X1504803D01*
X1504716Y435876D01*
X1504696Y435864D01*
G03X1504591Y435792I768J-1233D01*
G02X1504271Y435941I-120J160D01*
G03X1502830Y436989I-1146J-61D01*
G02X1502585Y437135I-51J193D01*
G03X1502515Y437344I-1408J-355D01*
G01X1502500Y437381D01*
Y438328D01*
G02X1502949Y438725I400J0D01*
G03X1503768Y438864I177J1441D01*
G02X1504037Y438770I88J-179D01*
G03X1504780Y440369I1038J490D01*
G02X1504535Y440515I-51J193D01*
G03X1504190Y441153I-1409J-350D01*
G01X1504059Y441295D01*
X1505097Y442333D01*
X1507241D01*
X1507269Y442325D01*
G03X1507981I356J1200D01*
G01X1508009Y442333D01*
X1510391D01*
X1510419Y442325D01*
G03X1511131I356J1200D01*
G01X1511159Y442333D01*
X1513541D01*
X1513569Y442325D01*
G03X1514281I356J1200D01*
G01X1514309Y442333D01*
X1516133D01*
X1516512Y441954D01*
G02X1516448Y441336I-283J-283D01*
G03X1517965Y439650I627J-962D01*
G02X1518558Y439681I310J-252D01*
G01X1519531Y438708D01*
G02X1519500Y438115I-283J-283D01*
G03X1520132Y436081I725J-890D01*
G02X1520500Y435682I-32J-399D01*
G01Y435618D01*
G02X1520132Y435219I-400J0D01*
G03Y432931I93J-1144D01*
G02X1520500Y432532I-32J-399D01*
G01Y432468D01*
G02X1520132Y432069I-400J0D01*
G03Y429781I93J-1144D01*
G02X1520500Y429382I-32J-399D01*
G01Y429318D01*
G02X1520132Y428919I-400J0D01*
G03Y426631I93J-1144D01*
G02X1520500Y426232I-32J-399D01*
G01Y426168D01*
G02X1520132Y425769I-400J0D01*
G03X1519547Y423699I93J-1144D01*
G02X1519593Y423093I-236J-323D01*
G01X1518607Y422107D01*
G02X1518001Y422153I-283J282D01*
G03X1516397Y420549I-926J-678D01*
G02X1516443Y419943I-236J-323D01*
G01X1515457Y418957D01*
G02X1514851Y419003I-283J282D01*
G03X1513247Y417399I-926J-678D01*
G02X1513293Y416793I-236J-323D01*
G01X1512800Y416300D01*
X1511326D01*
X1511287Y416317D01*
G03X1510263I-512J-1142D01*
G01X1510224Y416300D01*
X1508176D01*
X1508137Y416317D01*
G03X1507113I-512J-1142D01*
G01X1507074Y416300D01*
X1505850D01*
X1504953Y415403D01*
G37*
G36*
G01X1467000Y465800D02*
G02X1467300Y465500I0J-300D01*
G02X1467000Y465200I-300J0D01*
G02X1466700Y465500I0J300D01*
G02X1467000Y465800I300J0D01*
G37*
G36*
G01X1520564Y547366D02*
X1519720Y548210D01*
Y550258D01*
X1519722D01*
Y553262D01*
X1519720D01*
Y559640D01*
X1524280Y564200D01*
X1533500D01*
X1534900Y565600D01*
Y582600D01*
X1535100Y582800D01*
X1549400D01*
X1551294Y580906D01*
X1554677D01*
X1555198Y580384D01*
Y577298D01*
X1555201D01*
Y570874D01*
X1554980Y570653D01*
Y550564D01*
X1551782Y547366D01*
X1520564D01*
G37*
G36*
G01X1535322Y608680D02*
Y606100D01*
X1536173Y605249D01*
X1538695D01*
X1538710Y605234D01*
Y603246D01*
X1538674Y603210D01*
X1535318D01*
X1533051Y605477D01*
X1533023D01*
X1532300Y606200D01*
X1519100D01*
X1518800Y606500D01*
Y613700D01*
X1519100Y614000D01*
X1524500D01*
X1524900Y614400D01*
Y617774D01*
X1530230D01*
X1530278Y617823D01*
X1532047D01*
X1532466Y617405D01*
Y615498D01*
X1532478D01*
Y613632D01*
X1533944Y612166D01*
G02X1533935Y611591I-283J-283D01*
G03X1534923Y609080I993J-1059D01*
G02X1535322Y608680I-1J-400D01*
G37*
G36*
G01X1492083Y604842D02*
X1483533D01*
X1483200Y605175D01*
Y612684D01*
X1483349Y612833D01*
X1488923D01*
X1489300Y613210D01*
Y616403D01*
X1489800Y616903D01*
X1496448D01*
X1499156Y614195D01*
Y607069D01*
X1498487Y606400D01*
X1493641D01*
X1492083Y604842D01*
G37*
G36*
G01X1533019Y619028D02*
X1532930Y619117D01*
Y621208D01*
X1532302Y621836D01*
X1529145D01*
X1528387Y621078D01*
X1524916D01*
X1524846Y621148D01*
Y624250D01*
X1525021Y624426D01*
X1533803D01*
X1534924Y623305D01*
Y619238D01*
X1534714Y619028D01*
X1533019D01*
G37*
G36*
G01X1544922Y86938D02*
Y85630D01*
X1544244Y84952D01*
X1544083Y85058D01*
X1541262Y85630D01*
X1536613Y84683D01*
X1534120Y85871D01*
X1533700Y86543D01*
Y87300D01*
X1533963Y87564D01*
X1540352D01*
Y87752D01*
X1540900Y88300D01*
Y93200D01*
X1540070Y94030D01*
X1534122D01*
X1533743Y94409D01*
X1533976Y95419D01*
X1533722Y96521D01*
Y100930D01*
X1533922Y101130D01*
X1543491D01*
X1544922Y96382D01*
Y89782D01*
X1544786Y89736D01*
G03Y86984I464J-1376D01*
G01X1544922Y86938D01*
G37*
G36*
G01X1558940Y116880D02*
X1556750Y119070D01*
Y122275D01*
X1557305Y122830D01*
X1558810D01*
X1559480Y122160D01*
X1570824D01*
X1571035Y121950D01*
X1571333D01*
G02X1571690Y121370I0J-400D01*
G03X1574552I1431J-721D01*
G02X1574909Y121950I357J180D01*
G01X1576908D01*
Y119502D01*
X1576140Y118733D01*
Y118714D01*
X1574306Y116880D01*
X1558940D01*
G37*
G36*
G01X1554800Y129400D02*
G02X1555100Y129100I0J-300D01*
G02X1554800Y128800I-300J0D01*
G02X1554500Y129100I0J300D01*
G02X1554800Y129400I300J0D01*
G37*
G36*
G01X1554945Y133700D02*
G02X1555245Y133400I0J-300D01*
G02X1554945Y133100I-300J0D01*
G02X1554645Y133400I0J300D01*
G02X1554945Y133700I300J0D01*
G37*
G36*
G01X1558100Y98500D02*
G02X1558400Y98200I0J-300D01*
G02X1558100Y97900I-300J0D01*
G02X1557800Y98200I0J300D01*
G02X1558100Y98500I300J0D01*
G37*
G36*
G01X1554800D02*
G02X1555100Y98200I0J-300D01*
G02X1554800Y97900I-300J0D01*
G02X1554500Y98200I0J300D01*
G02X1554800Y98500I300J0D01*
G37*
G36*
G01X1555000Y139300D02*
G02X1555300Y139000I0J-300D01*
G02X1555000Y138700I-300J0D01*
G02X1554700Y139000I0J300D01*
G02X1555000Y139300I300J0D01*
G37*
G36*
G01X1535690Y161150D02*
X1537940D01*
X1539918Y158160D01*
Y155404D01*
X1539917Y155395D01*
G03Y155123I1496J-136D01*
G01X1539918Y155114D01*
Y152904D01*
X1539936Y152886D01*
Y152226D01*
X1539932Y152206D01*
G03Y151594I1419J-306D01*
G01X1539936Y151574D01*
Y151274D01*
X1539662Y151000D01*
X1531220D01*
X1530780Y151440D01*
Y156000D01*
X1531370Y156590D01*
X1533760D01*
X1534630Y157460D01*
Y160090D01*
X1535690Y161150D01*
G37*
G36*
G01X1584889Y187840D02*
X1584766Y187963D01*
Y195786D01*
X1584930Y195950D01*
X1595193D01*
X1595743Y195400D01*
X1600171D01*
X1600300Y195529D01*
Y195956D01*
X1600342Y195998D01*
X1601252D01*
Y198100D01*
X1605600D01*
X1606300Y197400D01*
Y195700D01*
X1606900Y195100D01*
X1615700D01*
X1616700Y196100D01*
Y208100D01*
X1617300Y208700D01*
X1624793D01*
X1626844Y206649D01*
Y202960D01*
X1629084Y200720D01*
Y197119D01*
G02X1628891Y196919I-200J0D01*
G03X1627878Y196500I58J-1575D01*
G01X1626300D01*
X1626104Y196696D01*
Y198787D01*
X1625719Y199172D01*
X1622162D01*
X1622059Y199069D01*
Y199067D01*
X1622007Y199015D01*
Y194920D01*
X1622827Y194100D01*
Y190435D01*
X1622628Y190236D01*
X1617554D01*
X1617325Y190466D01*
X1604936D01*
Y191042D01*
X1603215D01*
X1602213Y192044D01*
X1599858D01*
G02X1599458Y192439I0J400D01*
G03X1596554I-1452J-18D01*
G02X1596154Y192044I-400J5D01*
G01X1595020D01*
X1593817Y193248D01*
X1592270D01*
X1592028Y193006D01*
Y193000D01*
X1586868Y187840D01*
X1584889D01*
G37*
G36*
G01X1574023Y187761D02*
X1573551Y188233D01*
X1563973D01*
X1563500Y188706D01*
Y192382D01*
X1563503Y192399D01*
G03Y192951I-1578J276D01*
G01X1563500Y192968D01*
Y193399D01*
X1564243Y194142D01*
X1577621D01*
X1577723Y194244D01*
X1580031D01*
X1581430Y195643D01*
X1583127D01*
X1583247Y195523D01*
Y190053D01*
X1583244Y190050D01*
Y187984D01*
X1583021Y187761D01*
X1574023D01*
G37*
G36*
G01X1557097Y250872D02*
Y250871D01*
X1557154Y250928D01*
G02X1557710Y250938I283J-283D01*
G03X1560119Y252307I990J1062D01*
G02X1560510Y252792I391J85D01*
G01X1564199D01*
X1565252Y251739D01*
Y240245D01*
X1564198Y239190D01*
Y235078D01*
X1564195Y235076D01*
X1562302D01*
G03X1559906I-1198J-821D01*
G01X1555623D01*
X1555018Y235681D01*
Y248793D01*
X1557097Y250872D01*
G37*
G36*
G01X1593358Y228986D02*
X1592231Y230113D01*
X1580372D01*
X1578720Y231766D01*
Y241160D01*
X1577800Y242079D01*
Y247772D01*
X1576700Y248872D01*
Y258163D01*
X1583393Y264856D01*
Y276439D01*
X1584054Y277100D01*
X1596169D01*
X1596232Y277036D01*
Y251780D01*
X1596064Y251753D01*
G03X1594881Y250011I236J-1433D01*
G01X1594904Y249904D01*
X1594000Y249000D01*
Y235511D01*
X1594889Y234622D01*
X1606049D01*
X1606795Y233876D01*
Y229224D01*
X1606557Y228986D01*
X1593358D01*
G37*
G36*
G01X1549113Y269905D02*
X1549077Y269941D01*
Y275414D01*
X1549363Y275700D01*
X1552748D01*
G03X1553052I152J6000D01*
G01X1555750D01*
X1555794Y275656D01*
Y272724D01*
X1555800D01*
Y271500D01*
X1554205Y269905D01*
X1549113D01*
G37*
G36*
G01X1542602Y253754D02*
Y255902D01*
X1542700Y256000D01*
X1544670D01*
X1546396Y257726D01*
Y261296D01*
X1546500Y261400D01*
X1548900D01*
X1549100Y261200D01*
Y258072D01*
X1547776Y256748D01*
X1547398D01*
Y254747D01*
X1547050Y254400D01*
X1544940D01*
X1544294Y253754D01*
X1542602D01*
G37*
G36*
G01X1575550Y275525D02*
Y269756D01*
X1573929Y268135D01*
Y266402D01*
X1573352Y265825D01*
X1572619D01*
X1571750Y266694D01*
X1560691D01*
X1559167Y268218D01*
G03X1557050Y269503I-3687J-3687D01*
G02X1556888Y270168I120J382D01*
G01X1557770Y271050D01*
Y272724D01*
X1557796D01*
Y275749D01*
X1557970Y275923D01*
X1575152D01*
X1575550Y275525D01*
G37*
G36*
G01X1532148Y253252D02*
X1531949Y253451D01*
Y258427D01*
X1532120Y258598D01*
X1534002D01*
Y258640D01*
X1534940D01*
X1535526Y259226D01*
Y263050D01*
X1535595Y263119D01*
X1538909D01*
X1539000Y263028D01*
Y259633D01*
X1534609Y255242D01*
Y255225D01*
X1534598Y255215D01*
Y253300D01*
X1534550Y253252D01*
X1532148D01*
G37*
G36*
G01X1541276D02*
X1538998D01*
Y253240D01*
X1538002D01*
Y253252D01*
X1535600D01*
Y254800D01*
X1538881Y258081D01*
X1540319D01*
X1540519Y258281D01*
Y261319D01*
X1540600Y261400D01*
X1541500D01*
X1541600Y261300D01*
Y253576D01*
X1541276Y253252D01*
G37*
G36*
G01X1536500Y275600D02*
Y280600D01*
X1536645Y280745D01*
X1538547D01*
X1538600Y280692D01*
Y278535D01*
X1541600Y275535D01*
Y271700D01*
X1541500Y271600D01*
X1540500D01*
X1536500Y275600D01*
G37*
G36*
G01X1546400Y272921D02*
Y275600D01*
X1546042Y275958D01*
X1542593D01*
X1539958Y278593D01*
Y280715D01*
X1539990Y280747D01*
X1549050D01*
X1549300Y280497D01*
Y277336D01*
X1547600Y275636D01*
Y273040D01*
G03X1547065Y272621I3149J-4572D01*
G02X1546400Y272921I-265J300D01*
G37*
G36*
G01X1596410Y380400D02*
X1594113D01*
X1585324Y389188D01*
X1584060D01*
X1584050Y389378D01*
G03X1582626Y390752I-1450J-78D01*
G02X1582430Y390952I4J200D01*
G01Y391698D01*
X1583978D01*
X1588828Y386848D01*
X1591379D01*
X1593173Y385054D01*
X1595445D01*
X1595922Y384577D01*
X1602681D01*
X1603599Y385495D01*
Y387997D01*
X1602170Y389426D01*
Y390561D01*
X1602001Y390730D01*
X1596503D01*
X1596403Y390630D01*
Y389306D01*
X1596209Y389112D01*
X1592717D01*
X1592647Y389042D01*
Y388431D01*
X1592507Y388291D01*
X1589426D01*
X1584555Y393162D01*
X1582670D01*
X1582430Y393402D01*
Y393863D01*
X1592596D01*
X1592980Y393479D01*
X1595926D01*
X1596004Y393557D01*
Y394384D01*
X1596878Y395258D01*
Y396359D01*
X1597085Y396566D01*
X1604197D01*
X1604678Y396085D01*
Y391916D01*
X1604771Y391823D01*
X1610244D01*
X1610357Y391936D01*
Y396933D01*
X1610294Y396996D01*
X1605883D01*
X1604809Y398070D01*
X1596409D01*
X1595890Y397551D01*
X1593473D01*
X1593452Y397530D01*
X1593450D01*
Y397528D01*
X1593392Y397470D01*
Y397469D01*
X1592915Y396992D01*
Y395479D01*
X1592766Y395330D01*
X1583453D01*
X1583391Y395392D01*
Y395749D01*
X1583491Y395849D01*
X1589749D01*
X1593500Y399600D01*
X1600700D01*
X1600800Y399500D01*
X1606100D01*
X1606300Y399700D01*
X1610600D01*
X1614600Y395700D01*
Y390600D01*
X1609100Y385100D01*
X1609090D01*
X1607640Y383650D01*
X1599660D01*
X1596410Y380400D01*
G37*
G36*
G01X1533513Y419389D02*
X1533316Y419586D01*
X1532353D01*
X1532159Y419392D01*
X1530347D01*
X1529917Y419822D01*
X1529234D01*
X1529071Y419985D01*
G02X1529213Y420326I142J141D01*
G01X1530157D01*
X1530834Y421003D01*
Y421456D01*
X1530876Y421498D01*
X1531606D01*
X1531671Y421434D01*
Y420998D01*
X1532342Y420327D01*
X1533303D01*
X1533986Y421010D01*
Y421447D01*
X1534038Y421498D01*
X1534736D01*
X1534821Y421413D01*
Y421001D01*
X1535499Y420323D01*
X1536455D01*
X1537136Y421004D01*
Y421429D01*
X1537206Y421498D01*
X1537872D01*
X1537969Y421402D01*
Y421005D01*
X1538648Y420326D01*
X1539605D01*
X1540283Y421004D01*
Y421433D01*
X1540348Y421498D01*
X1541114D01*
X1541137Y421325D01*
G03X1542029Y420354I1138J150D01*
G01X1542186Y420319D01*
Y419780D01*
X1542052Y419646D01*
X1542051D01*
X1541961Y419556D01*
X1541776D01*
X1541621Y419401D01*
X1539787D01*
X1539597Y419591D01*
X1538649D01*
X1538460Y419402D01*
X1536630D01*
X1536441Y419591D01*
X1535481D01*
X1535279Y419389D01*
X1533513D01*
G37*
G36*
G01X1550112Y417455D02*
X1552368D01*
X1553210Y416613D01*
X1553816D01*
X1553817Y416614D01*
X1554046D01*
X1554520Y416140D01*
Y415443D01*
X1554322Y415245D01*
Y415056D01*
X1553442Y414176D01*
X1551086D01*
G02X1550786Y414841I0J400D01*
G03X1550000Y416746I-861J759D01*
G02X1549813Y416945I13J199D01*
G01Y417100D01*
X1549961Y417250D01*
X1549953Y417296D01*
X1550112Y417455D01*
G37*
G36*
G01X1543699Y443801D02*
X1543500Y444000D01*
Y446416D01*
X1543504Y446435D01*
G03Y446915I-1229J240D01*
G01X1543500Y446934D01*
Y449566D01*
X1543504Y449585D01*
G03Y450065I-1229J240D01*
G01X1543500Y450084D01*
Y452716D01*
X1543504Y452735D01*
G03Y453215I-1229J240D01*
G01X1543500Y453234D01*
Y454979D01*
X1545608D01*
X1545638Y454969D01*
G03X1546082Y454909I387J1191D01*
G02X1546500Y454510I18J-399D01*
G01Y454368D01*
G02X1545926Y454008I-400J0D01*
G03Y451942I-501J-1033D01*
G02X1546500Y451582I174J-360D01*
G01Y451218D01*
G02X1545926Y450858I-400J0D01*
G03Y448792I-501J-1033D01*
G02X1546500Y448432I174J-360D01*
G01Y448068D01*
G02X1545926Y447708I-400J0D01*
G03X1545950Y445654I-501J-1033D01*
G02X1546533Y445298I183J-356D01*
G01Y444902D01*
G02X1545950Y444546I-400J0D01*
G03X1544354Y443940I-525J-1021D01*
G02X1543699Y443801I-373J144D01*
G37*
G36*
G01X1547292Y407550D02*
G02X1546964Y408180I-1J400D01*
G03X1545859Y409976I-939J660D01*
G02X1545632Y410142I-29J198D01*
G03X1545558Y410423I-1483J-240D01*
G02X1545802Y410941I375J140D01*
G03X1546421Y411453I-376J1085D01*
G02X1547080Y411504I347J-199D01*
G03X1549049Y412632I897J716D01*
G02X1549422Y413175I373J143D01*
G01X1553869D01*
X1553902Y413208D01*
X1554562Y412548D01*
X1554543Y412445D01*
G03X1554970Y411261I1232J-225D01*
G01Y410560D01*
X1554380Y409970D01*
X1554260Y410014D01*
G03X1552879Y409660I-435J-1174D01*
G01X1550871D01*
G03X1548820Y408251I-946J-820D01*
G01X1548890Y408120D01*
X1548320Y407550D01*
X1547292D01*
G37*
G36*
G01X1593355Y458842D02*
X1592476Y459722D01*
X1584605D01*
X1584062Y460264D01*
X1581065D01*
Y460815D01*
G03Y463365I-695J1275D01*
G01Y465460D01*
X1582805Y467200D01*
X1596800D01*
X1596998Y467002D01*
Y463998D01*
X1597000D01*
Y462002D01*
X1596998D01*
Y458842D01*
X1593355D01*
G37*
G36*
G01X1549000Y421516D02*
Y421000D01*
X1548213Y420213D01*
X1548117Y420224D01*
G03X1547249Y420000I-142J-1244D01*
G01X1545899D01*
X1545666Y420233D01*
X1545835Y420402D01*
X1545871Y420417D01*
G03X1544468Y422110I-446J1058D01*
G02X1543852Y422048I-333J221D01*
G01X1542940Y422960D01*
Y423564D01*
G03X1543509Y424416I-665J1060D01*
G02X1543892Y424749I395J-67D01*
G03X1544051Y424762I-39J1451D01*
G02X1544278Y424573I27J-198D01*
G03X1545630Y425755I1147J52D01*
G02X1545301Y426159I71J394D01*
G03Y426241I-1451J41D01*
G02X1545630Y426645I400J10D01*
G03Y428905I-205J1130D01*
G02X1545301Y429309I71J394D01*
G03Y429391I-1451J41D01*
G02X1545630Y429795I400J10D01*
G03X1544295Y431130I-205J1130D01*
G02X1543891Y430801I-394J71D01*
G03X1543740Y430798I-47J-1451D01*
G02X1543525Y430987I-15J200D01*
G03X1542940Y431986I-1250J-61D01*
G01Y433014D01*
G03X1543509Y433866I-665J1060D01*
G02X1543892Y434199I395J-67D01*
G03X1544051Y434212I-39J1451D01*
G02X1544278Y434023I27J-198D01*
G03X1545630Y435205I1147J52D01*
G02X1545301Y435609I71J394D01*
G03X1545299Y435738I-1451J42D01*
G01Y435950D01*
X1545950D01*
X1545999Y435998D01*
X1546715D01*
X1550085Y432628D01*
X1550615D01*
X1550625Y432438D01*
G03X1550839Y431797I1250J61D01*
G01X1550874Y431746D01*
Y431374D01*
X1549873Y430373D01*
X1549802Y430366D01*
G03X1549000Y428276I123J-1246D01*
G01Y427156D01*
G02X1548439Y426790I-400J0D01*
G03X1548138Y424604I-464J-1050D01*
G02X1548576Y424325I56J-396D01*
G03X1549000Y423667I1388J428D01*
G01Y423207D01*
X1548955Y423152D01*
G03X1549000Y421516I970J-792D01*
G37*
G36*
G01X1550500Y433630D02*
X1550031Y434099D01*
G02X1550213Y434769I283J283D01*
G03X1548921Y436437I-288J1111D01*
G02X1548232Y436419I-350J194D01*
G03X1546959Y437101I-1231J-769D01*
G02X1546555Y437430I-10J400D01*
G03X1544583Y438005I-1130J-205D01*
G02X1544006Y437994I-294J272D01*
G01X1543500Y438500D01*
Y440116D01*
X1543504Y440135D01*
G03Y440615I-1229J240D01*
G01X1543500Y440634D01*
Y442000D01*
X1548849D01*
G03X1549514Y441457I1076J640D01*
G01X1549558Y441442D01*
X1550917Y440083D01*
X1550828Y439947D01*
G03X1552353Y438103I1047J-687D01*
G01X1552476Y438154D01*
X1553020Y437610D01*
Y436839D01*
G03X1552821Y435132I805J-959D01*
G01X1552924Y434994D01*
X1551666Y433736D01*
X1551608Y433723D01*
G03X1551373Y433647I266J-1223D01*
G01X1551334Y433630D01*
X1550500D01*
G37*
G36*
G01X1618005Y485903D02*
X1598653D01*
X1598628Y485928D01*
X1592672D01*
X1592505Y486095D01*
Y490279D01*
X1592619Y490393D01*
Y494239D01*
X1593484Y495104D01*
Y496691D01*
X1592475Y497700D01*
X1587860D01*
X1587600Y497960D01*
Y501457D01*
X1587631Y501488D01*
X1601512D01*
X1602900Y500100D01*
Y497400D01*
X1604514Y495786D01*
Y494021D01*
X1605300Y493235D01*
X1613691D01*
X1613953Y493497D01*
X1616856D01*
X1616894Y493459D01*
Y491475D01*
X1617620Y490749D01*
X1618096D01*
X1618900Y489945D01*
Y486798D01*
X1618005Y485903D01*
G37*
G36*
G01X1573850Y473400D02*
X1574521Y472729D01*
X1575071D01*
X1575300Y472500D01*
Y471250D01*
X1575100Y471050D01*
X1574450D01*
X1573850Y470450D01*
Y469450D01*
X1574500Y468800D01*
X1574918D01*
X1575050Y468668D01*
Y468002D01*
X1574348Y467300D01*
X1572160D01*
X1570510Y468950D01*
X1564770D01*
X1564650Y469070D01*
Y469600D01*
X1565062Y470012D01*
Y470912D01*
X1566980Y472830D01*
Y474530D01*
X1567545Y475095D01*
X1570945D01*
X1571800Y475950D01*
X1572050D01*
X1572850Y476750D01*
Y478000D01*
X1572200Y478650D01*
Y480600D01*
X1572600Y481000D01*
X1574122D01*
X1574550Y480572D01*
Y479600D01*
X1573450Y478500D01*
Y477100D01*
X1574350Y476200D01*
X1574850D01*
X1575050Y476000D01*
Y475156D01*
X1574847Y474953D01*
X1574503D01*
X1573850Y474300D01*
Y473400D01*
G37*
G36*
G01X1577230Y503600D02*
X1576130Y504700D01*
Y506711D01*
X1573975Y508866D01*
X1571163D01*
X1569051Y506754D01*
X1567694D01*
X1567357Y507091D01*
Y511047D01*
X1570460Y514150D01*
X1573198D01*
Y514148D01*
X1576202D01*
Y514150D01*
X1578198D01*
Y514148D01*
X1581202D01*
Y514150D01*
X1584550D01*
X1590500Y508200D01*
X1608800D01*
X1612950Y512350D01*
X1617050D01*
X1617700Y511700D01*
Y506500D01*
X1614800Y503600D01*
X1577230D01*
G37*
G36*
G01X1613155Y527165D02*
G03I-12800J0D01*
G37*
G36*
G01X1580104Y584696D02*
X1578632Y586168D01*
Y588291D01*
X1578722Y588381D01*
Y590164D01*
X1579853Y591296D01*
X1591004D01*
X1591404Y590896D01*
Y585396D01*
X1590704Y584696D01*
X1580104D01*
G37*
G36*
G01X1559595Y547198D02*
X1557832Y548961D01*
Y564371D01*
X1558011Y564550D01*
Y575227D01*
X1557206Y576032D01*
Y580406D01*
X1557400Y580600D01*
X1563400D01*
X1566974Y577026D01*
Y571442D01*
X1569742Y568674D01*
X1576899D01*
X1581093Y572868D01*
X1586668D01*
X1586896Y572640D01*
Y569687D01*
X1587303Y569280D01*
Y567706D01*
X1587268D01*
Y562702D01*
X1587303D01*
Y560706D01*
X1587268D01*
Y555702D01*
X1587303D01*
Y555360D01*
X1586298Y554355D01*
X1581121D01*
X1573964Y547198D01*
X1559595D01*
G37*
G36*
G01X1590425Y555712D02*
X1590272Y555865D01*
Y567706D01*
X1590245D01*
X1588923Y569028D01*
Y572954D01*
X1587980Y573897D01*
X1581814D01*
X1581138Y574573D01*
Y583503D01*
X1581329Y583694D01*
X1585546D01*
G02X1585912Y583135I-1J-400D01*
G03X1585758Y582396I1698J-739D01*
G01Y579550D01*
G03X1589462I1852J0D01*
G01Y580274D01*
X1592579D01*
X1597524Y575329D01*
Y572182D01*
X1600174Y569532D01*
Y556420D01*
X1599466Y555712D01*
X1590425D01*
G37*
G36*
G01X1594804Y598996D02*
X1594304Y599496D01*
Y602796D01*
X1593404Y603696D01*
X1586213D01*
X1585658Y604251D01*
X1585502D01*
Y604252D01*
X1582630D01*
X1582454Y604427D01*
Y606569D01*
X1584885Y609000D01*
X1586500D01*
Y608996D01*
X1596404D01*
X1599204Y606196D01*
Y600496D01*
X1597704Y598996D01*
X1594804D01*
G37*
G36*
G01X1550963Y612629D02*
X1551045Y612711D01*
X1565304D01*
X1565417Y612598D01*
Y598576D01*
X1565201Y598360D01*
X1551086D01*
X1550963Y598483D01*
Y612629D01*
G37*
G36*
G01X1583102Y592298D02*
X1583004Y592396D01*
X1581104D01*
X1581000Y592500D01*
Y601500D01*
X1581700Y602200D01*
X1587000D01*
X1587396Y602596D01*
X1592004D01*
Y595796D01*
X1588904D01*
X1588660Y595552D01*
X1588476D01*
Y595368D01*
X1588204Y595096D01*
Y592496D01*
X1588006Y592298D01*
X1583102D01*
G37*
G36*
G01X1646200Y5600D02*
G02X1646500Y5300I0J-300D01*
G02X1646200Y5000I-300J0D01*
G02X1645900Y5300I0J300D01*
G02X1646200Y5600I300J0D01*
G37*
G36*
G01X1619100Y6800D02*
G02X1619400Y6500I0J-300D01*
G02X1619100Y6200I-300J0D01*
G02X1618800Y6500I0J300D01*
G02X1619100Y6800I300J0D01*
G37*
G36*
G01X1606700Y4900D02*
G02X1607000Y4600I0J-300D01*
G02X1606700Y4300I-300J0D01*
G02X1606400Y4600I0J300D01*
G02X1606700Y4900I300J0D01*
G37*
G36*
G01X1626400D02*
G02X1626700Y4600I0J-300D01*
G02X1626400Y4300I-300J0D01*
G02X1626100Y4600I0J300D01*
G02X1626400Y4900I300J0D01*
G37*
G36*
G01X1636500D02*
G02X1636800Y4600I0J-300D01*
G02X1636500Y4300I-300J0D01*
G02X1636200Y4600I0J300D01*
G02X1636500Y4900I300J0D01*
G37*
G36*
G01X1633500Y123834D02*
G03X1633374Y126134I-861J1106D01*
G01X1633353Y126147D01*
X1633122Y126378D01*
X1626178D01*
X1626127Y126327D01*
X1626068Y126315D01*
G03X1624964Y125211I271J-1375D01*
G01X1624952Y125152D01*
X1624254Y124454D01*
X1624225Y124439D01*
G03X1623878Y122553I539J-1074D01*
G01Y121773D01*
X1623547Y121442D01*
X1621013D01*
X1620778Y121678D01*
Y126677D01*
X1621556Y127455D01*
Y128700D01*
X1620778Y129478D01*
Y132986D01*
X1621541Y133749D01*
Y135043D01*
X1620778Y135806D01*
Y139369D01*
X1621491Y140082D01*
Y141339D01*
X1620778Y142052D01*
Y145795D01*
G03Y148179I-738J1192D01*
G01Y148973D01*
G03X1621321Y149510I-677J1228D01*
G01X1621334Y149534D01*
X1623538Y151738D01*
X1623588Y151753D01*
G03X1624452Y152468I-387J1348D01*
G01X1624507Y152578D01*
X1625118D01*
G03X1627508I1195J734D01*
G01X1628065D01*
X1628638Y152005D01*
Y151420D01*
X1628034Y150816D01*
Y149527D01*
X1628889Y148672D01*
X1630134D01*
X1631958Y150496D01*
X1634496D01*
X1634559Y150559D01*
X1634603Y150574D01*
G03X1634503Y152877I-390J1137D01*
G01X1634450Y152891D01*
X1634042Y153298D01*
X1634037Y153374D01*
G03X1633478Y154408I-1399J-88D01*
G01Y155778D01*
X1633678Y155978D01*
X1634530D01*
X1636802Y153706D01*
Y152866D01*
X1636527Y152591D01*
Y152578D01*
X1636475Y152521D01*
G03Y150901I888J-810D01*
G01X1636527Y150844D01*
Y150839D01*
X1636870Y150496D01*
X1638271D01*
X1640253Y152478D01*
X1640941D01*
G03X1643233I1146J808D01*
G01X1647078D01*
X1647475Y152080D01*
Y151189D01*
G03X1647375Y149239I955J-1027D01*
G01X1647499Y149099D01*
X1646987Y148586D01*
X1646478Y148077D01*
Y130387D01*
X1645935Y129844D01*
X1644790D01*
X1643925Y128979D01*
Y127779D01*
X1644779Y126925D01*
X1645532D01*
X1646478Y125979D01*
Y125978D01*
X1647678Y124778D01*
Y122878D01*
X1647378Y122578D01*
X1640078D01*
X1638791Y123865D01*
G02X1638891Y124503I283J282D01*
G03X1637074Y124987I-641J1247D01*
G02X1636906Y124678I-168J-109D01*
G01X1636778D01*
X1634578Y122478D01*
X1634000D01*
X1633500Y122978D01*
Y123834D01*
G37*
G36*
G01X1606589Y225969D02*
Y221815D01*
X1605548Y220774D01*
X1590043D01*
X1589660Y221157D01*
Y225108D01*
X1590620Y226068D01*
X1593333D01*
X1593377Y226112D01*
X1606446D01*
X1606589Y225969D01*
G37*
G36*
G01X1612400Y265800D02*
X1612200Y266000D01*
Y271400D01*
X1612400Y271600D01*
X1635200D01*
X1635400Y271400D01*
Y266000D01*
X1635200Y265800D01*
X1630223D01*
G03X1626061I-2081J-1801D01*
G01X1612400D01*
G37*
G36*
G01X1634200Y222000D02*
X1634100Y222100D01*
Y227300D01*
X1633050Y228350D01*
X1627050D01*
X1623400Y232000D01*
X1613211D01*
X1612790Y232421D01*
Y238436D01*
X1619448D01*
X1619813Y238800D01*
X1625600D01*
X1627000Y237400D01*
X1629400D01*
X1630900Y238900D01*
Y241400D01*
X1628900Y243400D01*
Y245600D01*
X1629000Y245700D01*
X1635300D01*
X1635700Y245300D01*
Y243500D01*
X1641900Y237300D01*
Y234910D01*
G03Y232916I1206J-997D01*
G01Y230083D01*
X1640882Y229064D01*
X1637352D01*
X1635876Y227589D01*
Y227276D01*
X1635700Y227100D01*
Y222200D01*
X1635500Y222000D01*
X1634200D01*
G37*
G36*
G01X1640200Y327300D02*
X1640000Y327500D01*
Y336950D01*
X1640800Y337750D01*
X1643998D01*
Y337748D01*
X1646002D01*
Y337750D01*
X1647198D01*
Y337748D01*
X1649202D01*
Y337750D01*
X1650600D01*
X1651098Y338248D01*
X1654252D01*
X1654750Y337750D01*
X1655398D01*
Y337748D01*
X1657252D01*
X1657500Y337500D01*
Y331650D01*
X1656702Y330852D01*
X1654385D01*
X1654166Y330632D01*
X1649117D01*
X1649085Y330600D01*
X1643150D01*
X1642052Y329502D01*
X1641998D01*
Y327498D01*
X1641800Y327300D01*
X1640200D01*
G37*
G36*
G01X1628530Y339020D02*
X1628370Y339180D01*
Y347130D01*
X1628550Y347310D01*
X1636430D01*
X1636610Y347130D01*
Y342176D01*
X1636548Y342115D01*
Y339078D01*
X1636490Y339020D01*
X1628530D01*
G37*
G36*
G01X1660300Y330850D02*
Y328550D01*
X1659600Y327850D01*
X1654650D01*
X1654450Y328050D01*
Y328493D01*
X1654462Y328526D01*
G03X1654512Y329426I-1471J533D01*
G01X1654485Y329535D01*
X1654800Y329850D01*
X1658050D01*
X1658600Y330400D01*
Y335250D01*
X1658650Y335300D01*
Y338800D01*
X1658200Y339250D01*
X1657402D01*
Y339252D01*
X1655398D01*
Y339250D01*
X1649202D01*
Y339252D01*
X1647198D01*
Y339250D01*
X1646002D01*
Y339252D01*
X1643998D01*
Y339250D01*
X1637700D01*
X1637550Y339400D01*
Y341700D01*
X1638150Y342300D01*
X1640550D01*
X1641650Y343400D01*
X1641932D01*
X1641962Y343390D01*
G03X1642443Y343314I482J1489D01*
G01X1644203D01*
X1644289Y343400D01*
X1646450D01*
X1646798Y343748D01*
X1647152D01*
Y344102D01*
X1647350Y344300D01*
Y346030D01*
X1647560Y346240D01*
X1649960D01*
X1651900Y344300D01*
X1663500D01*
X1665150Y342650D01*
Y332200D01*
X1664200Y331250D01*
X1663002D01*
Y331252D01*
X1660998D01*
Y331250D01*
X1660700D01*
X1660300Y330850D01*
G37*
G36*
G01X1605008Y365578D02*
X1604752Y365834D01*
Y368750D01*
X1604653D01*
Y370446D01*
X1604752D01*
Y373707D01*
X1604984Y373939D01*
X1609799D01*
X1610067Y373671D01*
X1610565D01*
X1610771Y373465D01*
Y372196D01*
X1608547Y369972D01*
Y366382D01*
X1607743Y365578D01*
X1605008D01*
G37*
G36*
G01X1650480Y368515D02*
G02X1650780Y368215I0J-300D01*
G02X1650480Y367915I-300J0D01*
G02X1650180Y368215I0J300D01*
G02X1650480Y368515I300J0D01*
G37*
G36*
G01X1642114Y368442D02*
G02X1642414Y368142I0J-300D01*
G02X1642114Y367842I-300J0D01*
G02X1641814Y368142I0J300D01*
G02X1642114Y368442I300J0D01*
G37*
G36*
G01X1642126Y358194D02*
G02X1642426Y357894I0J-300D01*
G02X1642126Y357594I-300J0D01*
G02X1641826Y357894I0J300D01*
G02X1642126Y358194I300J0D01*
G37*
G36*
G01X1602700Y365711D02*
X1602615Y365626D01*
X1599335D01*
X1596653Y368308D01*
Y373382D01*
X1597172Y373901D01*
X1602394D01*
X1602700Y373595D01*
Y365711D01*
G37*
G36*
G01X1599157Y458842D02*
X1599002Y458999D01*
Y462002D01*
X1599000D01*
Y463998D01*
X1599002D01*
Y467002D01*
X1599200Y467200D01*
X1602513D01*
X1603664Y466049D01*
Y465428D01*
X1605110Y463982D01*
X1605278D01*
Y461946D01*
X1604740Y461408D01*
X1604658D01*
X1602093Y458842D01*
X1599157D01*
G37*
G36*
G01X1621015Y536659D02*
X1649008D01*
X1654080Y541731D01*
X1665167D01*
X1665628Y541270D01*
Y539720D01*
X1668491Y536857D01*
Y528856D01*
X1664888Y525253D01*
X1644917D01*
X1640991Y521327D01*
X1631548D01*
G03X1631338Y521636I-1390J-718D01*
G01Y523730D01*
X1631493Y523885D01*
X1636959D01*
X1637256Y523588D01*
X1639148D01*
X1640536Y524976D01*
Y528463D01*
X1633467Y535532D01*
X1626545D01*
X1625674Y534661D01*
Y533110D01*
X1625573Y533009D01*
X1623312D01*
X1623120Y532817D01*
X1620274D01*
X1620201Y532890D01*
Y536291D01*
X1620486Y536576D01*
G02X1621015Y536659I863J-3776D01*
G37*
G36*
G01X1622252Y500500D02*
Y503702D01*
X1622200D01*
Y513200D01*
X1622900Y513900D01*
X1628000D01*
X1628400Y513500D01*
Y510121D01*
X1627060Y508781D01*
Y508760D01*
X1626000Y507700D01*
Y500900D01*
X1625600Y500500D01*
X1622252D01*
G37*
G36*
G01X1614304Y494505D02*
X1613533Y495276D01*
X1605624D01*
X1605516Y495384D01*
Y500398D01*
X1605784Y500666D01*
X1613666D01*
X1616900Y503900D01*
X1620000D01*
X1620243Y503657D01*
Y499715D01*
X1618128Y497600D01*
X1617500D01*
X1616900Y497000D01*
Y496478D01*
X1616896D01*
Y494576D01*
X1616826Y494505D01*
X1614304D01*
G37*
G36*
G01X1675800Y4400D02*
G02X1676100Y4100I0J-300D01*
G02X1675800Y3800I-300J0D01*
G02X1675500Y4100I0J300D01*
G02X1675800Y4400I300J0D01*
G37*
G36*
G01X1664200Y5700D02*
G02X1664500Y5400I0J-300D01*
G02X1664200Y5100I-300J0D01*
G02X1663900Y5400I0J300D01*
G02X1664200Y5700I300J0D01*
G37*
G36*
G01X1656600Y6600D02*
G02X1656900Y6300I0J-300D01*
G02X1656600Y6000I-300J0D01*
G02X1656300Y6300I0J300D01*
G02X1656600Y6600I300J0D01*
G37*
G36*
G01X1696700Y188842D02*
X1696200Y189342D01*
Y194900D01*
X1695500Y195600D01*
Y197748D01*
X1695744D01*
Y200100D01*
X1700200D01*
X1700500Y199800D01*
Y197500D01*
X1704200Y193800D01*
Y189400D01*
X1703642Y188842D01*
X1696700D01*
G37*
G36*
G01X1657949Y257540D02*
G02X1658249Y257240I0J-300D01*
G02X1657949Y256940I-300J0D01*
G02X1657649Y257240I0J300D01*
G02X1657949Y257540I300J0D01*
G37*
G36*
G01X1650624Y358184D02*
G02X1650924Y357884I0J-300D01*
G02X1650624Y357584I-300J0D01*
G02X1650324Y357884I0J300D01*
G02X1650624Y358184I300J0D01*
G37*
G36*
G01X1696790Y500650D02*
X1694936Y498796D01*
X1693767D01*
X1693338Y498367D01*
Y493327D01*
X1693318Y493307D01*
X1689358D01*
X1689296Y493369D01*
Y498040D01*
X1691157Y499901D01*
Y501895D01*
X1691912Y502650D01*
Y515604D01*
X1692050Y515742D01*
X1694943D01*
X1697663Y518462D01*
X1708829D01*
X1709030Y518261D01*
Y515350D01*
X1709530Y514850D01*
X1715500D01*
X1715900Y514450D01*
Y511600D01*
X1715450Y511150D01*
X1708720D01*
X1708316Y511554D01*
X1701154D01*
X1699300Y509700D01*
Y506041D01*
X1696790Y503531D01*
Y500650D01*
G37*
G36*
G01X1708742Y508850D02*
Y506029D01*
X1709230Y505542D01*
Y505510D01*
X1713520Y501220D01*
X1714310D01*
X1715840Y499690D01*
Y491370D01*
X1715500Y491030D01*
X1704460D01*
X1702348Y493142D01*
X1696532D01*
X1696345Y493329D01*
Y498414D01*
X1698309Y500378D01*
Y503459D01*
X1700630Y505780D01*
Y509150D01*
X1701580Y510100D01*
X1701828D01*
Y510048D01*
X1703832D01*
Y510100D01*
X1708510D01*
G02X1708880Y509549I-1J-400D01*
G03X1708742Y508850I1714J-701D01*
G37*
G36*
G01X1676497Y482584D02*
X1675300Y483781D01*
Y484550D01*
X1677966Y487216D01*
Y493568D01*
X1678259Y493861D01*
Y505136D01*
X1682502D01*
X1682700Y504937D01*
Y488200D01*
X1677084Y482584D01*
X1676497D01*
G37*
G36*
G01X1678259Y508264D02*
Y515059D01*
X1678500Y515300D01*
X1680800D01*
X1682700Y513400D01*
Y508264D01*
X1678259D01*
G37*
G36*
G01X1713911Y536791D02*
G02I-1706J0D01*
G37*
G36*
G01X1708815D02*
G02I-1610J0D01*
G37*
G36*
G01X1698806D02*
G02I-1601J0D01*
G37*
G36*
G01X1693827D02*
G02I-1622J0D01*
G37*
G36*
G01X1763100Y21800D02*
G02X1763400Y21500I0J-300D01*
G02X1763100Y21200I-300J0D01*
G02X1762800Y21500I0J300D01*
G02X1763100Y21800I300J0D01*
G37*
G36*
G01X1753903Y22416D02*
G02X1754203Y22116I0J-300D01*
G02X1753903Y21816I-300J0D01*
G02X1753603Y22116I0J300D01*
G02X1753903Y22416I300J0D01*
G37*
G36*
G01X1749364Y39271D02*
G02X1749664Y38971I0J-300D01*
G02X1749364Y38671I-300J0D01*
G02X1749064Y38971I0J300D01*
G02X1749364Y39271I300J0D01*
G37*
G36*
G01X1758100Y37300D02*
G02X1758400Y37000I0J-300D01*
G02X1758100Y36700I-300J0D01*
G02X1757800Y37000I0J300D01*
G02X1758100Y37300I300J0D01*
G37*
G36*
G01X1835000Y73595D02*
Y71500D01*
X1835769Y70731D01*
X1835710Y70604D01*
G03X1837839Y68475I1451J-678D01*
G01X1837966Y68534D01*
X1838500Y68000D01*
X1840500D01*
X1842018Y66482D01*
Y51163D01*
X1841070Y50215D01*
Y45470D01*
X1840800Y45200D01*
X1826890D01*
X1825590Y46500D01*
X1825585D01*
X1819150Y52935D01*
G02X1819209Y53549I283J283D01*
G03X1818914Y56109I-813J1203D01*
G01X1818785Y56158D01*
Y61085D01*
X1817984Y61886D01*
Y62227D01*
X1813720Y66492D01*
X1813378D01*
X1811352Y68518D01*
X1798098D01*
G02X1797699Y68894I0J400D01*
G03X1796100Y70402I-1599J-94D01*
G02X1795700Y70821I0J400D01*
G03X1794100Y69296I-1600J77D01*
G02X1794500Y68877I0J-400D01*
G03Y68727I1600J-75D01*
G01Y68518D01*
X1784455D01*
X1784437Y68500D01*
X1774500D01*
X1773500Y69500D01*
Y78798D01*
X1773502D01*
Y80502D01*
X1773739Y80739D01*
X1777339D01*
X1778900Y82300D01*
X1792100D01*
X1792738Y82938D01*
X1792718Y82958D01*
Y83962D01*
X1795704D01*
Y83996D01*
X1797052Y82648D01*
X1797031Y82543D01*
G03X1798252Y80818I1423J-287D01*
G02X1798586Y80331I-55J-396D01*
G03X1800202Y81438I1414J-331D01*
G02X1799868Y81925I55J396D01*
G03X1798167Y83679I-1414J331D01*
G01X1798062Y83658D01*
X1795943Y85778D01*
X1795704D01*
Y86164D01*
X1792718D01*
Y92900D01*
X1792900D01*
X1795508Y95508D01*
Y99000D01*
X1795502Y99006D01*
Y99302D01*
X1795206D01*
X1795000Y99508D01*
Y100798D01*
X1795252D01*
Y102252D01*
X1795500Y102500D01*
X1802120D01*
X1803688Y104068D01*
X1805792D01*
X1807360Y102500D01*
X1821500D01*
X1822800Y101200D01*
Y99796D01*
G02X1822173Y99466I-400J-1D01*
G03X1820636Y97006I-823J-1196D01*
G01Y95304D01*
X1822204Y93736D01*
X1822800D01*
Y86660D01*
X1822905Y86555D01*
X1825005D01*
X1827200Y84360D01*
Y83249D01*
G02X1827012Y83049I-200J0D01*
G03Y80151I88J-1449D01*
G02X1827200Y79951I-12J-200D01*
G01Y79800D01*
X1828200Y78800D01*
X1831200D01*
X1831348Y78948D01*
X1831402D01*
Y79002D01*
X1831700Y79300D01*
Y81300D01*
X1831848Y81448D01*
X1834002D01*
Y81500D01*
X1834500D01*
X1835000Y81000D01*
Y80113D01*
X1833273Y78385D01*
X1833171Y78403D01*
G03X1833692Y74623I-341J-1973D01*
G02X1834234Y74415I172J-361D01*
G03X1835000Y73595I1480J614D01*
G37*
G36*
G01X1761986Y86028D02*
G03X1760712Y86954I-1622J-892D01*
G01X1760550Y86986D01*
Y91068D01*
X1760582D01*
Y92442D01*
X1760586Y92464D01*
G03Y93276I-1806J406D01*
G01X1760582Y93298D01*
Y94672D01*
X1760550D01*
Y94850D01*
X1760000Y95400D01*
X1754464D01*
X1754432Y95432D01*
X1754068D01*
X1749500Y100000D01*
X1746000D01*
X1743000Y103000D01*
Y103438D01*
X1745062Y105500D01*
X1753614D01*
X1753706Y105408D01*
X1762360D01*
X1765753Y102014D01*
X1767764D01*
X1772953Y107203D01*
X1780569D01*
X1780748Y107024D01*
Y104198D01*
X1780750D01*
Y103506D01*
X1779980Y102736D01*
Y96920D01*
X1780800Y96100D01*
X1781400D01*
X1783900Y93600D01*
Y88584D01*
X1783787Y88471D01*
X1780446D01*
X1780082Y88835D01*
X1775515D01*
X1774350Y90000D01*
Y91400D01*
X1773350Y92400D01*
X1770250D01*
X1769450Y91600D01*
Y86278D01*
X1769200Y86028D01*
X1761986D01*
G37*
G36*
G01X1766168Y103427D02*
X1763186Y106409D01*
X1754121D01*
X1753526Y107004D01*
Y108522D01*
X1753522Y108526D01*
Y109564D01*
X1753954Y109996D01*
X1758735D01*
X1759422Y109309D01*
X1762631D01*
X1763566Y110244D01*
Y113601D01*
X1764033Y114068D01*
Y117153D01*
X1764246Y117366D01*
X1767527D01*
X1767984Y116909D01*
Y114000D01*
X1771234Y110750D01*
X1775998D01*
Y110748D01*
X1778002D01*
Y110750D01*
X1779498D01*
Y110748D01*
X1781452D01*
X1781750Y110450D01*
Y108954D01*
X1781005Y108209D01*
X1772461D01*
X1767679Y103427D01*
X1766168D01*
G37*
G36*
G01X1784500Y122500D02*
X1782500D01*
X1782000Y122000D01*
Y117388D01*
G03Y117212I2100J-88D01*
G01Y112400D01*
X1781850Y112250D01*
X1781502D01*
Y112252D01*
X1779498D01*
Y112250D01*
X1778002D01*
Y112252D01*
X1775998D01*
Y112250D01*
X1774710D01*
Y112278D01*
X1772706D01*
Y112250D01*
X1772250D01*
X1771000Y113500D01*
Y119000D01*
X1773500Y121500D01*
X1775984D01*
X1776027Y121478D01*
G03X1776570Y121348I544J1072D01*
G01X1777970D01*
G03X1778513Y121478I-1J1202D01*
G01X1778556Y121500D01*
X1779000D01*
Y121929D01*
X1779024Y121974D01*
G03X1779059Y122042I-1050J584D01*
G01X1779074Y122074D01*
X1779282Y122282D01*
X1779203Y122362D01*
Y142112D01*
X1779503Y142412D01*
X1783088D01*
X1783500Y142000D01*
Y132000D01*
X1786399Y129101D01*
X1786398Y129017D01*
G03X1786461Y128557I1602J-15D01*
G01X1786468Y128530D01*
Y128302D01*
X1786448D01*
Y127502D01*
X1785748D01*
Y125498D01*
X1786448D01*
Y124448D01*
X1784500Y122500D01*
G37*
G36*
G01X1743351Y105762D02*
X1743064Y106049D01*
Y109960D01*
X1750312Y117208D01*
X1761767D01*
X1762002Y116974D01*
Y114160D01*
X1762006D01*
Y110592D01*
X1761842Y110428D01*
X1759802D01*
X1759185Y111045D01*
X1749823D01*
X1745280Y106502D01*
X1744674D01*
X1744647D01*
X1743908Y105762D01*
X1743351D01*
G37*
G36*
G01X1739512Y168970D02*
X1740265Y169723D01*
X1746415D01*
X1746861Y169277D01*
Y159184D01*
X1746179Y158502D01*
X1740311D01*
X1739512Y159301D01*
Y168970D01*
G37*
G36*
G01X1717400Y209300D02*
X1721000Y212900D01*
X1728800D01*
X1729750Y211950D01*
Y209250D01*
X1729200Y208700D01*
X1726600D01*
X1726300Y208400D01*
Y200500D01*
X1726000Y200200D01*
X1721400D01*
X1720700Y200900D01*
Y201600D01*
X1717400Y204900D01*
Y209300D01*
G37*
G36*
G01X1740150Y171200D02*
X1739200Y172150D01*
X1713100D01*
X1712800Y172450D01*
Y173833D01*
G02X1713279Y174225I400J0D01*
G03X1715110Y176319I317J1570D01*
G02X1715488Y176850I378J131D01*
G01X1724550D01*
X1726500Y174900D01*
X1747100D01*
X1748000Y175800D01*
Y177100D01*
X1748400Y177500D01*
X1750250D01*
X1750750Y177000D01*
Y171910D01*
X1750040Y171200D01*
X1740150D01*
G37*
G36*
G01X1733600Y239300D02*
X1733300Y239600D01*
Y252368D01*
X1741800D01*
Y239700D01*
X1741400Y239300D01*
X1733600D01*
G37*
G36*
G01X1722140Y509100D02*
X1720800Y510440D01*
Y520000D01*
X1722100Y521300D01*
X1730700D01*
X1732400Y519600D01*
Y512200D01*
X1732202Y512002D01*
X1727198D01*
Y511998D01*
X1725400Y510200D01*
Y509300D01*
X1725202Y509102D01*
X1723198D01*
Y509100D01*
X1722140D01*
G37*
G36*
G01X1773495Y514198D02*
X1773413Y514116D01*
X1769046D01*
X1768246Y514916D01*
X1759290D01*
X1758900Y515306D01*
Y522625D01*
X1759647Y523372D01*
X1772017D01*
X1773495Y521894D01*
Y514198D01*
G37*
G36*
G01X1747334Y508326D02*
Y501115D01*
X1746269Y500050D01*
X1740950D01*
X1731015Y490115D01*
X1718330D01*
X1717650Y490795D01*
Y497550D01*
X1717830Y497730D01*
X1721710D01*
X1722190Y498210D01*
Y498214D01*
X1722476Y498500D01*
Y507376D01*
X1722700Y507600D01*
X1723198D01*
Y507598D01*
X1725202D01*
Y507600D01*
X1725600D01*
X1727000Y509000D01*
X1727398D01*
Y508998D01*
X1732202D01*
Y509000D01*
X1746660D01*
X1747334Y508326D01*
G37*
G36*
G01X1721467Y499072D02*
X1721335Y498940D01*
X1717560D01*
X1717499Y499001D01*
Y502217D01*
X1717800Y502518D01*
X1721318D01*
X1721467Y502369D01*
Y499072D01*
G37*
G36*
G01X1761250Y495150D02*
X1760450Y495950D01*
Y500600D01*
X1761000Y501150D01*
X1765800D01*
X1767100Y502450D01*
Y511393D01*
X1767462Y511755D01*
X1773142D01*
X1773757Y511140D01*
X1777314D01*
X1778203Y512029D01*
Y513280D01*
X1777383Y514100D01*
X1776600D01*
X1776502Y514198D01*
Y519202D01*
X1776500D01*
Y522600D01*
X1777900Y524000D01*
X1783383D01*
X1784427Y522956D01*
Y522032D01*
X1787200Y519259D01*
Y514450D01*
X1781600Y508850D01*
Y496900D01*
X1779850Y495150D01*
X1761250D01*
G37*
G36*
G01X1757260Y502300D02*
X1747430Y512130D01*
X1739480D01*
X1737960Y513650D01*
Y538339D01*
X1739447Y539826D01*
X1746479D01*
X1747255Y539050D01*
Y537840D01*
X1747238Y537801D01*
G03Y535781I2290J-1010D01*
G01X1747255Y535742D01*
Y534440D01*
X1748966Y532729D01*
X1756040D01*
X1757500Y531269D01*
Y513500D01*
X1759108Y511892D01*
X1764108D01*
X1764500Y511500D01*
Y503750D01*
X1763050Y502300D01*
X1757260D01*
G37*
G36*
G01X1830900Y15100D02*
X1830600Y15400D01*
Y25099D01*
G03X1830945Y27989I-964J1581D01*
G01X1830600Y28334D01*
Y33000D01*
X1830900Y33300D01*
X1835800D01*
X1836606Y32494D01*
Y27816D01*
X1839184D01*
X1840000Y27000D01*
Y22301D01*
X1839980Y22260D01*
G03X1839848Y21456I1309J-628D01*
G01X1839859Y21359D01*
X1839000Y20500D01*
X1837000D01*
X1836800Y20300D01*
Y20120D01*
X1836606D01*
Y15806D01*
X1835900Y15100D01*
X1830900D01*
G37*
G36*
G01X1815000Y41800D02*
X1782762D01*
X1779744Y44818D01*
Y54580D01*
X1783563Y58399D01*
X1783638D01*
X1790729Y65490D01*
X1813305D01*
X1816983Y61812D01*
Y56367D01*
G02X1816379Y56023I-400J0D01*
G03Y53527I-742J-1248D01*
G02X1816983Y53183I204J-344D01*
G01Y43783D01*
X1815000Y41800D01*
G37*
G36*
G01X1785298Y83302D02*
X1784998Y83602D01*
Y94202D01*
X1783000Y96200D01*
Y97598D01*
X1783002D01*
Y102602D01*
X1783000D01*
Y103700D01*
X1782750Y103950D01*
Y104398D01*
X1782752D01*
Y106951D01*
X1783200Y107400D01*
X1787750D01*
X1788550Y106600D01*
Y105650D01*
X1788800Y105400D01*
X1791700D01*
X1793750Y103350D01*
Y102802D01*
X1793748D01*
Y100798D01*
X1793750D01*
Y99558D01*
X1793442Y99250D01*
Y95000D01*
X1792742Y94300D01*
X1792000D01*
X1791786Y94086D01*
Y93902D01*
X1791716D01*
Y83931D01*
X1791088Y83302D01*
X1785298D01*
G37*
G36*
G01X1831460Y136210D02*
X1829981Y137689D01*
Y147301D01*
X1831017Y148337D01*
X1838337D01*
X1839118Y147556D01*
Y140448D01*
X1839110Y140440D01*
Y139502D01*
X1838378D01*
Y136210D01*
X1831460D01*
G37*
G36*
G01X1815000Y164400D02*
X1815500Y164900D01*
X1821500D01*
X1821900Y164500D01*
Y154700D01*
X1821400Y154200D01*
X1815600D01*
X1815000Y154800D01*
Y164400D01*
G37*
G36*
G01X1832500Y152100D02*
X1830200Y154400D01*
Y158600D01*
X1830348Y158748D01*
X1833502D01*
Y158800D01*
X1833700D01*
X1834200Y159300D01*
X1834998D01*
Y159298D01*
X1837002D01*
Y159300D01*
X1837300D01*
X1838100Y158500D01*
Y152700D01*
X1837500Y152100D01*
X1832500D01*
G37*
G36*
G01X1802148Y154437D02*
X1801848Y154737D01*
Y158436D01*
X1801850D01*
Y163438D01*
X1801848D01*
Y170787D01*
X1802348Y171287D01*
X1812298D01*
X1814148Y169437D01*
Y164964D01*
X1813998Y164815D01*
Y158937D01*
X1807448D01*
X1805852Y157341D01*
X1805776Y157336D01*
G03X1804646Y156137I71J-1199D01*
G01Y154737D01*
G03X1804650Y154651I1201J13D01*
G01Y154437D01*
X1802148D01*
G37*
G36*
G01X1789848Y158237D02*
X1788348Y159737D01*
Y169637D01*
X1789183Y170472D01*
X1798213D01*
X1798848Y169837D01*
Y163438D01*
X1798846D01*
Y158435D01*
X1798648Y158237D01*
X1789848D01*
G37*
G36*
G01X1822948Y156937D02*
X1822902Y156984D01*
Y164915D01*
X1822748Y165068D01*
Y165948D01*
X1823800Y167000D01*
X1841498D01*
Y166998D01*
X1843502D01*
Y167000D01*
X1844400D01*
X1844900Y166500D01*
X1853200D01*
X1853900Y165800D01*
Y164300D01*
X1853500Y163900D01*
Y160502D01*
X1845085D01*
X1844884Y160300D01*
X1840978D01*
G03X1838768I-1105J-942D01*
G01X1837716D01*
X1837715Y160302D01*
X1837698D01*
X1837200Y160800D01*
X1837002D01*
Y160802D01*
X1834998D01*
Y160800D01*
X1830300D01*
X1826837Y157337D01*
X1826048D01*
X1825648Y156937D01*
X1822948D01*
G37*
G36*
G01X1794374Y511316D02*
X1806655D01*
X1807900Y510071D01*
Y498300D01*
X1806100Y496500D01*
X1796200D01*
X1794000Y498700D01*
Y510942D01*
X1794374Y511316D01*
G37*
G36*
G01X1784420Y495433D02*
X1783100Y496753D01*
Y508934D01*
X1786326Y512160D01*
X1791240D01*
X1792700Y510700D01*
Y498000D01*
X1793281Y497419D01*
Y495744D01*
X1792970Y495433D01*
X1784420D01*
G37*
G36*
G01X1821852Y501096D02*
G03X1820478Y502550I-1452J4D01*
G02X1820100Y502949I22J399D01*
G01Y515700D01*
X1821300Y516900D01*
X1830270D01*
X1833844Y513326D01*
Y501156D01*
X1833383Y500695D01*
X1822252D01*
G02X1821852Y501096I0J400D01*
G37*
G36*
G01X1782934Y526648D02*
X1782583Y526999D01*
Y536993D01*
X1782765Y537175D01*
Y538491D01*
X1780978Y540278D01*
Y546956D01*
X1781398Y547376D01*
X1794761D01*
X1795080Y547057D01*
X1805314D01*
X1806085Y546286D01*
Y539703D01*
X1805703Y539321D01*
X1801363D01*
G03X1800207Y539832I-1157J-1054D01*
G01X1794722D01*
X1794211Y539321D01*
X1793882D01*
X1793217Y538656D01*
Y526788D01*
X1793077Y526648D01*
X1782934D01*
G37*
G36*
G01X1846499Y32945D02*
X1846534Y32980D01*
X1846837D01*
X1846882Y33025D01*
X1848547D01*
X1848583Y32989D01*
Y27283D01*
X1848849Y27017D01*
Y20190D01*
X1848545Y19886D01*
Y15181D01*
X1848339Y14975D01*
X1847999D01*
X1847948Y14924D01*
X1846580D01*
X1846499Y15005D01*
Y32945D01*
G37*
G36*
G01X1852936Y12380D02*
X1852915Y12395D01*
X1851278D01*
X1849708Y13965D01*
Y19633D01*
X1849850Y19775D01*
Y27432D01*
X1849708Y27574D01*
Y32947D01*
X1849741Y32980D01*
X1856046D01*
X1856063Y32977D01*
G03X1856603I270J1541D01*
G01X1856620Y32980D01*
X1868136D01*
X1868436Y32680D01*
Y24280D01*
X1869636Y23080D01*
Y14438D01*
G02X1869031Y14094I-400J0D01*
G03X1866835Y12795I-745J-1246D01*
G02X1866435Y12380I-400J-15D01*
G01X1852936D01*
G37*
G36*
G01X1886825Y75531D02*
X1884076Y78280D01*
X1877142D01*
X1877140Y78278D01*
X1872822D01*
X1868100Y83000D01*
X1868008D01*
X1867963Y83046D01*
X1858054D01*
X1857800Y83300D01*
Y85300D01*
X1857400Y85700D01*
X1855738D01*
X1855019Y86419D01*
Y92119D01*
X1855700Y92800D01*
X1865415D01*
X1866499Y91716D01*
X1870072D01*
X1870352Y91436D01*
Y89469D01*
X1871184Y88638D01*
X1882542D01*
X1887494Y83686D01*
X1901318D01*
X1905856Y88224D01*
X1908476D01*
X1909600Y87100D01*
Y79700D01*
X1908100Y78200D01*
X1904982D01*
X1904505Y78677D01*
X1902798D01*
X1901388Y77267D01*
X1894623D01*
X1893761Y76405D01*
Y75783D01*
X1893509Y75531D01*
X1886825D01*
G37*
G36*
G01X1889218Y53830D02*
G02X1889518Y53530I0J-300D01*
G02X1889218Y53230I-300J0D01*
G02X1888918Y53530I0J300D01*
G02X1889218Y53830I300J0D01*
G37*
G36*
G01Y43830D02*
G02X1889518Y43530I0J-300D01*
G02X1889218Y43230I-300J0D01*
G02X1888918Y43530I0J300D01*
G02X1889218Y43830I300J0D01*
G37*
G36*
G01X1890803Y63489D02*
G02X1891103Y63189I0J-300D01*
G02X1890803Y62889I-300J0D01*
G02X1890503Y63189I0J300D01*
G02X1890803Y63489I300J0D01*
G37*
G36*
G01X1841910Y87690D02*
X1841900Y87700D01*
Y87900D01*
X1840800Y89000D01*
X1840600D01*
X1840400Y89200D01*
Y92400D01*
X1840700Y92700D01*
X1843900D01*
X1844200Y92400D01*
Y89100D01*
X1844300Y89000D01*
Y80490D01*
X1844105Y80295D01*
X1839655D01*
X1839260Y80690D01*
Y83290D01*
X1839580Y83610D01*
X1840740D01*
X1841910Y84780D01*
Y87690D01*
G37*
G36*
G01X1864390Y46000D02*
X1864337Y46039D01*
G03X1859284Y47011I-3551J-4839D01*
G03X1856161Y46754I-1086J-5903D01*
G03X1855033Y46791I-760J-5954D01*
G02X1854609Y47190I-24J399D01*
G01Y74091D01*
X1853315Y75385D01*
Y81605D01*
X1853754Y82044D01*
X1867548D01*
X1868212Y81380D01*
Y61410D01*
X1865438Y58637D01*
Y46238D01*
X1865200Y46000D01*
X1864390D01*
G37*
G36*
G01X1887798Y84802D02*
X1882961Y89639D01*
X1871599D01*
X1871354Y89884D01*
Y92314D01*
X1870433Y93235D01*
X1866695D01*
X1865930Y94000D01*
X1858476D01*
X1858206Y94270D01*
Y96721D01*
X1858355Y96870D01*
Y100705D01*
X1858750Y101100D01*
Y104607D01*
X1859300Y105157D01*
X1862946D01*
X1864134Y103969D01*
X1866390D01*
G03X1866822I216J5998D01*
G01X1868401D01*
X1874749Y97621D01*
X1885858D01*
X1887828Y99591D01*
X1895707D01*
X1896190Y99108D01*
Y91923D01*
X1896913Y91200D01*
X1899400D01*
X1900700Y89900D01*
Y85000D01*
X1900502Y84802D01*
X1887798D01*
G37*
G36*
G01X1873600Y113300D02*
X1873230Y113670D01*
Y121170D01*
X1872700Y121700D01*
X1867100D01*
X1866800Y122000D01*
Y123000D01*
X1866900Y123100D01*
X1872530D01*
X1873230Y123800D01*
Y129350D01*
X1873690Y129810D01*
X1889320D01*
X1889800Y129330D01*
Y127600D01*
X1890400Y127000D01*
X1893031D01*
X1893072Y126980D01*
G03X1893750Y126826I677J1410D01*
G01X1895466D01*
X1895594Y126697D01*
G02X1895311Y126014I-283J-283D01*
G01X1893750D01*
G03X1892959Y125800I-1J-1564D01*
G01X1890100D01*
X1889800Y125500D01*
Y119600D01*
X1890200Y119200D01*
X1896000D01*
X1896200Y119000D01*
Y118134D01*
X1893750D01*
G03X1892926Y117900I-1J-1564D01*
G01X1890800D01*
X1889800Y116900D01*
Y113700D01*
X1889400Y113300D01*
X1873600D01*
G37*
G36*
G01X1851691Y152600D02*
X1851615Y152676D01*
X1845824D01*
X1845300Y153200D01*
Y159300D01*
X1845500Y159500D01*
X1855500D01*
X1856000Y159000D01*
Y153100D01*
X1855500Y152600D01*
X1851691D01*
G37*
G36*
G01X1855250Y106050D02*
X1855000Y106300D01*
Y111550D01*
X1855600Y112150D01*
X1857039D01*
G03X1857181I71J1450D01*
G01X1858150D01*
X1859050Y113050D01*
X1864800D01*
X1864850Y113000D01*
Y108000D01*
X1864750Y107900D01*
X1860500D01*
X1858650Y106050D01*
X1855250D01*
G37*
G36*
G01X1846800Y95700D02*
G02X1847100Y95400I0J-300D01*
G02X1846800Y95100I-300J0D01*
G02X1846500Y95400I0J300D01*
G02X1846800Y95700I300J0D01*
G37*
G36*
G01X1887830Y102527D02*
G02X1888130Y102227I0J-300D01*
G02X1887830Y101927I-300J0D01*
G02X1887530Y102227I0J300D01*
G02X1887830Y102527I300J0D01*
G37*
G36*
G01X1885400Y147300D02*
G02X1885700Y147000I0J-300D01*
G02X1885400Y146700I-300J0D01*
G02X1885100Y147000I0J300D01*
G02X1885400Y147300I300J0D01*
G37*
G36*
G01X1895800Y149500D02*
G02X1896100Y149200I0J-300D01*
G02X1895800Y148900I-300J0D01*
G02X1895500Y149200I0J300D01*
G02X1895800Y149500I300J0D01*
G37*
G36*
G01X1882550Y99770D02*
G02X1882850Y99470I0J-300D01*
G02X1882550Y99170I-300J0D01*
G02X1882250Y99470I0J300D01*
G02X1882550Y99770I300J0D01*
G37*
G36*
G01X1878550D02*
G02X1878850Y99470I0J-300D01*
G02X1878550Y99170I-300J0D01*
G02X1878250Y99470I0J300D01*
G02X1878550Y99770I300J0D01*
G37*
G36*
G01X1852600Y97800D02*
G02X1852900Y97500I0J-300D01*
G02X1852600Y97200I-300J0D01*
G02X1852300Y97500I0J300D01*
G02X1852600Y97800I300J0D01*
G37*
G36*
G01X1840520Y136450D02*
X1840382Y136589D01*
Y139502D01*
X1840300D01*
Y139849D01*
X1842148Y141696D01*
X1842464D01*
Y146700D01*
X1842261D01*
Y149039D01*
X1844897Y151675D01*
X1851200D01*
X1851268Y151608D01*
Y148196D01*
X1851500D01*
Y145957D01*
X1851349Y145919D01*
G03X1853708Y142878I511J-2039D01*
G01X1854260D01*
X1854771Y143390D01*
X1856530D01*
X1856835Y143085D01*
Y142030D01*
X1856833Y142016D01*
G03Y141380I2330J-318D01*
G01X1856835Y141366D01*
Y140345D01*
X1857420Y139760D01*
X1857810D01*
X1858700Y138870D01*
Y137610D01*
X1858430Y137340D01*
X1845060D01*
X1844481Y136761D01*
X1844473Y136754D01*
G03X1844208Y136488I994J-1256D01*
G01X1844170Y136450D01*
X1840520D01*
G37*
G36*
G01X1872885Y172703D02*
Y166769D01*
X1872080Y165964D01*
X1868232D01*
X1867785Y166412D01*
Y172607D01*
X1868353Y173175D01*
X1872413D01*
X1872885Y172703D01*
G37*
G36*
G01X1858400Y251500D02*
G02X1858700Y251200I0J-300D01*
G02X1858400Y250900I-300J0D01*
G02X1858100Y251200I0J300D01*
G02X1858400Y251500I300J0D01*
G37*
G36*
G01X1843700Y253700D02*
G02X1844000Y253400I0J-300D01*
G02X1843700Y253100I-300J0D01*
G02X1843400Y253400I0J300D01*
G02X1843700Y253700I300J0D01*
G37*
G36*
G01X1852300Y252300D02*
G02X1852600Y252000I0J-300D01*
G02X1852300Y251700I-300J0D01*
G02X1852000Y252000I0J300D01*
G02X1852300Y252300I300J0D01*
G37*
G36*
G01X1897700Y436950D02*
X1897502Y437148D01*
Y448615D01*
X1894202Y451915D01*
Y464851D01*
X1894750Y465400D01*
X1898900D01*
X1899400Y464900D01*
Y452200D01*
X1899498Y452102D01*
Y451985D01*
X1902600Y448884D01*
Y437100D01*
X1902450Y436950D01*
X1897700D01*
G37*
G36*
G01X1892500Y465200D02*
X1893200Y464500D01*
Y451500D01*
X1896500Y448200D01*
Y437400D01*
X1896100Y437000D01*
X1884850D01*
X1884500Y437350D01*
Y448400D01*
X1881600Y451300D01*
Y464500D01*
X1882300Y465200D01*
X1892500D01*
G37*
G36*
G01X1903700Y449200D02*
X1900500Y452400D01*
Y466400D01*
X1899700Y467200D01*
X1893500D01*
X1892200Y468500D01*
Y474200D01*
X1893400Y475400D01*
X1905500D01*
X1906800Y474100D01*
Y468500D01*
X1905650Y467350D01*
X1903250D01*
X1902600Y466700D01*
Y453500D01*
X1905700Y450400D01*
Y437150D01*
X1905550Y437000D01*
X1903900D01*
X1903700Y437200D01*
Y449200D01*
G37*
G36*
G01X1888866Y584350D02*
X1886082Y587134D01*
Y598156D01*
X1887810Y599884D01*
G02X1888400Y599858I283J-283D01*
G03X1889182Y605044I2686J2247D01*
G02X1888564Y605380I-218J336D01*
G01Y608830D01*
G02X1889182Y609166I400J0D01*
G03Y615044I1904J2939D01*
G02X1888564Y615380I-218J336D01*
G01Y616852D01*
X1890713Y619000D01*
X1909400D01*
X1911500Y616900D01*
Y595200D01*
X1902754Y586454D01*
X1899650D01*
X1897546Y584350D01*
X1888866D01*
G37*
G36*
G01X1957044Y73554D02*
X1953091Y69600D01*
X1943723D01*
X1941346Y67223D01*
X1929337D01*
X1928300Y68260D01*
Y71906D01*
G03Y74306I-1410J1200D01*
G01Y80950D01*
X1930383Y83033D01*
X1941888D01*
X1941996Y82925D01*
G02X1941989Y82352I-282J-283D01*
G03X1941947Y79493I1380J-1450D01*
G01Y78597D01*
X1942189Y78355D01*
X1948883D01*
X1948944Y78416D01*
X1948996Y78430D01*
G03X1950377Y80975I-524J1932D01*
G02X1950758Y81498I381J123D01*
G01X1955098D01*
X1955738Y82138D01*
X1955755D01*
X1956414Y82798D01*
X1957902D01*
X1958146Y82554D01*
Y80023D01*
X1957100Y78977D01*
Y78774D01*
X1957044D01*
Y73554D01*
G37*
G36*
G01X1951558Y83140D02*
X1950998Y83700D01*
X1945700D01*
X1945100Y84300D01*
X1934300D01*
X1933500Y85100D01*
Y93200D01*
X1937150Y96850D01*
X1943076D01*
X1943112Y96835D01*
G03X1944208I548J1345D01*
G01X1944244Y96850D01*
X1946122D01*
X1946162Y96832D01*
G03X1947378I608J1318D01*
G01X1947418Y96850D01*
X1959850D01*
X1960800Y95900D01*
Y94140D01*
X1960770D01*
Y92170D01*
X1959886Y91286D01*
X1958016D01*
X1957435Y90705D01*
Y85235D01*
X1955340Y83140D01*
X1951558D01*
G37*
G36*
G01X1909227Y89727D02*
X1903101D01*
X1900398Y92430D01*
X1897628D01*
X1897380Y92678D01*
Y100662D01*
X1898884Y102166D01*
X1908697D01*
X1909682Y101181D01*
Y90182D01*
X1909227Y89727D01*
G37*
G36*
G01X1954060Y97965D02*
X1953990Y98035D01*
Y99120D01*
X1954082Y99212D01*
X1957148D01*
X1957250Y99314D01*
X1957253D01*
X1957559Y99620D01*
Y105984D01*
X1960109D01*
X1960113Y105983D01*
G03X1961306Y105989I525J14175D01*
G02X1961724Y105589I18J-400D01*
G01Y105416D01*
X1961659Y105351D01*
Y98251D01*
X1961373Y97965D01*
X1954060D01*
G37*
G36*
G01X1900100Y145400D02*
G02X1900400Y145100I0J-300D01*
G02X1900100Y144800I-300J0D01*
G02X1899800Y145100I0J300D01*
G02X1900100Y145400I300J0D01*
G37*
G36*
G01X1912100Y142900D02*
G02X1912400Y142600I0J-300D01*
G02X1912100Y142300I-300J0D01*
G02X1911800Y142600I0J300D01*
G02X1912100Y142900I300J0D01*
G37*
G36*
G01X1915030Y147550D02*
G02X1915330Y147250I0J-300D01*
G02X1915030Y146950I-300J0D01*
G02X1914730Y147250I0J300D01*
G02X1915030Y147550I300J0D01*
G37*
G36*
G01X1949360Y99970D02*
X1948700Y100630D01*
Y102030D01*
X1948692Y102038D01*
Y102732D01*
X1947998D01*
X1947990Y102740D01*
X1947692D01*
Y103232D01*
X1946088D01*
X1945340Y103980D01*
Y105446D01*
X1945780Y105886D01*
X1956459D01*
X1956558Y105788D01*
Y104403D01*
G02X1956009Y104032I-400J0D01*
G03X1955426Y104144I-581J-1452D01*
G01X1953736D01*
G03X1951620Y101844I-1010J-1194D01*
G01X1952448Y101016D01*
X1955426D01*
G03X1956250Y101250I1J1564D01*
G01X1956298Y101280D01*
X1956558D01*
Y100214D01*
X1953667D01*
X1953424Y99970D01*
X1952511D01*
G03X1952369I-71J-1450D01*
G01X1949360D01*
G37*
G36*
G01X1919635Y211622D02*
G03X1918174Y213930I-1146J891D01*
G02X1917687Y214321I-87J391D01*
G01Y217287D01*
X1918900Y218500D01*
X1941300D01*
X1941406Y218394D01*
Y216709D01*
X1942153Y215962D01*
X1944026D01*
X1944506Y215482D01*
Y212357D01*
X1943124Y210976D01*
X1919951D01*
G02X1919635Y211622I0J400D01*
G37*
G36*
G01X1899465Y180050D02*
X1899585Y180170D01*
X1913145D01*
X1913535Y179780D01*
Y166380D01*
X1913185Y166030D01*
X1899925D01*
X1899465Y166490D01*
Y180050D01*
G37*
G36*
G01X1924300Y236700D02*
X1924000Y237000D01*
Y244200D01*
X1924550Y244750D01*
X1927150D01*
X1927250Y244850D01*
X1946598D01*
Y236700D01*
X1924300D01*
G37*
G36*
G01X1953002Y220670D02*
X1955842D01*
Y228778D01*
X1953002D01*
Y229261D01*
G03X1952938Y229875I-3002J-3D01*
G02X1953329Y230357I391J82D01*
G01X1962439D01*
X1963814Y231732D01*
X1969968D01*
X1971700Y230000D01*
Y219577D01*
X1971300Y219177D01*
X1962834D01*
Y219236D01*
X1958082D01*
G03X1955680Y219177I-1181J-845D01*
G01X1953346D01*
G02X1952953Y219649I0J400D01*
G03X1953002Y220187I-2953J540D01*
G01Y220670D01*
G37*
G36*
G01X1941950Y227950D02*
Y222250D01*
X1941200Y221500D01*
X1911578D01*
G03X1910748Y222134I-1237J-760D01*
G01X1910699Y222149D01*
X1909859Y222989D01*
Y229735D01*
X1912068Y231944D01*
X1923344D01*
X1924177Y232777D01*
G02X1924757Y232762I283J-283D01*
G03X1924891Y232632I1076J975D01*
G02X1924948Y232084I-260J-304D01*
G03X1927044Y232303I1152J-884D01*
G02X1926987Y232851I260J304D01*
G03X1927259Y234021I-1152J884D01*
G02X1927651Y234500I392J79D01*
G01X1943500D01*
X1944000Y234000D01*
Y230000D01*
X1943682Y229682D01*
G03X1943239Y229239I781J-1224D01*
G01X1941950Y227950D01*
G37*
G36*
G01X1906822Y437056D02*
X1906702Y437176D01*
Y437298D01*
Y450815D01*
X1903700Y453816D01*
Y465150D01*
X1904050Y465500D01*
X1908550D01*
X1908900Y465150D01*
Y452700D01*
X1912000Y449600D01*
Y437200D01*
X1911856Y437056D01*
X1906822D01*
G37*
G36*
G01X1913300Y437100D02*
X1913100Y437300D01*
Y452100D01*
X1914300Y453300D01*
X1920500D01*
X1921500Y452300D01*
Y437250D01*
X1921350Y437100D01*
X1920773D01*
G03X1920627I-73J-1500D01*
G01X1917773D01*
G03X1917627I-73J-1500D01*
G01X1914773D01*
G03X1914627I-73J-1500D01*
G01X1913300D01*
G37*
G36*
G01X1909000Y475120D02*
X1909599Y475719D01*
X1910208Y475110D01*
X1913189D01*
X1913240Y475060D01*
X1916280D01*
X1918800Y472540D01*
Y465800D01*
X1918300Y465300D01*
Y455700D01*
X1917900Y455300D01*
X1910500D01*
X1909902Y455899D01*
Y465565D01*
X1909875Y465591D01*
Y466375D01*
X1909000Y467250D01*
Y475120D01*
G37*
G36*
G01X1943392Y601600D02*
X1938173Y606819D01*
X1938194Y606924D01*
G03X1936484Y608634I-1424J286D01*
G01X1936379Y608613D01*
X1935803Y609189D01*
X1935802Y609270D01*
G03X1933246Y610193I-1452J-20D01*
G01X1929711D01*
X1929518Y610386D01*
Y619518D01*
X1930000Y620000D01*
X1936300D01*
X1941800Y614500D01*
X1947800D01*
X1948900Y613400D01*
Y602700D01*
X1947800Y601600D01*
X1943392D01*
G37*
G36*
G01X1962272Y94250D02*
X1964157D01*
X1964471Y93936D01*
Y85686D01*
X1966746Y83411D01*
Y82605D01*
X1967912Y81439D01*
X1971039D01*
X1971921Y80557D01*
Y77998D01*
X1971922Y77999D01*
Y75157D01*
X1968558Y71793D01*
X1965840D01*
X1964304Y73329D01*
X1960295D01*
X1960048Y73576D01*
Y78774D01*
X1959944D01*
Y79306D01*
X1959650Y79600D01*
Y80508D01*
X1959670D01*
Y82708D01*
X1960450Y83487D01*
Y85510D01*
X1960460D01*
Y90443D01*
X1961300Y91284D01*
X1961484D01*
X1962250Y92050D01*
Y92136D01*
X1962272D01*
Y94250D01*
G37*
%LPC*%
G75*
G36*
G01X145913Y-57530D02*
X145628Y-57814D01*
X43852D01*
X43567Y-57530D01*
X34836D01*
Y-37300D01*
X145500D01*
Y-39050D01*
X450380D01*
Y-57500D01*
X394400D01*
Y-57530D01*
X145913D01*
G37*
G36*
G01X794100Y-37100D02*
X1115285D01*
Y-57100D01*
X794100D01*
Y-37100D01*
G37*
G36*
G01X461500Y-37300D02*
X783207D01*
Y-57200D01*
X461500D01*
Y-37300D01*
G37*
G36*
G01X1131655Y-37410D02*
X1370957D01*
Y-57634D01*
X1131655D01*
Y-37410D01*
G37*
G36*
G01X1386200Y-37300D02*
X1670408D01*
Y-57200D01*
X1386200D01*
Y-37300D01*
G37*
G36*
G01X213300Y659600D02*
Y639900D01*
X51200D01*
Y659600D01*
X213300D01*
G37*
G36*
G01X903000D02*
Y639900D01*
X615600D01*
Y659600D01*
X903000D01*
G37*
G36*
G01X20748Y61204D02*
Y57412D01*
X18744D01*
Y61216D01*
X19638D01*
Y64206D01*
X22042D01*
Y61204D01*
X20748D01*
G37*
G36*
G01X20422Y29836D02*
Y26046D01*
X18420D01*
Y29848D01*
X19314D01*
Y32840D01*
X21716D01*
Y29836D01*
X20422D01*
G37*
G36*
G01X7025Y423338D02*
X2024D01*
G02X1153Y426085I1J1512D01*
G03X1161Y426733I-230J327D01*
G02X3170Y427007I864J1167D01*
G03X3486Y426362I316J-245D01*
G01X5564D01*
G03X5880Y427007I0J400D01*
G02X7889Y426733I1145J893D01*
G03X7897Y426085I238J-321D01*
G02X8536Y424860I-872J-1234D01*
G01Y424765D01*
X8527Y424681D01*
G02X7025Y423338I-1502J168D01*
G37*
G36*
G01X17025D02*
X12024D01*
G02X11153Y426085I1J1512D01*
G03X11161Y426733I-230J327D01*
G02X13170Y427007I864J1167D01*
G03X13486Y426362I316J-245D01*
G01X17025D01*
G02X18260Y425722I0J-1512D01*
G03X18908Y425714I327J230D01*
G02Y423986I1167J-864D01*
G03X18260Y423978I-321J-238D01*
G02X17025Y423338I-1235J872D01*
G37*
G36*
G01X25949Y439185D02*
G02X23212Y438482I-1502J169D01*
G03X22564Y438490I-327J-230D01*
G02X22290Y440499I-1167J864D01*
G03X22936Y440815I246J316D01*
G01Y442893D01*
G03X22290Y443209I-400J0D01*
G02X22564Y445218I-893J1145D01*
G03X23212Y445226I321J238D01*
G02X25958Y444364I1235J-872D01*
G01X25959Y439354D01*
X25958D01*
Y439269D01*
X25949Y439185D01*
G37*
G36*
G01X10322Y572492D02*
Y568702D01*
X8320D01*
Y572504D01*
X9214D01*
Y575496D01*
X11616D01*
Y572492D01*
X10322D01*
G37*
G36*
G01Y536492D02*
Y532702D01*
X8320D01*
Y536504D01*
X9214D01*
Y539496D01*
X11616D01*
Y536492D01*
X10322D01*
G37*
G36*
G01X111262Y498092D02*
G03X111162Y498665I-321J239D01*
G02X113126Y499010I799J1212D01*
G03X113226Y498437I321J-239D01*
G02X111262Y498092I-799J-1212D01*
G37*
G36*
G01X103432Y592702D02*
Y594690D01*
X103975Y595234D01*
X103991Y595275D01*
G02X106034Y593488I1361J-505D01*
G01Y592702D01*
X107234D01*
Y592202D01*
X109734D01*
Y587198D01*
X107234D01*
Y586698D01*
X102232D01*
Y592702D01*
X103432D01*
G37*
G36*
G01Y554902D02*
Y556440D01*
X104035Y557044D01*
X104051Y557085D01*
G02X106034Y555268I1361J-505D01*
G01Y554902D01*
X107234D01*
Y554402D01*
X109734D01*
Y549398D01*
X107234D01*
Y548898D01*
X102232D01*
Y554902D01*
X103432D01*
G37*
G36*
G01X90071Y523153D02*
G03X90674Y523075I335J219D01*
G02X90434Y521206I976J-1075D01*
G03X89831Y521284I-335J-219D01*
G02X90071Y523153I-976J1075D01*
G37*
G36*
G01X106909Y517453D02*
G03X107040Y517102I131J-151D01*
G01X107234D01*
Y516602D01*
X109734D01*
Y511598D01*
X107234D01*
Y511098D01*
X102232D01*
Y517102D01*
X103432D01*
Y517864D01*
X104581Y519014D01*
X104597Y519055D01*
G02X106909Y517453I1361J-505D01*
G37*
G36*
G01X134446Y345026D02*
Y341234D01*
X132444D01*
Y345038D01*
X133338D01*
Y348028D01*
X135740D01*
Y345026D01*
X134446D01*
G37*
G36*
G01X154008Y338902D02*
X156122Y341016D01*
Y341920D01*
X143247D01*
X142498Y342669D01*
Y361971D01*
X143678Y363150D01*
X164766D01*
X166202Y361715D01*
Y344485D01*
X163637Y341920D01*
X159126D01*
Y339772D01*
X155252Y335898D01*
X151712D01*
X151049D01*
X148622D01*
X147920Y335196D01*
X147513D01*
Y335198D01*
X144909D01*
G02X144008Y336100I1J902D01*
G01Y338700D01*
G02X144909Y339602I901J1D01*
G01X147509D01*
G02X148025Y339439I-1J-902D01*
G01X148077Y339403D01*
X148082D01*
X148584Y338902D01*
X151062D01*
X151716D01*
X154008D01*
G37*
G36*
G01X134446Y313026D02*
Y309234D01*
X132444D01*
Y313038D01*
X133338D01*
Y316028D01*
X135740D01*
Y313026D01*
X134446D01*
G37*
G36*
G01X145825Y303893D02*
Y303898D01*
X143100D01*
G02X142198Y304800I0J902D01*
G01Y307400D01*
G02X143100Y308302I902J0D01*
G01X145700D01*
G02X145790Y308297I-5J-902D01*
G01X145800Y308296D01*
X146113D01*
X146808Y307602D01*
X152054D01*
X152609D01*
X153478D01*
X153498Y307622D01*
Y309862D01*
X142598D01*
Y331864D01*
X163352D01*
X165802Y329415D01*
Y312285D01*
X163378Y309862D01*
X156502D01*
Y306378D01*
X155602Y305478D01*
Y304598D01*
X152601D01*
X152054D01*
X146822D01*
X146116Y303893D01*
X145825D01*
G37*
G36*
G01X146200Y275102D02*
X148838D01*
X149174D01*
X149874Y274402D01*
X154605D01*
X155000Y274796D01*
Y275009D01*
X154998Y275011D01*
Y277900D01*
X154906Y277992D01*
X143385D01*
X142598Y278778D01*
Y299308D01*
X143285Y299994D01*
X164052D01*
X166502Y297545D01*
Y280515D01*
X163978Y277992D01*
X158002D01*
Y276172D01*
X158202Y275972D01*
Y271398D01*
X155203D01*
X154625D01*
X149902D01*
X149203Y270699D01*
X148827D01*
G02X148800Y270698I-47J900D01*
G01X146200D01*
G02X145298Y271600I0J902D01*
G01Y274200D01*
G02X146200Y275102I902J0D01*
G37*
G36*
G01X134446Y249026D02*
Y245234D01*
X132444D01*
Y249038D01*
X133338D01*
Y252028D01*
X135740D01*
Y249026D01*
X134446D01*
G37*
G36*
G01X145027Y238799D02*
G02X145000Y238798I-47J900D01*
G01X142400D01*
G02X141498Y239700I0J902D01*
G01Y242300D01*
G02X142400Y243202I902J0D01*
G01X145000D01*
G02X145047Y243200I-15J-901D01*
G01X145443D01*
X146142Y242502D01*
X147538D01*
X148026Y242014D01*
X151170D01*
X151732D01*
X152588D01*
X153698Y243124D01*
Y245730D01*
X153436Y245992D01*
X143385D01*
X142598Y246778D01*
Y267308D01*
X143285Y267994D01*
X164052D01*
X166502Y265545D01*
Y248515D01*
X163978Y245992D01*
X157102D01*
X156702Y245592D01*
Y241880D01*
Y240992D01*
X154720Y239010D01*
X154708D01*
X151740D01*
X151115D01*
X146978D01*
X146766Y238799D01*
X145027D01*
G37*
G36*
G01X134446Y217026D02*
Y213234D01*
X132444D01*
Y217038D01*
X133338D01*
Y220028D01*
X135740D01*
Y217026D01*
X134446D01*
G37*
G36*
G01X153278Y209802D02*
X155514Y212037D01*
Y213704D01*
X155356Y213862D01*
X143385D01*
X142598Y214648D01*
Y235178D01*
X143285Y235864D01*
X164052D01*
X166502Y233415D01*
Y216385D01*
X163978Y213862D01*
X158684D01*
X158516Y213694D01*
Y210793D01*
Y209912D01*
X155402Y206798D01*
X155256D01*
X152411D01*
X151784D01*
X148923D01*
X145889D01*
X145839Y206671D01*
G02X145000Y206098I-839J328D01*
G01X142400D01*
G02X141498Y207000I0J902D01*
G01Y209600D01*
G02X142400Y210502I902J0D01*
G01X145000D01*
G02X145839Y209929I0J-901D01*
G01X145889Y209802D01*
X148906D01*
X151854D01*
X152447D01*
X153278D01*
G37*
G36*
G01X134446Y377026D02*
Y373234D01*
X132444D01*
Y377038D01*
X133338D01*
Y380028D01*
X135740D01*
Y377026D01*
X134446D01*
G37*
G36*
G01X273494Y297940D02*
G02X273560Y298045I192J-47D01*
G02X273587Y298063I177J-237D01*
G02X273699Y298092I101J-158D01*
G02X273692Y295624I-205J-1233D01*
G01X273664Y295627D01*
G03X273649Y295629I-25J-134D01*
G02X273636Y295634I55J162D01*
G02X273614Y295640I36J177D01*
G03X273598Y295648I-89J-157D01*
G02X273565Y295669I47J110D01*
G02X273554Y295679I56J73D01*
G02X273532Y295700I110J137D01*
G02X273527Y295708I13J14D01*
G03X273518Y295719I-364J-288D01*
G01Y295720D01*
X273514Y295727D01*
G02X273510Y295734I8J9D01*
G01X273509Y295738D01*
X273508Y295739D01*
G03X273504Y295745I-22J-10D01*
G01Y295746D01*
X273502Y295754D01*
X273495Y295773D01*
G02X273489Y295799I173J54D01*
G01X273487Y295812D01*
X273488D01*
G03X273487Y295837I-92J9D01*
G01X273486D01*
Y295856D01*
G02X273488Y295952I1069J26D01*
G03X273486Y296010I-439J14D01*
G03X273592Y296017I-5J885D01*
G03X273769Y296060I-76J700D01*
G01X273827Y296080D01*
G03X273996Y296181I-279J659D01*
G03X274058Y296232I-599J792D01*
G03X274156Y296338I-2279J2206D01*
G02X274225Y296438I781J-465D01*
G03X274317Y296672I-851J470D01*
G03X274338Y296854I-610J163D01*
G03X274328Y296986I-1660J-59D01*
G03X274251Y297231I-1035J-191D01*
G03X274139Y297405I-764J-369D01*
G03X273962Y297564I-770J-679D01*
G03X273774Y297657I-511J-796D01*
G03X273623Y297696I-298J-844D01*
G02X273606Y297699I4J73D01*
G01X273576Y297704D01*
X273536Y297706D01*
X273487Y297707D01*
G02X273488Y297744I180J14D01*
G01Y297873D01*
G02X273494Y297940I264J10D01*
G37*
G36*
G01Y309642D02*
G02X273560Y309747I192J-48D01*
G02X273587Y309765I177J-237D01*
G02X273699Y309793I99J-159D01*
G02X273692Y307325I-205J-1233D01*
G01X273664Y307328D01*
G03X273649Y307330I-25J-134D01*
G02X273636Y307335I55J162D01*
G02X273614Y307341I36J177D01*
G03X273598Y307349I-89J-157D01*
G02X273565Y307370I47J111D01*
G02X273554Y307380I56J73D01*
G02X273532Y307401I110J137D01*
G02X273527Y307410I13J13D01*
G03X273518Y307420I-350J-306D01*
G01Y307421D01*
X273514Y307428D01*
G02X273510Y307435I8J9D01*
G01X273509Y307439D01*
X273508Y307440D01*
G03X273504Y307446I-22J-10D01*
G01Y307447D01*
X273502Y307455D01*
X273495Y307474D01*
G02X273489Y307500I173J54D01*
G01X273487Y307513D01*
X273488D01*
G03X273487Y307538I-92J9D01*
G01X273486D01*
Y307558D01*
G02X273488Y307653I1069J25D01*
G03X273486Y307711I-439J14D01*
G03X273592Y307719I-13J885D01*
G03X273769Y307761I-73J701D01*
G01X273827Y307782D01*
G03X273996Y307882I-276J660D01*
G03X274058Y307934I-606J786D01*
G03X274156Y308039I-2269J2216D01*
G02X274225Y308139I781J-465D01*
G03X274317Y308373I-851J470D01*
G03X274338Y308555I-610J163D01*
G03X274328Y308687I-1660J-59D01*
G03X274251Y308932I-1034J-191D01*
G03X274139Y309106I-764J-369D01*
G03X273962Y309265I-769J-679D01*
G03X273774Y309358I-511J-796D01*
G03X273623Y309398I-304J-842D01*
G02X273606Y309400I0J73D01*
G01X273576Y309406D01*
X273536Y309407D01*
X273487Y309408D01*
G02X273488Y309445I180J14D01*
G01Y309574D01*
G02X273494Y309642I264J11D01*
G37*
G36*
G01X273699Y317591D02*
G02X273692Y315123I-205J-1233D01*
G01X273664Y315126D01*
G03X273649Y315128I-25J-134D01*
G02X273636Y315133I55J162D01*
G02X273614Y315139I36J177D01*
G03X273598Y315147I-89J-157D01*
G02X273565Y315168I47J111D01*
G02X273554Y315178I56J73D01*
G02X273532Y315199I110J137D01*
G02X273527Y315208I13J13D01*
G01X273526D01*
G03X273518Y315219I-380J-268D01*
G01Y315220D01*
X273514Y315226D01*
G02X273510Y315233I8J9D01*
G01X273509Y315237D01*
X273508Y315238D01*
G03X273504Y315246I-24J-7D01*
G01X273502Y315253D01*
X273495Y315272D01*
G02X273489Y315298I173J54D01*
G01X273487Y315311D01*
X273488D01*
G03X273487Y315336I-92J9D01*
G01X273486D01*
Y315356D01*
G02X273488Y315451I1069J25D01*
G03X273486Y315510I-439J15D01*
G03X273592Y315517I-5J884D01*
G03X273769Y315559I-73J701D01*
G01X273827Y315580D01*
G03X273996Y315680I-276J660D01*
G03X274058Y315732I-606J786D01*
G03X274156Y315837I-2269J2216D01*
G02X274225Y315937I781J-465D01*
G03X274317Y316172I-852J469D01*
G03X274338Y316353I-610J162D01*
G03X274328Y316485I-1660J-59D01*
G03X274251Y316730I-1034J-191D01*
G03X274139Y316904I-764J-369D01*
G03X273962Y317063I-769J-679D01*
G03X273774Y317156I-511J-796D01*
G03X273623Y317196I-304J-842D01*
G02X273606Y317198I0J73D01*
G01X273576Y317204D01*
X273536Y317206D01*
X273487D01*
G02X273488Y317243I180J14D01*
G01Y317372D01*
G02X273494Y317440I264J11D01*
G02X273560Y317545I192J-48D01*
G02X273587Y317563I177J-237D01*
G02X273699Y317591I99J-159D01*
G37*
G36*
G01Y290289D02*
G02X273692Y287821I-205J-1233D01*
G01X273664Y287824D01*
G03X273649Y287826I-25J-134D01*
G02X273636Y287831I55J162D01*
G02X273614Y287837I36J177D01*
G03X273598Y287845I-89J-157D01*
G02X273565Y287866I47J111D01*
G02X273554Y287876I56J73D01*
G02X273532Y287897I110J137D01*
G02X273527Y287906I13J13D01*
G01X273526D01*
G03X273518Y287917I-380J-268D01*
G01Y287918D01*
X273514Y287924D01*
G02X273510Y287931I8J9D01*
G01X273509Y287935D01*
X273508Y287936D01*
G03X273504Y287944I-24J-7D01*
G01X273502Y287951D01*
X273495Y287970D01*
G02X273489Y287997I173J53D01*
G01X273487Y288009D01*
X273488D01*
G03X273487Y288034I-92J9D01*
G01X273486D01*
Y288054D01*
G02X273488Y288149I1069J25D01*
G03X273486Y288208I-439J15D01*
G03X273592Y288215I-5J884D01*
G03X273769Y288257I-73J701D01*
G01X273827Y288278D01*
G03X273996Y288378I-276J660D01*
G03X274058Y288430I-606J786D01*
G03X274156Y288535I-2269J2216D01*
G02X274225Y288635I781J-465D01*
G03X274317Y288870I-852J469D01*
G03X274338Y289051I-610J162D01*
G03X274328Y289183I-1660J-59D01*
G03X274251Y289428I-1034J-191D01*
G03X274139Y289602I-764J-369D01*
G03X273962Y289761I-769J-679D01*
G03X273774Y289854I-511J-796D01*
G03X273623Y289894I-304J-842D01*
G02X273606Y289896I0J73D01*
G01X273576Y289902D01*
X273536Y289904D01*
X273487D01*
G02X273488Y289941I180J14D01*
G01Y290071D01*
G02X273494Y290138I264J10D01*
G02X273560Y290243I192J-48D01*
G02X273587Y290261I177J-237D01*
G02X273699Y290289I99J-159D01*
G37*
G36*
G01X270105Y323089D02*
X270106Y323096D01*
Y323224D01*
X270105Y323226D01*
G02X270112Y323290I264J4D01*
G02X270178Y323395I191J-47D01*
G02X270204Y323413I181J-233D01*
G02X270316Y323441I99J-158D01*
G02X270309Y320976I-206J-1232D01*
G01X270281Y320979D01*
X270259Y320983D01*
G02X270254Y320985I60J158D01*
G02X270238Y320989I36J176D01*
G01X270214Y320999D01*
G02X270184Y321020I53J107D01*
G02X270172Y321030I52J75D01*
G02X270151Y321051I112J133D01*
G02X270148Y321055I12J12D01*
G01X270141Y321065D01*
X270136Y321071D01*
X270135Y321072D01*
X270129Y321082D01*
G02X270128Y321085I9J5D01*
G01X270124Y321095D01*
X270120Y321103D01*
Y321105D01*
X270114Y321124D01*
G02X270108Y321150I171J53D01*
G01X270105Y321163D01*
X270106D01*
Y321207D01*
X270105Y321211D01*
G02X270106Y321302I1068J34D01*
G03X270105Y321360I-440J21D01*
G03X270209Y321367I-7J885D01*
G03X270387Y321409I-72J702D01*
G01X270444Y321430D01*
G03X270614Y321530I-275J662D01*
G03X270676Y321582I-607J787D01*
G03X270775Y321688I-2269J2218D01*
G02X270843Y321788I783J-459D01*
G03X270936Y322022I-851J474D01*
G03X270956Y322204I-612J159D01*
G03X270947Y322336I-1662J-47D01*
G03X270869Y322581I-1035J-195D01*
G03X270758Y322756I-767J-364D01*
G03X270579Y322916I-769J-681D01*
G03X270391Y323008I-507J-799D01*
G03X270240Y323048I-304J-843D01*
G02X270228Y323049I0J72D01*
G01X270221Y323051D01*
X270193Y323056D01*
X270154Y323058D01*
X270106D01*
G02X270105Y323089I178J21D01*
G37*
G36*
G01X270108Y319188D02*
Y319326D01*
G02X270115Y319390I264J4D01*
G02X270181Y319495I191J-47D01*
G02X270207Y319513I181J-233D01*
G02X270319Y319541I99J-158D01*
G02X270312Y317076I-206J-1232D01*
G01X270284Y317079D01*
X270262Y317083D01*
G02X270257Y317085I60J158D01*
G02X270241Y317088I25J178D01*
G01X270219Y317099D01*
X270218D01*
G02X270186Y317120I49J109D01*
G02X270175Y317130I56J72D01*
G02X270153Y317151I109J136D01*
G02X270151Y317154I13J11D01*
G01X270143Y317166D01*
X270139Y317171D01*
X270138Y317172D01*
X270132Y317182D01*
G02X270131Y317184I9J6D01*
G01X270129Y317188D01*
X270116Y317224D01*
G02X270110Y317250I172J53D01*
G01X270108Y317263D01*
X270110Y317275D01*
X270108Y317287D01*
Y317307D01*
X270107Y317310D01*
G02X270109Y317402I1068J23D01*
G03X270107Y317460I-440J14D01*
G03X270212Y317467I-6J885D01*
G03X270390Y317509I-72J702D01*
G01X270447Y317530D01*
G03X270617Y317630I-275J662D01*
G03X270679Y317682I-607J787D01*
G03X270777Y317788I-2280J2206D01*
G02X270846Y317888I780J-465D01*
G03X270938Y318122I-852J470D01*
G03X270959Y318304I-611J163D01*
G03X270949Y318436I-1661J-59D01*
G03X270872Y318681I-1035J-191D01*
G03X270760Y318856I-766J-367D01*
G03X270582Y319016I-771J-679D01*
G03X270394Y319108I-508J-799D01*
G03X270243Y319148I-304J-843D01*
G02X270231Y319149I0J72D01*
G01X270224Y319151D01*
X270196Y319156D01*
X270156Y319158D01*
X270108D01*
G02Y319188I179J15D01*
G37*
G36*
G01X273488Y313339D02*
Y313475D01*
G02X273495Y313539I264J4D01*
G02X273561Y313644I191J-47D01*
G02X273587Y313662I180J-233D01*
G02X273700Y313691I100J-157D01*
G02X273692Y311225I-205J-1232D01*
G01X273665Y311228D01*
X273645Y311231D01*
G02X273637Y311235I72J153D01*
G02X273621Y311239I35J176D01*
G01X273597Y311249D01*
G02X273567Y311270I52J107D01*
G02X273555Y311280I52J75D01*
G02X273534Y311301I112J133D01*
G02X273531Y311305I12J12D01*
G01X273524Y311314D01*
X273519Y311320D01*
X273510Y311338D01*
X273508Y311340D01*
X273503Y311355D01*
X273497Y311374D01*
G02X273491Y311399I171J54D01*
G01X273488Y311412D01*
Y311460D01*
G02X273489Y311552I1068J34D01*
G03X273488Y311609I-440J21D01*
G03X273592Y311616I-7J886D01*
G03X273770Y311659I-75J702D01*
G01X273827Y311679D01*
G03X273997Y311780I-278J661D01*
G03X274059Y311831I-600J793D01*
G03X274158Y311938I-2279J2208D01*
G02X274227Y312038I780J-464D01*
G03X274319Y312271I-852J471D01*
G03X274339Y312454I-612J159D01*
G03X274330Y312586I-1662J-47D01*
G03X274253Y312831I-1036J-191D01*
G03X274141Y313006I-766J-367D01*
G03X273962Y313165I-767J-683D01*
G03X273774Y313258I-511J-797D01*
G03X273623Y313297I-299J-845D01*
G02X273611Y313298I0J72D01*
G01X273604Y313300D01*
X273576Y313305D01*
X273537Y313307D01*
X273489Y313308D01*
G02X273488Y313339I178J21D01*
G37*
G36*
G01Y305538D02*
Y305676D01*
G02X273495Y305740I264J4D01*
G02X273561Y305845I191J-47D01*
G02X273587Y305863I181J-233D01*
G02X273699Y305891I99J-158D01*
G02X273692Y303426I-206J-1232D01*
G01X273664Y303429D01*
X273642Y303433D01*
G02X273637Y303435I60J158D01*
G02X273621Y303438I25J178D01*
G01X273599Y303449D01*
X273598D01*
G02X273566Y303470I49J109D01*
G02X273555Y303480I56J72D01*
G02X273533Y303501I109J136D01*
G02X273529Y303505I11J15D01*
G01X273523Y303515D01*
X273519Y303521D01*
X273518Y303522D01*
X273512Y303532D01*
G02X273511Y303534I9J6D01*
G01X273509Y303538D01*
X273496Y303574D01*
G02X273490Y303600I172J53D01*
G01X273488Y303613D01*
X273490Y303625D01*
X273488Y303637D01*
Y303657D01*
X273487Y303660D01*
G02X273489Y303752I1068J23D01*
G03X273487Y303810I-440J14D01*
G03X273592Y303817I-6J886D01*
G03X273769Y303859I-73J702D01*
G01X273827Y303880D01*
G03X273997Y303980I-275J662D01*
G03X274059Y304032I-607J787D01*
G03X274157Y304138I-2280J2206D01*
G02X274226Y304238I780J-465D01*
G03X274318Y304472I-852J470D01*
G03X274339Y304654I-611J163D01*
G03X274329Y304786I-1661J-59D01*
G03X274252Y305031I-1035J-191D01*
G03X274140Y305206I-766J-367D01*
G03X273962Y305366I-771J-679D01*
G03X273774Y305458I-508J-799D01*
G03X273623Y305498I-304J-843D01*
G02X273611Y305499I0J72D01*
G01X273604Y305501D01*
X273576Y305506D01*
X273536Y305508D01*
X273488D01*
G02Y305538I179J15D01*
G37*
G36*
G01Y301629D02*
Y301766D01*
G02X273495Y301830I264J4D01*
G02X273561Y301935I191J-47D01*
G02X273587Y301953I181J-233D01*
G02X273700Y301981I99J-158D01*
G02X273692Y299515I-205J-1232D01*
G01X273665Y299518D01*
X273645Y299521D01*
G02X273637Y299525I72J154D01*
G02X273621Y299529I35J176D01*
G01X273597Y299539D01*
G02X273567Y299560I52J107D01*
G02X273555Y299570I52J75D01*
G02X273534Y299591I112J133D01*
G02X273531Y299594I11J14D01*
G01X273523Y299606D01*
X273519Y299610D01*
X273510Y299628D01*
X273508Y299630D01*
X273503Y299645D01*
X273497Y299664D01*
G02X273491Y299689I171J54D01*
G01X273488Y299702D01*
Y299751D01*
G02X273489Y299842I1068J34D01*
G03X273488Y299899I-440J21D01*
G03X273592Y299907I-16J886D01*
G03X273770Y299949I-72J702D01*
G01X273827Y299970D01*
G03X273997Y300070I-275J662D01*
G03X274059Y300122I-607J787D01*
G03X274158Y300228I-2269J2218D01*
G02X274227Y300328I780J-464D01*
G03X274319Y300561I-852J471D01*
G03X274339Y300744I-612J159D01*
G03X274330Y300876I-1662J-47D01*
G03X274253Y301121I-1036J-191D01*
G03X274141Y301296I-766J-367D01*
G03X273962Y301455I-767J-683D01*
G03X273774Y301548I-511J-796D01*
G03X273623Y301588I-304J-843D01*
G02X273608Y301589I-3J72D01*
G01X273606Y301590D01*
X273576Y301596D01*
X273537Y301597D01*
X273489Y301598D01*
G02X273488Y301629I178J21D01*
G37*
G36*
G01X273487Y293851D02*
X273488Y293857D01*
Y293985D01*
X273487Y293986D01*
G02X273495Y294051I264J1D01*
G02X273560Y294156I191J-46D01*
G02X273586Y294174I181J-233D01*
G02X273699Y294203I100J-157D01*
G02X273691Y291737I-205J-1232D01*
G01X273664Y291740D01*
X273644Y291743D01*
G02X273636Y291747I72J153D01*
G02X273599Y291759I37J176D01*
G02X273566Y291781I49J109D01*
G02X273554Y291792I55J72D01*
G02X273533Y291813I112J133D01*
G02X273530Y291817I12J12D01*
G01X273523Y291826D01*
X273518Y291832D01*
X273509Y291850D01*
X273508Y291851D01*
X273507Y291855D01*
X273505Y291858D01*
X273503Y291867D01*
X273496Y291886D01*
G02X273490Y291911I171J54D01*
G01X273487Y291924D01*
X273488D01*
Y291968D01*
X273487Y291972D01*
G02X273488Y292064I1068J34D01*
G03X273487Y292121I-439J21D01*
G03X273592Y292128I-6J886D01*
G03X273769Y292170I-73J702D01*
G01X273826Y292191D01*
G03X273996Y292292I-277J660D01*
G03X274058Y292343I-600J792D01*
G03X274157Y292449I-2269J2218D01*
G02X274226Y292549I780J-464D01*
G03X274318Y292783I-853J470D01*
G03X274338Y292965I-612J159D01*
G03X274329Y293098I-1662J-46D01*
G03X274252Y293342I-1035J-193D01*
G03X274140Y293518I-767J-365D01*
G03X273961Y293677I-767J-683D01*
G03X273773Y293770I-511J-797D01*
G03X273622Y293809I-299J-845D01*
G02X273610Y293810I0J72D01*
G01X273603Y293812D01*
X273576Y293817D01*
X273536Y293819D01*
X273488Y293820D01*
G02X273487Y293851I178J21D01*
G37*
G36*
G01X273488Y286042D02*
Y286178D01*
G02X273495Y286242I264J4D01*
G02X273561Y286347I191J-47D01*
G02X273587Y286365I181J-233D01*
G02X273700Y286394I100J-157D01*
G02X273692Y283928I-205J-1232D01*
G01X273665Y283931D01*
X273645Y283934D01*
G02X273637Y283938I72J153D01*
G02X273600Y283950I36J176D01*
G02X273567Y283972I49J109D01*
G02X273555Y283983I55J72D01*
G02X273534Y284004I112J133D01*
G02X273531Y284008I12J12D01*
G01X273524Y284017D01*
X273519Y284023D01*
X273510Y284041D01*
X273508Y284043D01*
X273503Y284058D01*
X273497Y284077D01*
G02X273491Y284102I171J54D01*
G01X273488Y284115D01*
Y284163D01*
G02X273489Y284255I1068J34D01*
G03X273488Y284312I-440J21D01*
G03X273592Y284319I-7J886D01*
G03X273770Y284361I-72J702D01*
G01X273827Y284382D01*
G03X273997Y284483I-277J661D01*
G03X274059Y284534I-600J792D01*
G03X274158Y284640I-2269J2218D01*
G02X274227Y284740I780J-464D01*
G03X274319Y284974I-853J470D01*
G03X274339Y285156I-612J159D01*
G03X274330Y285289I-1662J-46D01*
G03X274253Y285533I-1035J-193D01*
G03X274141Y285708I-766J-367D01*
G03X273962Y285868I-769J-681D01*
G03X273774Y285960I-507J-799D01*
G03X273623Y286000I-304J-843D01*
G02X273611Y286001I0J72D01*
G01X273604Y286003D01*
X273576Y286008D01*
X273537Y286010D01*
X273489Y286011D01*
G02X273488Y286042I178J21D01*
G37*
G36*
G01X270108Y284087D02*
Y284223D01*
G02X270115Y284287I264J4D01*
G02X270181Y284392I191J-47D01*
G02X270207Y284410I181J-233D01*
G02X270320Y284438I99J-157D01*
G02X270312Y281973I-206J-1232D01*
G01X270285Y281976D01*
X270265Y281979D01*
G02X270257Y281983I72J153D01*
G02X270243Y281985I18J178D01*
G01X270216Y281997D01*
G02X270187Y282017I52J107D01*
G02X270175Y282027I52J75D01*
G02X270170Y282031I106J138D01*
G01X270133Y282067D01*
X270129Y282087D01*
X270123Y282103D01*
X270117Y282122D01*
G02X270111Y282147I171J54D01*
G01X270108Y282160D01*
Y282208D01*
G02X270109Y282300I1068J34D01*
G03X270108Y282357I-440J21D01*
G03X270213Y282364I-6J886D01*
G03X270390Y282406I-73J702D01*
G01X270447Y282427D01*
G03X270617Y282527I-275J662D01*
G03X270679Y282579I-607J787D01*
G03X270778Y282685I-2269J2218D01*
G02X270847Y282785I780J-464D01*
G03X270939Y283019I-853J470D01*
G03X270959Y283201I-612J159D01*
G03X270950Y283334I-1662J-46D01*
G03X270873Y283578I-1035J-193D01*
G03X270761Y283753I-766J-367D01*
G03X270582Y283913I-769J-681D01*
G03X270394Y284005I-507J-799D01*
G03X270243Y284045I-304J-843D01*
G02X270231Y284046I0J72D01*
G01X270224Y284048D01*
X270196Y284053D01*
X270157Y284055D01*
X270109Y284056D01*
G02X270108Y284087I178J21D01*
G37*
G36*
G01X270107Y280193D02*
X270108Y280199D01*
Y280327D01*
X270107Y280328D01*
G02X270115Y280393I264J1D01*
G02X270180Y280498I191J-46D01*
G02X270206Y280516I181J-233D01*
G02X270319Y280545I100J-157D01*
G02X270311Y278079I-205J-1232D01*
G01X270284Y278082D01*
X270264Y278085D01*
G02X270256Y278089I72J153D01*
G02X270240Y278093I35J176D01*
G01X270217Y278103D01*
G02X270186Y278123I48J109D01*
G02X270175Y278134I58J69D01*
G02X270153Y278155I109J136D01*
G02X270150Y278159I12J12D01*
G01X270143Y278168D01*
X270138Y278174D01*
X270129Y278192D01*
X270128Y278193D01*
X270127Y278197D01*
X270125Y278200D01*
X270123Y278209D01*
X270116Y278228D01*
G02X270110Y278253I171J54D01*
G01X270107Y278266D01*
X270108D01*
Y278310D01*
X270107Y278314D01*
G02X270108Y278406I1068J34D01*
G03X270107Y278463I-439J21D01*
G03X270212Y278470I-6J886D01*
G03X270389Y278512I-73J702D01*
G01X270446Y278533D01*
G03X270616Y278634I-277J661D01*
G03X270678Y278685I-600J792D01*
G03X270777Y278792I-2279J2208D01*
G02X270846Y278892I780J-465D01*
G03X270938Y279125I-852J471D01*
G03X270958Y279308I-611J159D01*
G03X270949Y279440I-1662J-47D01*
G03X270872Y279684I-1035J-193D01*
G03X270760Y279860I-767J-365D01*
G03X270581Y280019I-767J-683D01*
G03X270393Y280112I-511J-796D01*
G03X270242Y280151I-299J-845D01*
G02X270230Y280152I0J72D01*
G01X270223Y280154D01*
X270196Y280159D01*
X270156Y280161D01*
X270108Y280162D01*
G02X270107Y280193I178J21D01*
G37*
G36*
G01X395337Y348951D02*
G02X395378Y346174I-164J-1391D01*
G02X395337Y348951I-212J1386D01*
G37*
G36*
G01X402123Y348948D02*
G02X402163Y346178I-189J-1388D01*
G02X402123Y348948I-237J1382D01*
G37*
G36*
G01X443872Y347282D02*
Y348165D01*
X443853Y348205D01*
G02X446393Y348204I1270J591D01*
G01X446374Y348164D01*
Y347282D01*
G02X443872I-1251J-736D01*
G37*
G36*
G01X384908Y344214D02*
G02X385076Y347009I119J1395D01*
G02X384908Y344214I-41J-1400D01*
G37*
G36*
G01X381750Y345058D02*
G02X381788Y342265I-94J-1398D01*
G02X381750Y345058I-140J1395D01*
G37*
G36*
G01X378461Y343098D02*
G02X378291Y340308I-185J-1389D01*
G02X378461Y343098I-23J1402D01*
G37*
G36*
G01X374965Y341159D02*
G02X375003Y338363I-70J-1399D01*
G02X374965Y341159I-116J1397D01*
G37*
G36*
G01X371678Y339201D02*
G02X371503Y336408I-163J-1392D01*
G02X371678Y339201I4J1402D01*
G37*
G36*
G01X368178Y337260D02*
G02X368217Y334461I-43J-1400D01*
G02X368178Y337260I-90J1399D01*
G37*
G36*
G01X364715Y332509D02*
G02X364893Y335303I32J1401D01*
G02X364715Y332509I-138J-1394D01*
G37*
G36*
G01X361572Y333347D02*
G02X361612Y330579I-197J-1387D01*
G02X361572Y333347I-245J1381D01*
G37*
G36*
G01X198115Y338432D02*
X199402Y337145D01*
Y331215D01*
X198015Y329828D01*
X191085D01*
X189698Y331215D01*
Y337045D01*
X191085Y338432D01*
X193098D01*
Y339482D01*
X196102D01*
Y338432D01*
X198115D01*
G37*
G36*
G01X358289Y331379D02*
G02X358109Y328613I-294J-1370D01*
G02X358289Y331379I-122J1397D01*
G37*
G36*
G01X354787Y329450D02*
G02X354828Y326675I-172J-1390D01*
G02X354787Y329450I-221J1385D01*
G37*
G36*
G01X354859Y325540D02*
G02X354755Y322766I-243J-1380D01*
G02X354859Y325540I-147J1394D01*
G37*
G36*
G01X354930Y321625D02*
G02X354682Y318861I-316J-1365D01*
G02X354930Y321625I-75J1400D01*
G37*
G36*
G01X354998Y317708D02*
G02X354609Y314959I-383J-1348D01*
G02X354998Y317708I-1J1402D01*
G37*
G36*
G01X354536Y311061D02*
G02X355065Y313787I72J1400D01*
G02X354536Y311061I-449J-1327D01*
G37*
G36*
G01X306036Y309616D02*
X306093Y309562D01*
X306378D01*
X306433Y309607D01*
G02Y307513I856J-1047D01*
G01X306378Y307558D01*
X306093D01*
X306036Y307504D01*
G02Y309616I-997J1056D01*
G37*
G36*
G01X299276D02*
X299333Y309562D01*
X299618D01*
X299673Y309607D01*
G02Y307513I856J-1047D01*
G01X299618Y307558D01*
X299333D01*
X299276Y307504D01*
G02Y309616I-997J1056D01*
G37*
G36*
G01X292516D02*
X292573Y309562D01*
X292858D01*
X292913Y309607D01*
G02Y307513I856J-1047D01*
G01X292858Y307558D01*
X292573D01*
X292516Y307504D01*
G02Y309616I-997J1056D01*
G37*
G36*
G01X285756D02*
X285813Y309562D01*
X286098D01*
X286153Y309607D01*
G02Y307513I856J-1047D01*
G01X286098Y307558D01*
X285813D01*
X285756Y307504D01*
G02Y309616I-997J1056D01*
G37*
G36*
G01X278996D02*
X279053Y309562D01*
X279338D01*
X279393Y309607D01*
G02Y307513I856J-1047D01*
G01X279338Y307558D01*
X279053D01*
X278996Y307504D01*
G02Y309616I-997J1056D01*
G37*
G36*
G01X339835Y301816D02*
X339892Y301762D01*
X340177D01*
X340232Y301807D01*
G02Y299713I856J-1047D01*
G01X340177Y299758D01*
X339892D01*
X339835Y299704D01*
G02Y301816I-997J1056D01*
G37*
G36*
G01X333075D02*
X333132Y301762D01*
X333417D01*
X333472Y301807D01*
G02Y299713I856J-1047D01*
G01X333417Y299758D01*
X333132D01*
X333075Y299704D01*
G02Y301816I-997J1056D01*
G37*
G36*
G01X326315D02*
X326372Y301762D01*
X326657D01*
X326712Y301807D01*
G02Y299713I856J-1047D01*
G01X326657Y299758D01*
X326372D01*
X326315Y299704D01*
G02Y301816I-997J1056D01*
G37*
G36*
G01X319555D02*
X319612Y301762D01*
X319897D01*
X319952Y301807D01*
G02Y299713I856J-1047D01*
G01X319897Y299758D01*
X319612D01*
X319555Y299704D01*
G02Y301816I-997J1056D01*
G37*
G36*
G01X312795D02*
X312852Y301762D01*
X313137D01*
X313192Y301807D01*
G02Y299713I856J-1047D01*
G01X313137Y299758D01*
X312852D01*
X312795Y299704D01*
G02Y301816I-997J1056D01*
G37*
G36*
G01X306036D02*
X306093Y301762D01*
X306378D01*
X306433Y301807D01*
G02Y299713I856J-1047D01*
G01X306378Y299758D01*
X306093D01*
X306036Y299704D01*
G02Y301816I-997J1056D01*
G37*
G36*
G01X299276D02*
X299333Y301762D01*
X299618D01*
X299673Y301807D01*
G02Y299713I856J-1047D01*
G01X299618Y299758D01*
X299333D01*
X299276Y299704D01*
G02Y301816I-997J1056D01*
G37*
G36*
G01X292516D02*
X292573Y301762D01*
X292858D01*
X292913Y301807D01*
G02Y299713I856J-1047D01*
G01X292858Y299758D01*
X292573D01*
X292516Y299704D01*
G02Y301816I-997J1056D01*
G37*
G36*
G01X285756D02*
X285813Y301762D01*
X286098D01*
X286153Y301807D01*
G02Y299713I856J-1047D01*
G01X286098Y299758D01*
X285813D01*
X285756Y299704D01*
G02Y301816I-997J1056D01*
G37*
G36*
G01X278996D02*
X279053Y301762D01*
X279338D01*
X279393Y301807D01*
G02Y299713I856J-1047D01*
G01X279338Y299758D01*
X279053D01*
X278996Y299704D01*
G02Y301816I-997J1056D01*
G37*
G36*
G01X198115Y305702D02*
X199402Y304415D01*
Y298485D01*
X198015Y297098D01*
X191085D01*
X189698Y298485D01*
Y304315D01*
X191085Y305702D01*
X193098D01*
Y306752D01*
X196102D01*
Y305702D01*
X198115D01*
G37*
G36*
G01X339835Y294015D02*
X339892Y293960D01*
X340177D01*
X340232Y294006D01*
G02Y291912I856J-1047D01*
G01X340177Y291958D01*
X339892D01*
X339835Y291903D01*
G02Y294015I-997J1056D01*
G37*
G36*
G01X333075D02*
X333132Y293960D01*
X333417D01*
X333472Y294006D01*
G02Y291912I856J-1047D01*
G01X333417Y291958D01*
X333132D01*
X333075Y291903D01*
G02Y294015I-997J1056D01*
G37*
G36*
G01X326315D02*
X326372Y293960D01*
X326657D01*
X326712Y294006D01*
G02Y291912I856J-1047D01*
G01X326657Y291958D01*
X326372D01*
X326315Y291903D01*
G02Y294015I-997J1056D01*
G37*
G36*
G01X319555D02*
X319612Y293960D01*
X319897D01*
X319952Y294006D01*
G02Y291912I856J-1047D01*
G01X319897Y291958D01*
X319612D01*
X319555Y291903D01*
G02Y294015I-997J1056D01*
G37*
G36*
G01X312795D02*
X312852Y293960D01*
X313137D01*
X313192Y294006D01*
G02Y291912I856J-1047D01*
G01X313137Y291958D01*
X312852D01*
X312795Y291903D01*
G02Y294015I-997J1056D01*
G37*
G36*
G01X306036D02*
X306093Y293960D01*
X306378D01*
X306433Y294006D01*
G02Y291912I856J-1047D01*
G01X306378Y291958D01*
X306093D01*
X306036Y291903D01*
G02Y294015I-997J1056D01*
G37*
G36*
G01X299276D02*
X299333Y293960D01*
X299618D01*
X299673Y294006D01*
G02Y291912I856J-1047D01*
G01X299618Y291958D01*
X299333D01*
X299276Y291903D01*
G02Y294015I-997J1056D01*
G37*
G36*
G01X292516D02*
X292573Y293960D01*
X292858D01*
X292913Y294006D01*
G02Y291912I856J-1047D01*
G01X292858Y291958D01*
X292573D01*
X292516Y291903D01*
G02Y294015I-997J1056D01*
G37*
G36*
G01X285756D02*
X285813Y293960D01*
X286098D01*
X286153Y294006D01*
G02Y291912I856J-1047D01*
G01X286098Y291958D01*
X285813D01*
X285756Y291903D01*
G02Y294015I-997J1056D01*
G37*
G36*
G01X278996D02*
X279053Y293960D01*
X279338D01*
X279393Y294006D01*
G02Y291912I856J-1047D01*
G01X279338Y291958D01*
X279053D01*
X278996Y291903D01*
G02Y294015I-997J1056D01*
G37*
G36*
G01X306036Y286216D02*
X306093Y286162D01*
X306378D01*
X306433Y286207D01*
G02Y284113I856J-1047D01*
G01X306378Y284158D01*
X306093D01*
X306036Y284104D01*
G02Y286216I-997J1056D01*
G37*
G36*
G01X299276D02*
X299333Y286162D01*
X299618D01*
X299673Y286207D01*
G02Y284113I856J-1047D01*
G01X299618Y284158D01*
X299333D01*
X299276Y284104D01*
G02Y286216I-997J1056D01*
G37*
G36*
G01X292516D02*
X292573Y286162D01*
X292858D01*
X292913Y286207D01*
G02Y284113I856J-1047D01*
G01X292858Y284158D01*
X292573D01*
X292516Y284104D01*
G02Y286216I-997J1056D01*
G37*
G36*
G01X285756D02*
X285813Y286162D01*
X286098D01*
X286153Y286207D01*
G02Y284113I856J-1047D01*
G01X286098Y284158D01*
X285813D01*
X285756Y284104D01*
G02Y286216I-997J1056D01*
G37*
G36*
G01X278996D02*
X279053Y286162D01*
X279338D01*
X279393Y286207D01*
G02Y284113I856J-1047D01*
G01X279338Y284158D01*
X279053D01*
X278996Y284104D01*
G02Y286216I-997J1056D01*
G37*
G36*
G01X198115Y276702D02*
X199402Y275415D01*
Y269485D01*
X198015Y268098D01*
X191085D01*
X189698Y269485D01*
Y275315D01*
X191085Y276702D01*
X193098D01*
Y277752D01*
X196102D01*
Y276702D01*
X198115D01*
G37*
G36*
G01X361572Y267047D02*
G02X361612Y264279I-197J-1387D01*
G02X361572Y267047I-245J1381D01*
G37*
G36*
G01X364715Y262309D02*
G02X364893Y265103I32J1401D01*
G02X364715Y262309I-138J-1394D01*
G37*
G36*
G01X368178Y263160D02*
G02X368217Y260361I-43J-1400D01*
G02X368178Y263160I-90J1399D01*
G37*
G36*
G01X371678Y261201D02*
G02X371503Y258408I-163J-1392D01*
G02X371678Y261201I4J1402D01*
G37*
G36*
G01X374965Y259259D02*
G02X375003Y256463I-70J-1399D01*
G02X374965Y259259I-116J1397D01*
G37*
G36*
G01X378461Y257298D02*
G02X378291Y254508I-185J-1389D01*
G02X378461Y257298I-23J1402D01*
G37*
G36*
G01X381750Y255358D02*
G02X381788Y252565I-94J-1398D01*
G02X381750Y255358I-140J1395D01*
G37*
G36*
G01X199702Y236985D02*
X198315Y235598D01*
X196102D01*
Y234596D01*
X193098D01*
Y235598D01*
X190915D01*
X189428Y237085D01*
Y244115D01*
X190915Y245602D01*
X193098D01*
Y246600D01*
X196102D01*
Y245602D01*
X198115D01*
X199702Y244015D01*
Y236985D01*
G37*
G36*
G01X196271Y379320D02*
G03Y378780I295J-270D01*
G02X194129I-1071J-980D01*
G03Y379320I-295J270D01*
G02X196271I1071J980D01*
G37*
G36*
G01X359640Y32310D02*
G03X359634Y31747I281J-285D01*
G02X357571Y31768I-1042J-1011D01*
G03X357577Y32331I-281J285D01*
G02X359640Y32310I1042J1011D01*
G37*
G36*
G01X358796Y570993D02*
G03Y570454I295J-270D01*
G02X356652I-1072J-980D01*
G03Y570993I-295J270D01*
G02X358796I1072J980D01*
G37*
G36*
G01X415790Y10076D02*
G02X414707Y10523I-1027J-954D01*
G03X414898Y10723I-9J200D01*
G01Y11248D01*
X413398D01*
Y15152D01*
X414898D01*
Y15457D01*
G03X414706Y15657I-200J0D01*
G02X415925Y16275I56J1401D01*
G03X416257Y15652I332J-223D01*
G01X419402D01*
Y14702D01*
X421368D01*
G02Y11698I0J-1502D01*
G01X419402D01*
Y10748D01*
X416083D01*
G03X415790Y10076I0J-400D01*
G37*
G36*
G01X405748D02*
G02X403696I-1026J-955D01*
G03X403403Y10748I-293J272D01*
G01X402448D01*
Y11248D01*
X400948D01*
Y15152D01*
X402448D01*
Y15652D01*
X403228D01*
G03X403560Y16275I0J400D01*
G02X405886I1163J782D01*
G03X406218Y15652I332J-223D01*
G01X406564D01*
G03X406898Y16271I0J400D01*
G02X407511Y15756I1171J771D01*
G03X406952Y15389I-159J-367D01*
G01Y14702D01*
X408184D01*
G02Y11698I0J-1502D01*
G01X406952D01*
Y10748D01*
X406041D01*
G03X405748Y10076I0J-400D01*
G37*
G36*
G01X429173D02*
G02X427755Y10466I-1026J-956D01*
G01X427898Y10508D01*
Y11248D01*
X426398D01*
Y15152D01*
X427898D01*
Y15652D01*
X429989D01*
G03X430323Y16271I0J400D01*
G02X432402Y15973I1171J771D01*
G01Y14702D01*
X433508D01*
G02Y11698I0J-1502D01*
G01X432402D01*
Y10748D01*
X429465D01*
G03X429173Y10076I1J-400D01*
G37*
G36*
G01X381706Y26683D02*
G03Y26062I251J-310D01*
G02X379878I-914J-1129D01*
G03Y26683I-251J311D01*
G02X381706I914J1129D01*
G37*
G36*
G01X375755Y-11870D02*
G02X375549Y-10457I-1354J524D01*
G03X376238Y-10356I316J245D01*
G02X378635Y-9869I1354J-524D01*
G03X379205Y-9874I287J278D01*
G02X379189Y-11911I1027J-1027D01*
G03X378619Y-11906I-287J-278D01*
G02X376444Y-11769I-1027J1026D01*
G03X375755Y-11870I-316J-245D01*
G37*
G36*
G01X530522Y202546D02*
G03X530464Y202545I-21J-438D01*
G03X530457Y202651I-885J-5D01*
G03X530415Y202828I-701J-73D01*
G01X530394Y202885D01*
G03X530294Y203054I-660J-276D01*
G03X530242Y203117I-791J-600D01*
G03X530137Y203215I-2216J-2269D01*
G02X530037Y203284I465J781D01*
G03X529802Y203376I-469J-852D01*
G03X529621Y203396I-159J-610D01*
G03X529489Y203387I47J-1661D01*
G03X529244Y203310I191J-1035D01*
G03X529070Y203198I369J-764D01*
G03X528910Y203020I678J-770D01*
G03X528818Y202833I797J-508D01*
G03X528778Y202682I842J-304D01*
G02X528775Y202664I-73J3D01*
G01X528770Y202635D01*
X528768Y202595D01*
X528767Y202546D01*
G02X528730I-19J180D01*
G01X528601D01*
G02X528534Y202553I-6J265D01*
G02X528429Y202619I47J192D01*
G02X528411Y202646I237J177D01*
G02X528383Y202758I158J99D01*
G02X530850Y202750I1233J-206D01*
G01X530847Y202723D01*
G03X530846Y202713I135J-19D01*
G03X530845Y202708I133J-29D01*
G02X530841Y202694I-166J40D01*
G02X530835Y202673I-177J39D01*
G03X530827Y202657I157J-88D01*
G02X530806Y202624I-111J47D01*
G02X530796Y202613I-73J56D01*
G02X530774Y202591I-135J113D01*
G02X530766Y202586I-14J13D01*
G03X530755Y202576I307J-348D01*
G01X530754D01*
X530747Y202572D01*
G02X530740Y202569I-8J9D01*
G01X530736Y202567D01*
G03X530728Y202563I7J-24D01*
G01X530720Y202561D01*
X530701Y202554D01*
G02X530675Y202548I-54J173D01*
G01X530662Y202545D01*
Y202546D01*
X530618D01*
G02X530522I-48J1068D01*
G37*
G36*
G01X619759Y90852D02*
X620556Y90055D01*
X620597Y90039D01*
G02X619080Y87637I-505J-1361D01*
G03X618454Y87548I-278J-287D01*
G01X613898D01*
Y88048D01*
X612398D01*
Y91052D01*
X613898D01*
Y91561D01*
G03X614189Y92091I-84J391D01*
G02X616909I1360J508D01*
G03X617284Y91552I375J-139D01*
G01X618402D01*
Y90852D01*
X619759D01*
G37*
G36*
G01X607074Y78833D02*
Y73857D01*
G02X603946I-1564J0D01*
G01Y78833D01*
G02X604001Y79247I1564J3D01*
G01X604008Y79273D01*
Y82884D01*
X607012D01*
Y79273D01*
X607019Y79247D01*
G02X607074Y78833I-1509J-411D01*
G37*
G36*
G01X617050Y60283D02*
Y56672D01*
X614048D01*
Y60283D01*
X614040Y60309D01*
G02X613984Y60723I1509J415D01*
G01Y65699D01*
G02X617114I1565J0D01*
G01Y60723D01*
G02X617058Y60309I-1565J1D01*
G01X617050Y60283D01*
G37*
G36*
G01X607074Y41033D02*
Y36057D01*
G02X603946I-1564J0D01*
G01Y41033D01*
G02X604001Y41447I1564J3D01*
G01X604008Y41473D01*
Y45084D01*
X607012D01*
Y41473D01*
X607019Y41447D01*
G02X607074Y41033I-1509J-411D01*
G37*
G36*
G01X617050Y22483D02*
Y18872D01*
X614048D01*
Y22483D01*
X614040Y22509D01*
G02X613984Y22923I1509J415D01*
G01Y27899D01*
G02X617114I1565J0D01*
G01Y22923D01*
G02X617058Y22509I-1565J1D01*
G01X617050Y22483D01*
G37*
G36*
G01X607012D02*
Y18872D01*
X604008D01*
Y22483D01*
X604001Y22509D01*
G02X603946Y22923I1509J411D01*
G01Y27899D01*
G02X607074I1564J0D01*
G01Y22923D01*
G02X607019Y22509I-1564J-3D01*
G01X607012Y22483D01*
G37*
G36*
G01X618752Y11776D02*
Y10998D01*
X614248D01*
Y11498D01*
X612748D01*
Y14502D01*
X614248D01*
Y15002D01*
X618752D01*
Y14380D01*
X619447D01*
X619486Y14398D01*
G02Y11758I606J-1320D01*
G01X619447Y11776D01*
X618752D01*
G37*
G36*
G01X607074Y3233D02*
Y-1743D01*
G02X603946I-1564J0D01*
G01Y3233D01*
G02X604001Y3647I1564J3D01*
G01X604008Y3673D01*
Y7284D01*
X607012D01*
Y3673D01*
X607019Y3647D01*
G02X607074Y3233I-1509J-411D01*
G37*
G36*
G01X617050Y-15317D02*
Y-18928D01*
X614048D01*
Y-15317D01*
X614040Y-15291D01*
G02X613984Y-14877I1509J415D01*
G01Y-9901D01*
G02X617114I1565J0D01*
G01Y-14877D01*
G02X617058Y-15291I-1565J1D01*
G01X617050Y-15317D01*
G37*
G36*
G01X619152Y48998D02*
X614648D01*
Y49498D01*
X613148D01*
Y52502D01*
X614648D01*
Y53002D01*
X615328D01*
Y53356D01*
X615179Y53395D01*
G02X616502Y53703I370J1404D01*
G03X616764Y53002I263J-301D01*
G01X619152D01*
Y52302D01*
X619783D01*
X619801Y52305D01*
G02X620339I269J-1427D01*
G01X620357Y52302D01*
X620487D01*
X620534Y52255D01*
X620575Y52239D01*
G02X619663Y49484I-506J-1361D01*
G03X619152Y49100I-111J-384D01*
G01Y48998D01*
G37*
G36*
G01X643548Y30106D02*
G02X643827Y32443I-5755J1872D01*
G03X644486Y32170I399J31D01*
G02X644253Y30217I944J-1103D01*
G03X643548Y30106I-324J-234D01*
G37*
G36*
G01X624396Y-2602D02*
G02X622991Y-1548I-1396J-398D01*
G03X623374Y-1038I-2J400D01*
G02X624779Y-2092I1396J398D01*
G03X624396Y-2602I2J-400D01*
G37*
G36*
G01X726058Y189791D02*
G03X726681Y189765I322J237D01*
G02X726606Y187950I1095J-954D01*
G03X725983Y187976I-322J-237D01*
G02X726058Y189791I-1095J954D01*
G37*
G36*
G01X663832Y169033D02*
X663862Y169018D01*
G02X661436Y166871I-771J-1573D01*
G01X661421Y166915D01*
X659468Y168868D01*
G02X661227Y171474I1132J1132D01*
G03X661488Y171739I78J184D01*
G02X661436Y171871I1603J708D01*
G01X661421Y171915D01*
X659468Y173868D01*
G02X661732Y176132I1132J1132D01*
G01X663832Y174033D01*
X663862Y174018D01*
G02X664664Y173216I-771J-1573D01*
G01X664679Y173186D01*
X664692Y173172D01*
Y173157D01*
X664708Y173120D01*
G02X663128Y170693I-1617J-675D01*
G03X662854Y170011I9J-400D01*
G01X663832Y169033D01*
G37*
G36*
G01X607074Y617610D02*
Y612657D01*
G02X603946I-1564J0D01*
G01Y617610D01*
G02X604001Y618024I1564J3D01*
G01X604008Y618050D01*
Y621662D01*
X607012D01*
Y618050D01*
X607019Y618024D01*
G02X607074Y617610I-1509J-411D01*
G37*
G36*
G01Y579810D02*
Y574857D01*
G02X603946I-1564J0D01*
G01Y579810D01*
G02X604001Y580224I1564J3D01*
G01X604008Y580250D01*
Y583862D01*
X607012D01*
Y580250D01*
X607019Y580224D01*
G02X607074Y579810I-1509J-411D01*
G37*
G36*
G01Y542010D02*
Y537057D01*
G02X603946I-1564J0D01*
G01Y542010D01*
G02X604001Y542424I1564J3D01*
G01X604008Y542450D01*
Y546062D01*
X607012D01*
Y542450D01*
X607019Y542424D01*
G02X607074Y542010I-1509J-411D01*
G37*
G36*
G01X619897Y513339D02*
X619856Y513323D01*
X618431Y511898D01*
X618152D01*
Y511198D01*
X613648D01*
Y511698D01*
X612148D01*
Y514702D01*
X613648D01*
Y515202D01*
X618023D01*
X618077Y515317D01*
G02X619897Y513339I1315J-617D01*
G37*
G36*
G01X629045Y611414D02*
G02X628146Y613356I-1340J559D01*
G03X628637Y613583I122J381D01*
G02X630086Y614472I1340J-559D01*
G03X630467Y615063I30J399D01*
G02X631632Y614311I1274J696D01*
G03X631251Y613720I-30J-399D01*
G02X629536Y611641I-1274J-696D01*
G03X629045Y611414I-122J-381D01*
G37*
G36*
G01X614397Y595448D02*
X614048D01*
Y599060D01*
X614040Y599086D01*
G02X613984Y599500I1509J415D01*
G01Y604499D01*
G02X617114I1565J0D01*
G01Y599500D01*
G02X617058Y599086I-1565J1D01*
G01X617050Y599060D01*
Y595448D01*
X616701D01*
G03X616453Y594735I1J-400D01*
G02X616585Y594617I-900J-1140D01*
G03X617156I285J280D01*
G02X619512Y592994I1036J-1017D01*
G01X619494Y592955D01*
Y591002D01*
X620252D01*
Y586998D01*
X615748D01*
Y587498D01*
X614248D01*
Y590502D01*
X615748D01*
Y591002D01*
X616890D01*
Y592005D01*
G03X616287Y592349I-400J-1D01*
G02X614645Y594735I-738J1250D01*
G03X614397Y595448I-249J313D01*
G37*
G36*
G01X604358Y557648D02*
X604008D01*
Y561260D01*
X604001Y561286D01*
G02X603946Y561700I1509J411D01*
G01Y566699D01*
G02X607074I1564J0D01*
G01Y561700D01*
G02X607019Y561286I-1564J-3D01*
G01X607012Y561260D01*
Y557648D01*
X606662D01*
G03X606414Y556935I1J-400D01*
G02X604606I-904J-1136D01*
G03X604358Y557648I-249J313D01*
G37*
G36*
G01X614397D02*
X614048D01*
Y561260D01*
X614040Y561286D01*
G02X613984Y561700I1509J415D01*
G01Y566699D01*
G02X617114I1565J0D01*
G01Y561700D01*
G02X617058Y561286I-1565J1D01*
G01X617050Y561260D01*
Y557648D01*
X616701D01*
G03X616453Y556935I1J-400D01*
G02X616961Y556139I-904J-1137D01*
G01X616974Y556085D01*
X617155Y555904D01*
X617515Y556264D01*
X617531Y556305D01*
G02X619802Y554668I1361J-505D01*
G01Y553202D01*
X620752D01*
Y549198D01*
X616248D01*
Y549698D01*
X614748D01*
Y552702D01*
X616248D01*
Y553202D01*
X617198D01*
Y554432D01*
G03X616529Y554727I-400J0D01*
G02X614645Y556935I-979J1073D01*
G03X614397Y557648I-249J313D01*
G37*
G36*
G01Y519848D02*
X614048D01*
Y523460D01*
X614040Y523486D01*
G02X613984Y523900I1509J415D01*
G01Y528899D01*
G02X617114I1565J0D01*
G01Y523900D01*
G02X617058Y523486I-1565J1D01*
G01X617050Y523460D01*
Y519848D01*
X616701D01*
G03X616453Y519135I1J-400D01*
G02X614645I-904J-1136D01*
G03X614397Y519848I-249J313D01*
G37*
G36*
G01X668457Y149878D02*
X667561Y150775D01*
X667517Y150790D01*
G02X669652Y153241I574J1655D01*
G01X669666Y153213D01*
X672203Y150676D01*
Y149337D01*
X671228Y148362D01*
Y146637D01*
X672202Y145663D01*
Y144900D01*
G02X669198Y144126I-1602J0D01*
G01X669184Y144151D01*
X667561Y145775D01*
X667517Y145790D01*
G02X668159Y149196I574J1655D01*
G03X668457Y149878I15J400D01*
G37*
G36*
G01X680492Y430157D02*
G03X680351Y430498I-141J141D01*
G01X680200D01*
G02X679353Y433459I0J1602D01*
G01X679372Y433471D01*
X681455Y435554D01*
X681471Y435591D01*
G02X684841Y434846I1620J-667D01*
G01Y434110D01*
X683821Y433090D01*
Y431669D01*
X684260Y431230D01*
X684264Y431226D01*
G02X684392Y431098I-1173J-1301D01*
G01X684396Y431094D01*
X684845Y430645D01*
Y429200D01*
X683779Y428134D01*
X682999D01*
X681502Y426638D01*
G02X679238Y428902I-1132J1132D01*
G01X680492Y430157D01*
G37*
G36*
G01X693445Y432359D02*
X692543Y433260D01*
X692501Y433275D01*
G02X694741Y435515I590J1650D01*
G01X694756Y435473D01*
X697264Y432964D01*
Y425944D01*
X697964Y425244D01*
X697994Y425214D01*
Y418032D01*
X697735Y417773D01*
X691845D01*
X691340Y418278D01*
Y429869D01*
G02X693149Y431676I1751J56D01*
G03X693445Y432359I13J400D01*
G37*
G36*
G01X676745Y484603D02*
G03X676157Y484596I-291J-275D01*
G02X676135Y486567I-1077J974D01*
G03X676723Y486574I291J275D01*
G02X678737Y486709I1077J-974D01*
G03X679277Y486731I258J306D01*
G02X679363Y484591I1023J-1031D01*
G03X678823Y484569I-258J-306D01*
G02X676745Y484603I-1022J1031D01*
G37*
G36*
G01X699600Y84653D02*
G02X699509Y86104I-1300J647D01*
G03X700200Y86147I333J221D01*
G02X700291Y84696I1300J-647D01*
G03X699600Y84653I-333J-221D01*
G37*
G36*
G01X757834Y100981D02*
G03Y100419I285J-281D01*
G02X755766I-1034J-1019D01*
G03Y100981I-285J281D01*
G02X757834I1034J1019D01*
G37*
G36*
G01X733665Y89394D02*
G03X734236Y89377I294J271D01*
G02X734175Y87343I1005J-1048D01*
G03X733604Y87360I-294J-271D01*
G02X731595Y87359I-1005J1048D01*
G03X731042I-276J-289D01*
G02Y89457I-1004J1049D01*
G03X731595I277J289D01*
G02X733665Y89394I1004J-1049D01*
G37*
G36*
G01X752995Y1353D02*
G03X753578Y1332I301J263D01*
G02X753505Y-653I1022J-1031D01*
G03X752922Y-632I-301J-263D01*
G02X752995Y1353I-1022J1031D01*
G37*
G36*
G01X755166Y-5343D02*
G03X754610I-278J-288D01*
G02Y-3257I-1010J1043D01*
G03X755166I278J288D01*
G02Y-5343I1010J-1043D01*
G37*
G36*
G01X755552Y24001D02*
G02X755493Y22344I1162J-871D01*
G03X754837Y22368I-336J-216D01*
G02X754896Y24025I-1162J871D01*
G03X755552Y24001I336J216D01*
G37*
G36*
G01X743532Y101511D02*
G03X742992Y101338I-184J-355D01*
G02X742368Y103289I-1292J662D01*
G03X742908Y103462I184J355D01*
G02X744717Y104157I1292J-662D01*
G03X745235Y104395I142J374D01*
G02X746083Y102543I1365J-495D01*
G03X745565Y102305I-142J-374D01*
G02X743532Y101511I-1365J495D01*
G37*
G36*
G01X698786Y221496D02*
Y218504D01*
X696384D01*
Y221508D01*
X697678D01*
Y225298D01*
X699680D01*
Y221496D01*
X698786D01*
G37*
G36*
G01X744691Y440640D02*
X745732D01*
G03X746015Y441322I0J400D01*
G01X743976Y443360D01*
X743883D01*
X743821Y443332D01*
G02X743840Y446509I-730J1593D01*
G01X743881Y446490D01*
X745273D01*
X748392Y443370D01*
G03X749057Y443535I283J283D01*
G02X750572Y439295I3584J-1110D01*
G03X749951Y438948I-221J-333D01*
G02X747050Y438830I-1451J-48D01*
G03X746651Y439210I-399J-20D01*
G01X744691D01*
G02Y440640I-1600J715D01*
G37*
G36*
G01X743840Y431509D02*
X743881Y431490D01*
X745077D01*
X745307Y431719D01*
X745159Y431867D01*
X745152Y431873D01*
G02X745045Y431971I1002J1201D01*
G01X743727Y433288D01*
X743612Y433252D01*
G02X743840Y436509I-521J1673D01*
G01X743881Y436490D01*
X744951D01*
X747257Y434183D01*
G02X747177Y431896I-1106J-1106D01*
G03X747173Y431296I263J-302D01*
G02X746714Y428678I-1043J-1166D01*
G01X746676Y428663D01*
X746373Y428360D01*
X743881D01*
X743840Y428341D01*
G02Y431509I-749J1584D01*
G37*
G36*
G01X784054Y345026D02*
Y341234D01*
X782052D01*
Y345038D01*
X782946D01*
Y348028D01*
X785348D01*
Y345026D01*
X784054D01*
G37*
G36*
G01X797147Y334200D02*
G02X797100Y334198I-62J899D01*
G01X794500D01*
G02X793598Y335100I0J902D01*
G01Y337700D01*
G02X794500Y338602I902J0D01*
G01X797100D01*
G02X797147Y338600I-15J-901D01*
G01X797600D01*
X798298Y337902D01*
X803303D01*
X803949D01*
X804678D01*
X805730Y338954D01*
Y341862D01*
X794085D01*
X792198Y343748D01*
Y362078D01*
X793985Y363864D01*
X813981D01*
X815452Y362394D01*
Y344536D01*
X812777Y341862D01*
X808734D01*
Y337710D01*
X806802Y335778D01*
Y334898D01*
X803812D01*
X803145D01*
X798448D01*
X797750Y334200D01*
X797147D01*
G37*
G36*
G01X784054Y313026D02*
Y309234D01*
X782052D01*
Y313038D01*
X782946D01*
Y316028D01*
X785348D01*
Y313026D01*
X784054D01*
G37*
G36*
G01X799709Y303371D02*
G02X798870Y302798I-839J328D01*
G01X796270D01*
G02X795368Y303700I0J902D01*
G01Y306300D01*
G02X796270Y307202I902J0D01*
G01X798870D01*
G02X798917Y307200I-15J-901D01*
G01X799300D01*
X799998Y306502D01*
X802670D01*
X803322D01*
X804178D01*
X805730Y308054D01*
Y309862D01*
X793222D01*
X792298Y310785D01*
Y330578D01*
X793585Y331864D01*
X814512D01*
X815620Y330756D01*
Y311381D01*
X814101Y309862D01*
X808734D01*
Y306810D01*
X806302Y304378D01*
Y303498D01*
X803329D01*
X802623D01*
X799759D01*
X799709Y303371D01*
G37*
G36*
G01X784054Y281026D02*
Y277234D01*
X782052D01*
Y281038D01*
X782946D01*
Y284028D01*
X785348D01*
Y281026D01*
X784054D01*
G37*
G36*
G01X797087Y275100D02*
X799700D01*
X800100D01*
X800698Y274502D01*
X803439D01*
X804131D01*
X804978D01*
X805730Y275254D01*
Y277862D01*
X793985D01*
X792198Y279648D01*
Y298178D01*
X793885Y299864D01*
X813639D01*
X815508Y297995D01*
Y279660D01*
X813710Y277862D01*
X808734D01*
Y274010D01*
X807102Y272378D01*
Y271498D01*
X804116D01*
X803563D01*
X801623D01*
X801521Y271396D01*
X800576D01*
X800526Y271269D01*
G02X799687Y270696I-839J328D01*
G01X797087D01*
G02X796186Y271598I1J902D01*
G01Y274198D01*
G02X797087Y275100I901J1D01*
G37*
G36*
G01X784054Y249026D02*
Y245234D01*
X782052D01*
Y249038D01*
X782946D01*
Y252028D01*
X785348D01*
Y249026D01*
X784054D01*
G37*
G36*
G01X815508Y248303D02*
X813067Y245862D01*
X808202D01*
X808102Y245760D01*
Y239498D01*
X805152D01*
X804492D01*
X801348D01*
X801301Y239365D01*
G02X800451Y238764I-850J301D01*
G01X797851D01*
G02X796950Y239666I1J902D01*
G01Y242266D01*
G02X797851Y243168I901J1D01*
G01X800442D01*
X800846D01*
X801512Y242502D01*
X804526D01*
X805018D01*
X805098Y242582D01*
Y245820D01*
X805058Y245862D01*
X793822D01*
X792198Y247485D01*
Y265778D01*
X794285Y267864D01*
X813523D01*
X815508Y265879D01*
Y248303D01*
G37*
G36*
G01X815480Y215317D02*
X814023Y213860D01*
X809261D01*
X809259Y213862D01*
X808569D01*
X807500Y212792D01*
Y209626D01*
X804852Y206978D01*
Y206098D01*
X801849D01*
X801159D01*
X798363D01*
X797888D01*
X797838Y205971D01*
G02X796999Y205398I-839J328D01*
G01X794399D01*
G02X793498Y206300I1J902D01*
G01Y208900D01*
G02X794399Y209802I901J1D01*
G01X796999D01*
G02X797014Y209801I-52J-899D01*
G01X797214Y209798D01*
Y209802D01*
X797377D01*
X798077Y209102D01*
X798351D01*
X801286D01*
Y209103D01*
X801871D01*
Y209102D01*
X802728D01*
X804496Y210870D01*
Y213862D01*
X793722D01*
X792298Y215285D01*
Y233878D01*
X794285Y235864D01*
X813970D01*
X815480Y234354D01*
Y215317D01*
G37*
G36*
G01X784004Y377026D02*
Y373234D01*
X782002D01*
Y377038D01*
X782896D01*
Y380028D01*
X785298D01*
Y377026D01*
X784004D01*
G37*
G36*
G01X754344Y585578D02*
X753954Y585187D01*
X753951Y585108D01*
G02X751348Y586033I-1451J42D01*
G03X751030Y586676I-318J243D01*
G01X750842D01*
Y592680D01*
X751523D01*
G03X751907Y593192I0J400D01*
G02X754299Y594653I1393J407D01*
G03X754861Y594664I275J290D01*
G02X757085Y592811I1039J-1014D01*
G03X757411Y592180I326J-231D01*
G01X758344D01*
Y587176D01*
X755844D01*
Y586676D01*
X754344D01*
Y585578D01*
G37*
G36*
G01X755844Y548876D02*
X750842D01*
Y554880D01*
X752342D01*
Y555248D01*
X753456Y556363D01*
X753459Y556442D01*
G02X755782Y555239I1451J-42D01*
G01X755703Y555179D01*
Y554880D01*
X755844D01*
Y554380D01*
X758344D01*
Y549376D01*
X755844D01*
Y548876D01*
G37*
G36*
G01X923307Y317591D02*
G02X923300Y315123I-205J-1233D01*
G01X923272Y315126D01*
G03X923263Y315127I-20J-135D01*
G01X923262D01*
G03X923257Y315128I-29J-132D01*
G02X923244Y315133I55J162D01*
G02X923222Y315139I36J177D01*
G03X923206Y315147I-89J-157D01*
G02X923173Y315168I47J111D01*
G02X923162Y315178I56J73D01*
G02X923140Y315199I110J137D01*
G02X923135Y315208I13J13D01*
G01X923134D01*
G03X923126Y315219I-380J-268D01*
G01Y315220D01*
X923122Y315226D01*
G02X923118Y315233I8J9D01*
G01X923117Y315237D01*
X923116Y315238D01*
G03X923112Y315246I-24J-7D01*
G01X923110Y315253D01*
X923103Y315272D01*
G02X923097Y315298I173J54D01*
G01X923095Y315311D01*
X923096D01*
G03X923095Y315336I-92J9D01*
G01X923094D01*
Y315356D01*
G02X923096Y315451I1069J25D01*
G03X923094Y315510I-439J15D01*
G03X923200Y315517I-5J884D01*
G03X923377Y315559I-73J701D01*
G01X923435Y315580D01*
G03X923604Y315680I-276J660D01*
G03X923666Y315732I-606J786D01*
G03X923764Y315837I-2269J2216D01*
G02X923833Y315937I781J-465D01*
G03X923925Y316172I-852J469D01*
G03X923946Y316353I-610J162D01*
G03X923936Y316485I-1660J-59D01*
G03X923859Y316730I-1034J-191D01*
G03X923747Y316904I-764J-369D01*
G03X923570Y317063I-769J-679D01*
G03X923382Y317156I-511J-796D01*
G03X923231Y317196I-304J-842D01*
G02X923214Y317198I0J73D01*
G01X923184Y317204D01*
X923144Y317206D01*
X923095D01*
G02X923096Y317243I180J14D01*
G01Y317372D01*
G02X923102Y317440I264J11D01*
G02X923168Y317545I192J-48D01*
G02X923195Y317563I177J-237D01*
G02X923307Y317591I99J-159D01*
G37*
G36*
G01Y309793D02*
G02X923300Y307325I-205J-1233D01*
G01X923272Y307328D01*
G03X923263Y307329I-20J-135D01*
G01X923262D01*
G03X923257Y307330I-29J-132D01*
G02X923244Y307335I55J162D01*
G02X923222Y307341I36J177D01*
G03X923206Y307349I-89J-157D01*
G02X923173Y307370I47J111D01*
G02X923162Y307380I56J73D01*
G02X923140Y307401I110J137D01*
G02X923135Y307410I13J13D01*
G03X923126Y307420I-350J-306D01*
G01Y307421D01*
X923122Y307428D01*
G02X923118Y307435I8J9D01*
G01X923117Y307439D01*
X923116Y307440D01*
G03X923112Y307446I-22J-10D01*
G01Y307447D01*
X923110Y307455D01*
X923103Y307474D01*
G02X923097Y307500I173J54D01*
G01X923095Y307513D01*
X923096D01*
G03X923095Y307538I-92J9D01*
G01X923094D01*
Y307558D01*
G02X923096Y307653I1069J25D01*
G03X923094Y307711I-439J14D01*
G03X923200Y307719I-13J885D01*
G03X923377Y307761I-73J701D01*
G01X923435Y307782D01*
G03X923604Y307882I-276J660D01*
G03X923666Y307934I-606J786D01*
G03X923764Y308039I-2269J2216D01*
G02X923833Y308139I781J-465D01*
G03X923925Y308373I-852J470D01*
G03X923946Y308555I-610J163D01*
G03X923936Y308687I-1660J-59D01*
G03X923859Y308932I-1034J-191D01*
G03X923747Y309106I-764J-369D01*
G03X923570Y309265I-769J-679D01*
G03X923382Y309358I-511J-796D01*
G03X923231Y309398I-304J-842D01*
G02X923214Y309400I0J73D01*
G01X923184Y309406D01*
X923144Y309407D01*
X923095Y309408D01*
G02X923096Y309445I180J14D01*
G01Y309574D01*
G02X923102Y309642I264J11D01*
G02X923168Y309747I192J-48D01*
G02X923195Y309765I177J-237D01*
G02X923307Y309793I99J-159D01*
G37*
G36*
G01Y298092D02*
G02X923300Y295624I-205J-1233D01*
G01X923272Y295627D01*
G03X923263Y295628I-20J-135D01*
G01X923262D01*
G03X923257Y295629I-29J-132D01*
G02X923244Y295634I55J162D01*
G02X923222Y295640I36J177D01*
G03X923206Y295648I-89J-157D01*
G02X923173Y295669I47J110D01*
G02X923162Y295679I56J73D01*
G02X923140Y295700I110J137D01*
G02X923135Y295708I13J14D01*
G03X923126Y295719I-364J-288D01*
G01Y295720D01*
X923122Y295727D01*
G02X923118Y295734I8J9D01*
G01X923117Y295738D01*
X923116Y295739D01*
G03X923112Y295745I-22J-10D01*
G01Y295746D01*
X923110Y295754D01*
X923103Y295773D01*
G02X923097Y295799I173J54D01*
G01X923095Y295812D01*
X923096D01*
G03X923095Y295837I-92J9D01*
G01X923094D01*
Y295856D01*
G02X923096Y295952I1069J26D01*
G03X923094Y296010I-439J14D01*
G03X923200Y296017I-5J885D01*
G03X923377Y296060I-76J700D01*
G01X923435Y296080D01*
G03X923604Y296181I-279J659D01*
G03X923666Y296232I-599J792D01*
G03X923764Y296338I-2279J2206D01*
G02X923833Y296438I781J-465D01*
G03X923925Y296672I-851J470D01*
G03X923946Y296854I-610J163D01*
G03X923936Y296986I-1660J-59D01*
G03X923859Y297231I-1035J-191D01*
G03X923747Y297405I-764J-369D01*
G03X923570Y297564I-770J-679D01*
G03X923382Y297657I-511J-796D01*
G03X923231Y297696I-298J-844D01*
G02X923214Y297699I4J73D01*
G01X923184Y297704D01*
X923144Y297706D01*
X923095Y297707D01*
G02X923096Y297744I180J14D01*
G01Y297873D01*
G02X923102Y297940I264J10D01*
G02X923168Y298045I192J-47D01*
G02X923195Y298063I177J-237D01*
G02X923307Y298092I101J-158D01*
G37*
G36*
G01Y290289D02*
G02X923300Y287821I-205J-1233D01*
G01X923272Y287824D01*
G03X923263Y287825I-19J-134D01*
G01X923262D01*
G03X923257Y287826I-29J-132D01*
G02X923244Y287831I55J162D01*
G02X923222Y287837I36J177D01*
G03X923206Y287845I-89J-157D01*
G02X923173Y287866I47J111D01*
G02X923162Y287876I56J73D01*
G02X923140Y287897I110J137D01*
G02X923135Y287906I13J13D01*
G01X923134D01*
G03X923126Y287917I-380J-268D01*
G01Y287918D01*
X923122Y287924D01*
G02X923118Y287931I8J9D01*
G01X923117Y287935D01*
X923116Y287936D01*
G03X923112Y287944I-24J-7D01*
G01X923110Y287951D01*
X923103Y287970D01*
G02X923097Y287997I173J53D01*
G01X923095Y288009D01*
X923096D01*
G03X923095Y288034I-92J9D01*
G01X923094D01*
Y288054D01*
G02X923096Y288149I1069J25D01*
G03X923094Y288208I-439J15D01*
G03X923200Y288215I-5J884D01*
G03X923377Y288257I-73J701D01*
G01X923435Y288278D01*
G03X923604Y288378I-276J660D01*
G03X923666Y288430I-606J786D01*
G03X923764Y288535I-2269J2216D01*
G02X923833Y288635I781J-465D01*
G03X923925Y288870I-852J469D01*
G03X923946Y289051I-610J162D01*
G03X923936Y289183I-1660J-59D01*
G03X923859Y289428I-1034J-191D01*
G03X923747Y289602I-764J-369D01*
G03X923570Y289761I-769J-679D01*
G03X923382Y289854I-511J-796D01*
G03X923231Y289894I-304J-842D01*
G02X923214Y289896I0J73D01*
G01X923184Y289902D01*
X923144Y289904D01*
X923095D01*
G02X923096Y289941I180J14D01*
G01Y290071D01*
G02X923102Y290138I264J10D01*
G02X923168Y290243I192J-48D01*
G02X923195Y290261I177J-237D01*
G02X923307Y290289I99J-159D01*
G37*
G36*
G01X919713Y323089D02*
X919714Y323096D01*
Y323224D01*
X919713Y323226D01*
G02X919720Y323290I264J4D01*
G02X919786Y323395I191J-47D01*
G02X919812Y323413I181J-233D01*
G02X919924Y323441I99J-158D01*
G02X919917Y320976I-206J-1232D01*
G01X919881Y320979D01*
G02X919862Y320985I41J164D01*
G02X919846Y320989I36J176D01*
G01X919822Y320999D01*
G02X919792Y321020I53J107D01*
G02X919780Y321030I52J75D01*
G02X919759Y321051I113J134D01*
G02X919756Y321055I12J12D01*
G01X919749Y321065D01*
X919744Y321071D01*
X919743Y321072D01*
X919737Y321082D01*
G02X919736Y321085I9J5D01*
G01X919732Y321095D01*
X919728Y321103D01*
Y321105D01*
X919722Y321124D01*
G02X919716Y321150I171J53D01*
G01X919713Y321163D01*
X919714D01*
Y321207D01*
X919713Y321211D01*
G02X919714Y321302I1068J34D01*
G03X919713Y321360I-440J21D01*
G03X919817Y321367I-7J885D01*
G03X919995Y321409I-72J702D01*
G01X920052Y321430D01*
G03X920222Y321530I-275J662D01*
G03X920284Y321582I-607J787D01*
G03X920383Y321688I-2269J2218D01*
G02X920451Y321788I783J-459D01*
G03X920544Y322022I-851J474D01*
G03X920564Y322204I-612J159D01*
G03X920555Y322336I-1662J-47D01*
G03X920477Y322581I-1035J-195D01*
G03X920366Y322756I-767J-364D01*
G03X920187Y322916I-769J-681D01*
G03X919999Y323008I-507J-799D01*
G03X919848Y323048I-304J-843D01*
G02X919836Y323049I0J72D01*
G01X919829Y323051D01*
X919801Y323056D01*
X919762Y323058D01*
X919714D01*
G02X919713Y323089I178J21D01*
G37*
G36*
G01X919716Y319188D02*
Y319326D01*
G02X919723Y319390I264J4D01*
G02X919789Y319495I191J-47D01*
G02X919815Y319513I181J-233D01*
G02X919927Y319541I99J-158D01*
G02X919920Y317076I-206J-1232D01*
G01X919884Y317079D01*
G02X919865Y317085I42J165D01*
G02X919849Y317088I25J178D01*
G01X919827Y317099D01*
X919826D01*
G02X919794Y317120I49J109D01*
G02X919783Y317130I56J72D01*
G02X919761Y317151I109J136D01*
G02X919759Y317154I13J11D01*
G01X919751Y317166D01*
X919747Y317171D01*
X919746Y317172D01*
X919740Y317182D01*
G02X919739Y317184I9J6D01*
G01X919737Y317188D01*
X919724Y317224D01*
G02X919718Y317250I172J53D01*
G01X919716Y317263D01*
X919718Y317275D01*
X919716Y317287D01*
Y317307D01*
X919715Y317310D01*
G02X919717Y317402I1068J23D01*
G03X919715Y317460I-440J14D01*
G03X919820Y317467I-6J886D01*
G03X919998Y317509I-72J702D01*
G01X920055Y317530D01*
G03X920225Y317630I-275J662D01*
G03X920287Y317682I-607J787D01*
G03X920385Y317788I-2280J2206D01*
G02X920454Y317888I780J-465D01*
G03X920546Y318122I-852J470D01*
G03X920567Y318304I-611J163D01*
G03X920557Y318436I-1661J-59D01*
G03X920480Y318681I-1035J-191D01*
G03X920368Y318856I-766J-367D01*
G03X920190Y319016I-771J-679D01*
G03X920002Y319108I-508J-799D01*
G03X919851Y319148I-304J-843D01*
G02X919839Y319149I0J72D01*
G01X919832Y319151D01*
X919804Y319156D01*
X919764Y319158D01*
X919716D01*
G02Y319188I179J15D01*
G37*
G36*
G01X923096Y313339D02*
Y313475D01*
G02X923103Y313539I264J4D01*
G02X923169Y313644I191J-47D01*
G02X923195Y313662I180J-233D01*
G02X923308Y313691I100J-157D01*
G02X923300Y311225I-205J-1232D01*
G01X923261Y311228D01*
G02X923245Y311235I60J159D01*
G02X923229Y311239I35J176D01*
G01X923205Y311249D01*
G02X923175Y311270I52J107D01*
G02X923163Y311280I52J74D01*
G02X923142Y311301I112J133D01*
G02X923139Y311305I12J12D01*
G01X923132Y311314D01*
X923127Y311320D01*
X923118Y311338D01*
X923116Y311340D01*
X923111Y311355D01*
X923105Y311374D01*
G02X923099Y311399I171J54D01*
G01X923096Y311412D01*
Y311460D01*
G02X923097Y311552I1068J34D01*
G03X923096Y311609I-440J21D01*
G03X923200Y311616I-7J886D01*
G03X923378Y311659I-75J702D01*
G01X923435Y311679D01*
G03X923605Y311780I-278J661D01*
G03X923667Y311831I-600J793D01*
G03X923766Y311938I-2279J2208D01*
G02X923835Y312038I780J-464D01*
G03X923927Y312271I-852J471D01*
G03X923947Y312454I-612J159D01*
G03X923938Y312586I-1662J-47D01*
G03X923861Y312831I-1036J-191D01*
G03X923749Y313006I-766J-367D01*
G03X923570Y313165I-767J-683D01*
G03X923382Y313258I-511J-797D01*
G03X923231Y313297I-299J-845D01*
G02X923219Y313298I0J72D01*
G01X923212Y313300D01*
X923184Y313305D01*
X923145Y313307D01*
X923097Y313308D01*
G02X923096Y313339I178J21D01*
G37*
G36*
G01Y305538D02*
Y305676D01*
G02X923103Y305740I264J4D01*
G02X923169Y305845I191J-47D01*
G02X923195Y305863I181J-233D01*
G02X923307Y305891I99J-158D01*
G02X923300Y303426I-206J-1232D01*
G01X923264Y303429D01*
G02X923245Y303435I41J164D01*
G02X923229Y303438I25J178D01*
G01X923207Y303449D01*
X923206D01*
G02X923174Y303470I49J109D01*
G02X923163Y303480I55J72D01*
G02X923141Y303501I109J136D01*
G02X923137Y303505I11J15D01*
G01X923131Y303515D01*
X923127Y303521D01*
X923126Y303522D01*
X923120Y303532D01*
G02X923119Y303534I9J6D01*
G01X923117Y303538D01*
X923104Y303574D01*
G02X923098Y303600I172J53D01*
G01X923096Y303613D01*
X923098Y303625D01*
X923096Y303637D01*
Y303657D01*
X923095Y303660D01*
G02X923097Y303752I1068J23D01*
G03X923095Y303810I-440J14D01*
G03X923200Y303817I-6J886D01*
G03X923377Y303859I-73J702D01*
G01X923435Y303880D01*
G03X923605Y303980I-275J662D01*
G03X923667Y304032I-607J787D01*
G03X923765Y304138I-2280J2206D01*
G02X923834Y304238I780J-465D01*
G03X923926Y304472I-852J470D01*
G03X923947Y304654I-611J163D01*
G03X923937Y304786I-1661J-59D01*
G03X923860Y305031I-1035J-191D01*
G03X923748Y305206I-766J-367D01*
G03X923570Y305366I-771J-679D01*
G03X923382Y305458I-508J-799D01*
G03X923231Y305498I-304J-843D01*
G02X923219Y305499I0J72D01*
G01X923212Y305501D01*
X923184Y305506D01*
X923144Y305508D01*
X923096D01*
G02Y305538I179J15D01*
G37*
G36*
G01Y301629D02*
Y301766D01*
G02X923103Y301830I264J4D01*
G02X923169Y301935I191J-47D01*
G02X923195Y301953I181J-233D01*
G02X923308Y301981I99J-158D01*
G02X923300Y299515I-205J-1232D01*
G01X923261Y299518D01*
G02X923245Y299525I60J159D01*
G02X923229Y299529I35J176D01*
G01X923205Y299539D01*
G02X923175Y299560I52J107D01*
G02X923163Y299570I52J75D01*
G02X923142Y299591I112J133D01*
G02X923139Y299594I11J14D01*
G01X923131Y299606D01*
X923127Y299610D01*
X923118Y299628D01*
X923116Y299630D01*
X923111Y299645D01*
X923105Y299664D01*
G02X923099Y299689I171J54D01*
G01X923096Y299702D01*
Y299751D01*
G02X923097Y299842I1068J34D01*
G03X923096Y299899I-440J21D01*
G03X923200Y299907I-16J886D01*
G03X923378Y299949I-72J702D01*
G01X923435Y299970D01*
G03X923605Y300070I-275J662D01*
G03X923667Y300122I-607J787D01*
G03X923766Y300228I-2269J2218D01*
G02X923835Y300328I780J-464D01*
G03X923927Y300561I-852J471D01*
G03X923947Y300744I-612J159D01*
G03X923938Y300876I-1662J-47D01*
G03X923861Y301121I-1036J-191D01*
G03X923749Y301296I-766J-367D01*
G03X923570Y301455I-767J-683D01*
G03X923382Y301548I-511J-796D01*
G03X923231Y301588I-304J-843D01*
G02X923216Y301589I-3J72D01*
G01X923214Y301590D01*
X923184Y301596D01*
X923145Y301597D01*
X923097Y301598D01*
G02X923096Y301629I178J21D01*
G37*
G36*
G01X923095Y293851D02*
X923096Y293857D01*
Y293985D01*
X923095Y293986D01*
G02X923103Y294051I264J1D01*
G02X923168Y294156I191J-46D01*
G02X923194Y294174I181J-233D01*
G02X923307Y294203I100J-157D01*
G02X923299Y291737I-205J-1232D01*
G01X923260Y291740D01*
G02X923244Y291747I60J159D01*
G02X923207Y291759I37J176D01*
G02X923174Y291781I49J109D01*
G02X923162Y291792I55J72D01*
G02X923141Y291813I112J133D01*
G02X923138Y291817I12J12D01*
G01X923131Y291826D01*
X923126Y291832D01*
X923117Y291850D01*
X923116Y291851D01*
X923115Y291855D01*
X923113Y291858D01*
X923111Y291867D01*
X923104Y291886D01*
G02X923098Y291911I171J54D01*
G01X923095Y291924D01*
X923096D01*
Y291968D01*
X923095Y291972D01*
G02X923096Y292064I1068J34D01*
G03X923095Y292121I-439J21D01*
G03X923200Y292128I-6J886D01*
G03X923377Y292170I-73J702D01*
G01X923434Y292191D01*
G03X923604Y292292I-277J660D01*
G03X923666Y292343I-600J792D01*
G03X923765Y292449I-2269J2218D01*
G02X923834Y292549I780J-464D01*
G03X923926Y292783I-853J470D01*
G03X923946Y292965I-612J159D01*
G03X923937Y293098I-1662J-46D01*
G03X923860Y293342I-1035J-193D01*
G03X923748Y293518I-767J-365D01*
G03X923569Y293677I-767J-683D01*
G03X923381Y293770I-511J-797D01*
G03X923230Y293809I-299J-845D01*
G02X923218Y293810I0J72D01*
G01X923211Y293812D01*
X923184Y293817D01*
X923144Y293819D01*
X923096Y293820D01*
G02X923095Y293851I178J21D01*
G37*
G36*
G01X923096Y286042D02*
Y286178D01*
G02X923103Y286242I264J4D01*
G02X923169Y286347I191J-47D01*
G02X923195Y286365I181J-233D01*
G02X923308Y286394I100J-157D01*
G02X923300Y283928I-205J-1232D01*
G01X923261Y283931D01*
G02X923245Y283938I60J159D01*
G02X923208Y283950I37J176D01*
G02X923175Y283972I49J109D01*
G02X923163Y283983I55J72D01*
G02X923142Y284004I112J133D01*
G02X923139Y284008I12J12D01*
G01X923132Y284017D01*
X923127Y284023D01*
X923118Y284041D01*
X923116Y284043D01*
X923111Y284058D01*
X923105Y284077D01*
G02X923099Y284102I171J54D01*
G01X923096Y284115D01*
Y284163D01*
G02X923097Y284255I1068J34D01*
G03X923096Y284312I-440J21D01*
G03X923200Y284319I-7J886D01*
G03X923378Y284361I-72J702D01*
G01X923435Y284382D01*
G03X923605Y284483I-277J661D01*
G03X923667Y284534I-600J792D01*
G03X923766Y284640I-2269J2218D01*
G02X923835Y284740I780J-464D01*
G03X923927Y284974I-853J470D01*
G03X923947Y285156I-612J159D01*
G03X923938Y285289I-1662J-46D01*
G03X923861Y285533I-1035J-193D01*
G03X923749Y285708I-766J-367D01*
G03X923570Y285868I-769J-680D01*
G03X923382Y285960I-507J-799D01*
G03X923231Y286000I-304J-843D01*
G02X923219Y286001I0J72D01*
G01X923212Y286003D01*
X923184Y286008D01*
X923145Y286010D01*
X923097Y286011D01*
G02X923096Y286042I178J21D01*
G37*
G36*
G01X919716Y284087D02*
Y284223D01*
G02X919723Y284287I264J4D01*
G02X919789Y284392I191J-47D01*
G02X919815Y284410I181J-233D01*
G02X919928Y284438I99J-157D01*
G02X919920Y281973I-206J-1232D01*
G01X919881Y281976D01*
G02X919865Y281983I60J159D01*
G02X919851Y281985I18J178D01*
G01X919824Y281997D01*
G02X919795Y282017I52J107D01*
G02X919783Y282027I52J75D01*
G02X919778Y282031I107J138D01*
G01X919741Y282067D01*
X919737Y282087D01*
X919731Y282103D01*
X919725Y282122D01*
G02X919719Y282147I171J54D01*
G01X919716Y282160D01*
Y282208D01*
G02X919717Y282300I1068J34D01*
G03X919716Y282357I-440J21D01*
G03X919821Y282364I-6J886D01*
G03X919998Y282406I-73J702D01*
G01X920055Y282427D01*
G03X920225Y282527I-275J662D01*
G03X920287Y282579I-607J787D01*
G03X920386Y282685I-2269J2218D01*
G02X920455Y282785I780J-464D01*
G03X920547Y283019I-853J470D01*
G03X920567Y283201I-612J159D01*
G03X920558Y283334I-1662J-46D01*
G03X920481Y283578I-1035J-193D01*
G03X920369Y283753I-766J-367D01*
G03X920190Y283913I-769J-681D01*
G03X920002Y284005I-507J-799D01*
G03X919851Y284045I-304J-843D01*
G02X919839Y284046I0J72D01*
G01X919832Y284048D01*
X919804Y284053D01*
X919765Y284055D01*
X919717Y284056D01*
G02X919716Y284087I178J21D01*
G37*
G36*
G01X919715Y280193D02*
X919716Y280199D01*
Y280327D01*
X919715Y280328D01*
G02X919723Y280393I264J1D01*
G02X919788Y280498I191J-46D01*
G02X919814Y280516I181J-233D01*
G02X919927Y280545I100J-157D01*
G02X919919Y278079I-205J-1232D01*
G01X919880Y278082D01*
G02X919864Y278089I60J159D01*
G02X919848Y278093I35J176D01*
G01X919825Y278103D01*
G02X919794Y278123I48J109D01*
G02X919783Y278134I58J69D01*
G02X919761Y278155I109J136D01*
G02X919758Y278159I12J12D01*
G01X919751Y278168D01*
X919746Y278174D01*
X919737Y278192D01*
X919736Y278193D01*
X919735Y278197D01*
X919733Y278200D01*
X919731Y278209D01*
X919724Y278228D01*
G02X919718Y278253I171J54D01*
G01X919715Y278266D01*
X919716D01*
Y278310D01*
X919715Y278314D01*
G02X919716Y278406I1068J34D01*
G03X919715Y278463I-439J21D01*
G03X919820Y278470I-6J886D01*
G03X919997Y278512I-73J702D01*
G01X920054Y278533D01*
G03X920224Y278634I-277J661D01*
G03X920286Y278685I-600J792D01*
G03X920385Y278792I-2279J2208D01*
G02X920454Y278892I780J-465D01*
G03X920546Y279125I-852J471D01*
G03X920566Y279308I-611J159D01*
G03X920557Y279440I-1662J-47D01*
G03X920480Y279684I-1035J-193D01*
G03X920368Y279860I-767J-365D01*
G03X920189Y280019I-767J-683D01*
G03X920001Y280112I-511J-796D01*
G03X919850Y280151I-299J-845D01*
G02X919838Y280152I0J72D01*
G01X919831Y280154D01*
X919804Y280159D01*
X919764Y280161D01*
X919716Y280162D01*
G02X919715Y280193I178J21D01*
G37*
G36*
G01X1093480Y347282D02*
Y348165D01*
X1093461Y348205D01*
G02X1096001Y348204I1270J591D01*
G01X1095982Y348164D01*
Y347282D01*
G02X1093480I-1251J-736D01*
G37*
G36*
G01X847615Y337302D02*
X849602Y335315D01*
Y330485D01*
X848115Y328998D01*
X842085D01*
X840598Y330485D01*
Y335915D01*
X841985Y337302D01*
X842998D01*
Y338502D01*
X846002D01*
Y337302D01*
X847615D01*
G37*
G36*
G01X955644Y309616D02*
X955701Y309562D01*
X955986D01*
X956041Y309607D01*
G02Y307513I856J-1047D01*
G01X955986Y307558D01*
X955701D01*
X955644Y307504D01*
G02Y309616I-997J1056D01*
G37*
G36*
G01X948884D02*
X948941Y309562D01*
X949226D01*
X949281Y309607D01*
G02Y307513I856J-1047D01*
G01X949226Y307558D01*
X948941D01*
X948884Y307504D01*
G02Y309616I-997J1056D01*
G37*
G36*
G01X942124D02*
X942181Y309562D01*
X942466D01*
X942521Y309607D01*
G02Y307513I856J-1047D01*
G01X942466Y307558D01*
X942181D01*
X942124Y307504D01*
G02Y309616I-997J1056D01*
G37*
G36*
G01X935364D02*
X935421Y309562D01*
X935706D01*
X935761Y309607D01*
G02Y307513I856J-1047D01*
G01X935706Y307558D01*
X935421D01*
X935364Y307504D01*
G02Y309616I-997J1056D01*
G37*
G36*
G01X928604D02*
X928661Y309562D01*
X928946D01*
X929001Y309607D01*
G02Y307513I856J-1047D01*
G01X928946Y307558D01*
X928661D01*
X928604Y307504D01*
G02Y309616I-997J1056D01*
G37*
G36*
G01X989443Y301816D02*
X989500Y301762D01*
X989785D01*
X989840Y301807D01*
G02Y299713I856J-1047D01*
G01X989785Y299758D01*
X989500D01*
X989443Y299704D01*
G02Y301816I-997J1056D01*
G37*
G36*
G01X982683D02*
X982740Y301762D01*
X983025D01*
X983080Y301807D01*
G02Y299713I856J-1047D01*
G01X983025Y299758D01*
X982740D01*
X982683Y299704D01*
G02Y301816I-997J1056D01*
G37*
G36*
G01X975923D02*
X975980Y301762D01*
X976265D01*
X976320Y301807D01*
G02Y299713I856J-1047D01*
G01X976265Y299758D01*
X975980D01*
X975923Y299704D01*
G02Y301816I-997J1056D01*
G37*
G36*
G01X969163D02*
X969220Y301762D01*
X969505D01*
X969560Y301807D01*
G02Y299713I856J-1047D01*
G01X969505Y299758D01*
X969220D01*
X969163Y299704D01*
G02Y301816I-997J1056D01*
G37*
G36*
G01X962403D02*
X962460Y301762D01*
X962745D01*
X962800Y301807D01*
G02Y299713I856J-1047D01*
G01X962745Y299758D01*
X962460D01*
X962403Y299704D01*
G02Y301816I-997J1056D01*
G37*
G36*
G01X955644D02*
X955701Y301762D01*
X955986D01*
X956041Y301807D01*
G02Y299713I856J-1047D01*
G01X955986Y299758D01*
X955701D01*
X955644Y299704D01*
G02Y301816I-997J1056D01*
G37*
G36*
G01X948884D02*
X948941Y301762D01*
X949226D01*
X949281Y301807D01*
G02Y299713I856J-1047D01*
G01X949226Y299758D01*
X948941D01*
X948884Y299704D01*
G02Y301816I-997J1056D01*
G37*
G36*
G01X942124D02*
X942181Y301762D01*
X942466D01*
X942521Y301807D01*
G02Y299713I856J-1047D01*
G01X942466Y299758D01*
X942181D01*
X942124Y299704D01*
G02Y301816I-997J1056D01*
G37*
G36*
G01X935364D02*
X935421Y301762D01*
X935706D01*
X935761Y301807D01*
G02Y299713I856J-1047D01*
G01X935706Y299758D01*
X935421D01*
X935364Y299704D01*
G02Y301816I-997J1056D01*
G37*
G36*
G01X928604D02*
X928661Y301762D01*
X928946D01*
X929001Y301807D01*
G02Y299713I856J-1047D01*
G01X928946Y299758D01*
X928661D01*
X928604Y299704D01*
G02Y301816I-997J1056D01*
G37*
G36*
G01X847615Y305702D02*
X849602Y303715D01*
Y298885D01*
X848115Y297398D01*
X842085D01*
X840598Y298885D01*
Y304315D01*
X841985Y305702D01*
X842998D01*
Y306952D01*
X846002D01*
Y305702D01*
X847615D01*
G37*
G36*
G01X989443Y294015D02*
X989500Y293960D01*
X989785D01*
X989840Y294006D01*
G02Y291912I856J-1047D01*
G01X989785Y291958D01*
X989500D01*
X989443Y291903D01*
G02Y294015I-997J1056D01*
G37*
G36*
G01X982683D02*
X982740Y293960D01*
X983025D01*
X983080Y294006D01*
G02Y291912I856J-1047D01*
G01X983025Y291958D01*
X982740D01*
X982683Y291903D01*
G02Y294015I-997J1056D01*
G37*
G36*
G01X975923D02*
X975980Y293960D01*
X976265D01*
X976320Y294006D01*
G02Y291912I856J-1047D01*
G01X976265Y291958D01*
X975980D01*
X975923Y291903D01*
G02Y294015I-997J1056D01*
G37*
G36*
G01X969163D02*
X969220Y293960D01*
X969505D01*
X969560Y294006D01*
G02Y291912I856J-1047D01*
G01X969505Y291958D01*
X969220D01*
X969163Y291903D01*
G02Y294015I-997J1056D01*
G37*
G36*
G01X962403D02*
X962460Y293960D01*
X962745D01*
X962800Y294006D01*
G02Y291912I856J-1047D01*
G01X962745Y291958D01*
X962460D01*
X962403Y291903D01*
G02Y294015I-997J1056D01*
G37*
G36*
G01X955644D02*
X955701Y293960D01*
X955986D01*
X956041Y294006D01*
G02Y291912I856J-1047D01*
G01X955986Y291958D01*
X955701D01*
X955644Y291903D01*
G02Y294015I-997J1056D01*
G37*
G36*
G01X948884D02*
X948941Y293960D01*
X949226D01*
X949281Y294006D01*
G02Y291912I856J-1047D01*
G01X949226Y291958D01*
X948941D01*
X948884Y291903D01*
G02Y294015I-997J1056D01*
G37*
G36*
G01X942124D02*
X942181Y293960D01*
X942466D01*
X942521Y294006D01*
G02Y291912I856J-1047D01*
G01X942466Y291958D01*
X942181D01*
X942124Y291903D01*
G02Y294015I-997J1056D01*
G37*
G36*
G01X935364D02*
X935421Y293960D01*
X935706D01*
X935761Y294006D01*
G02Y291912I856J-1047D01*
G01X935706Y291958D01*
X935421D01*
X935364Y291903D01*
G02Y294015I-997J1056D01*
G37*
G36*
G01X928604D02*
X928661Y293960D01*
X928946D01*
X929001Y294006D01*
G02Y291912I856J-1047D01*
G01X928946Y291958D01*
X928661D01*
X928604Y291903D01*
G02Y294015I-997J1056D01*
G37*
G36*
G01X955644Y286216D02*
X955701Y286162D01*
X955986D01*
X956041Y286207D01*
G02Y284113I856J-1047D01*
G01X955986Y284158D01*
X955701D01*
X955644Y284104D01*
G02Y286216I-997J1056D01*
G37*
G36*
G01X948884D02*
X948941Y286162D01*
X949226D01*
X949281Y286207D01*
G02Y284113I856J-1047D01*
G01X949226Y284158D01*
X948941D01*
X948884Y284104D01*
G02Y286216I-997J1056D01*
G37*
G36*
G01X942124D02*
X942181Y286162D01*
X942466D01*
X942521Y286207D01*
G02Y284113I856J-1047D01*
G01X942466Y284158D01*
X942181D01*
X942124Y284104D01*
G02Y286216I-997J1056D01*
G37*
G36*
G01X935364D02*
X935421Y286162D01*
X935706D01*
X935761Y286207D01*
G02Y284113I856J-1047D01*
G01X935706Y284158D01*
X935421D01*
X935364Y284104D01*
G02Y286216I-997J1056D01*
G37*
G36*
G01X928604D02*
X928661Y286162D01*
X928946D01*
X929001Y286207D01*
G02Y284113I856J-1047D01*
G01X928946Y284158D01*
X928661D01*
X928604Y284104D01*
G02Y286216I-997J1056D01*
G37*
G36*
G01X847615Y274002D02*
X849602Y272015D01*
Y267185D01*
X848115Y265698D01*
X842085D01*
X840598Y267185D01*
Y272615D01*
X841985Y274002D01*
X842998D01*
Y275252D01*
X846002D01*
Y274002D01*
X847615D01*
G37*
G36*
G01X849602Y237185D02*
X848315Y235898D01*
X846002D01*
Y234728D01*
X842998D01*
Y235898D01*
X840485D01*
X839198Y237185D01*
Y244315D01*
X840485Y245602D01*
X842998D01*
Y246732D01*
X846002D01*
Y245602D01*
X847715D01*
X849602Y243715D01*
Y237185D01*
G37*
G36*
G01X1009248Y32310D02*
G03X1009242Y31747I281J-285D01*
G02X1007179Y31768I-1042J-1011D01*
G03X1007185Y32331I-281J285D01*
G02X1009248Y32310I1042J1011D01*
G37*
G36*
G01X1008366Y570991D02*
G03Y570429I285J-281D01*
G02X1006298I-1034J-1019D01*
G03Y570991I-285J281D01*
G02X1008366I1034J1019D01*
G37*
G36*
G01X1031282Y24340D02*
G02X1029579Y24312I-832J-1190D01*
G03X1029568Y24960I-240J320D01*
G02X1031271Y24988I832J1190D01*
G03X1031282Y24340I240J-320D01*
G37*
G36*
G01X1030425Y-7486D02*
G02X1029003Y-8569I-18J-1452D01*
G03X1028621Y-8067I-387J102D01*
G02X1030043Y-6984I18J1452D01*
G03X1030425Y-7486I387J-102D01*
G37*
G36*
G01X1027571Y540020D02*
G03Y539480I295J-270D01*
G02X1025429I-1071J-980D01*
G03Y540020I-295J270D01*
G02X1027571I1071J980D01*
G37*
G36*
G01X1265145Y151638D02*
G03X1265685Y151628I275J290D01*
G02X1265647Y149486I961J-1088D01*
G03X1265107Y149496I-275J-290D01*
G02X1263127Y149550I-961J1088D01*
G03X1262565I-281J-285D01*
G02Y151618I-1019J1034D01*
G03X1263127I281J285D01*
G02X1265145Y151638I1019J-1034D01*
G37*
G36*
G01X1242768Y155762D02*
G02X1242759Y154082I1180J-846D01*
G03X1242107Y154086I-327J-230D01*
G02X1242116Y155766I-1180J846D01*
G03X1242768Y155762I327J230D01*
G37*
G36*
G01X1263617Y155767D02*
G02X1263510Y153969I1083J-967D01*
G03X1262883Y154006I-328J-229D01*
G02X1262990Y155804I-1083J967D01*
G03X1263617Y155767I328J229D01*
G37*
G36*
G01X1180130Y202546D02*
G03X1180072Y202545I-21J-438D01*
G03X1180065Y202651I-885J-5D01*
G03X1180023Y202828I-701J-73D01*
G01X1180002Y202885D01*
G03X1179902Y203054I-660J-276D01*
G03X1179850Y203117I-791J-600D01*
G03X1179745Y203215I-2216J-2269D01*
G02X1179645Y203284I465J781D01*
G03X1179410Y203376I-469J-852D01*
G03X1179229Y203396I-159J-610D01*
G03X1179097Y203387I47J-1661D01*
G03X1178852Y203310I191J-1035D01*
G03X1178678Y203198I369J-764D01*
G03X1178518Y203020I678J-770D01*
G03X1178426Y202833I797J-508D01*
G03X1178386Y202682I842J-304D01*
G02X1178383Y202664I-73J3D01*
G01X1178378Y202635D01*
X1178376Y202595D01*
X1178375Y202546D01*
G02X1178338I-18J180D01*
G01X1178209D01*
G02X1178142Y202553I-6J265D01*
G02X1178037Y202619I47J192D01*
G02X1178019Y202646I237J177D01*
G02X1177991Y202758I158J99D01*
G02X1180458Y202750I1233J-206D01*
G01X1180455Y202723D01*
G03X1180454Y202713I135J-19D01*
G03X1180453Y202708I133J-29D01*
G02X1180449Y202694I-166J40D01*
G02X1180443Y202673I-177J39D01*
G03X1180435Y202657I157J-88D01*
G02X1180414Y202624I-111J47D01*
G02X1180404Y202613I-73J56D01*
G02X1180382Y202591I-135J113D01*
G02X1180374Y202586I-14J13D01*
G03X1180363Y202576I307J-348D01*
G01X1180362D01*
X1180355Y202572D01*
G02X1180348Y202569I-8J9D01*
G01X1180344Y202567D01*
G03X1180336Y202563I7J-24D01*
G01X1180328Y202561D01*
X1180309Y202554D01*
G02X1180283Y202548I-54J173D01*
G01X1180270Y202545D01*
Y202546D01*
X1180226D01*
G02X1180130I-48J1068D01*
G37*
G36*
G01X1268360Y89939D02*
Y87526D01*
X1263856D01*
Y88026D01*
X1262356D01*
Y91030D01*
X1263856D01*
Y91952D01*
X1263838Y91992D01*
G02X1266590Y92363I1319J607D01*
G01X1266573Y92262D01*
X1266787Y92048D01*
X1267155Y92416D01*
X1267142Y92514D01*
G02X1269901Y92100I1439J192D01*
G01X1269882Y92061D01*
Y91462D01*
X1268360Y89939D01*
G37*
G36*
G01X1256682Y78754D02*
Y73857D01*
G02X1253554I-1564J0D01*
G01Y78833D01*
G02X1253611Y79254I1564J3D01*
G01X1253618Y79280D01*
Y82884D01*
X1256622D01*
Y79273D01*
X1256629Y79247D01*
G02X1256683Y78759I-1509J-414D01*
G01X1256682Y78754D01*
G37*
G36*
G01X1263593Y65698D02*
G02X1266721Y65700I1564J1D01*
G01X1266723Y60724D01*
G02X1266668Y60309I-1564J-4D01*
G01X1266660Y60283D01*
Y59565D01*
G03X1267287Y59236I400J0D01*
G02Y56844I824J-1196D01*
G03X1266692Y56672I-227J-329D01*
G01X1263658D01*
Y60283D01*
X1263650Y60309D01*
G02X1263595Y60722I1509J411D01*
G01X1263593Y65698D01*
G37*
G36*
G01X1256682Y40954D02*
Y36057D01*
G02X1253554I-1564J0D01*
G01Y41033D01*
G02X1253611Y41454I1564J3D01*
G01X1253618Y41480D01*
Y45084D01*
X1256622D01*
Y41473D01*
X1256629Y41447D01*
G02X1256683Y40959I-1509J-414D01*
G01X1256682Y40954D01*
G37*
G36*
G01X1263650Y22509D02*
G02X1263595Y22922I1509J411D01*
G01X1263593Y27898D01*
G02X1266123Y29129I1564J1D01*
G03X1266714Y29239I247J315D01*
G02X1267303Y27199I1246J-745D01*
G03X1266722Y26842I-181J-357D01*
G01X1266723Y22924D01*
G02X1266668Y22509I-1564J-4D01*
G01X1266660Y22483D01*
Y18872D01*
X1263658D01*
Y22483D01*
X1263650Y22509D01*
G37*
G36*
G01X1256622Y22483D02*
Y18872D01*
X1253618D01*
Y22476D01*
X1253611Y22502D01*
G02X1253554Y22923I1507J418D01*
G01Y27899D01*
G02X1256682I1564J0D01*
G01Y23002D01*
X1256683Y22997D01*
G02X1256629Y22509I-1563J-74D01*
G01X1256622Y22483D01*
G37*
G36*
G01X1268360Y11776D02*
Y10998D01*
X1263856D01*
Y11498D01*
X1262356D01*
Y14502D01*
X1263856D01*
Y15002D01*
X1268360D01*
Y14380D01*
X1269055D01*
X1269094Y14398D01*
G02Y11758I606J-1320D01*
G01X1269055Y11776D01*
X1268360D01*
G37*
G36*
G01X1256682Y3154D02*
Y-1743D01*
G02X1253554I-1564J0D01*
G01Y3233D01*
G02X1253611Y3654I1564J3D01*
G01X1253618Y3680D01*
Y7284D01*
X1256622D01*
Y3673D01*
X1256629Y3647D01*
G02X1256683Y3159I-1509J-414D01*
G01X1256682Y3154D01*
G37*
G36*
G01X1268321Y48998D02*
Y48658D01*
X1268453Y48610D01*
G02X1266968Y48306I-494J-1365D01*
G03X1266695Y48998I-273J292D01*
G01X1264256D01*
Y49498D01*
X1262756D01*
Y52502D01*
X1264256D01*
Y53002D01*
X1264936D01*
Y53356D01*
X1264787Y53395D01*
G02X1266392Y55562I370J1404D01*
G03X1267011Y55485I340J210D01*
G02X1269342Y53837I1011J-1042D01*
G01X1269324Y53798D01*
Y52583D01*
X1268760Y52019D01*
Y48998D01*
X1268321D01*
G37*
G36*
G01X1305376Y168863D02*
G03X1304830Y168862I-272J-293D01*
G02X1304825Y170987I-992J1060D01*
G03X1305371Y170988I272J293D01*
G02X1305376Y168863I992J-1060D01*
G37*
G36*
G01X1316732Y164870D02*
G02X1313728Y164096I-1602J0D01*
G01X1313714Y164121D01*
X1312047Y165788D01*
X1312006Y165803D01*
G02X1311728Y165936I614J1641D01*
G03X1311437Y165700I-102J-172D01*
G02X1310410Y166644I-1375J-466D01*
G03X1310898Y167109I95J388D01*
G02X1312663Y169196I1720J336D01*
G03X1312956Y169879I10J400D01*
G01X1312047Y170788D01*
X1312006Y170803D01*
G02X1314213Y173170I612J1642D01*
G01X1314228Y173137D01*
X1316114Y171251D01*
G02X1315180Y168348I-934J-1301D01*
G01X1314982D01*
G03X1314699Y167666I0J-400D01*
G01X1316732Y165633D01*
Y164870D01*
G37*
G36*
G01X1256684Y617610D02*
Y612634D01*
G02X1253556I-1564J0D01*
G01Y617610D01*
G02X1253611Y618024I1564J3D01*
G01X1253618Y618050D01*
Y621662D01*
X1256622D01*
Y618050D01*
X1256629Y618024D01*
G02X1256684Y617610I-1509J-411D01*
G37*
G36*
G01Y579810D02*
Y574834D01*
G02X1253556I-1564J0D01*
G01Y579810D01*
G02X1253611Y580224I1564J3D01*
G01X1253618Y580250D01*
Y583862D01*
X1256622D01*
Y580250D01*
X1256629Y580224D01*
G02X1256684Y579810I-1509J-411D01*
G37*
G36*
G01Y561700D02*
Y555144D01*
G02X1253556I-1564J0D01*
G01Y561700D01*
G02X1253611Y562114I1564J3D01*
G01X1253618Y562140D01*
Y565752D01*
X1256622D01*
Y562140D01*
X1256629Y562114D01*
G02X1256684Y561700I-1509J-411D01*
G37*
G36*
G01Y542010D02*
Y537034D01*
G02X1253556I-1564J0D01*
G01Y542010D01*
G02X1253611Y542424I1564J3D01*
G01X1253618Y542450D01*
Y546062D01*
X1256622D01*
Y542450D01*
X1256629Y542424D01*
G02X1256684Y542010I-1509J-411D01*
G37*
G36*
G01X1266721Y604477D02*
X1266723Y599501D01*
G02X1266668Y599086I-1564J-4D01*
G01X1266660Y599060D01*
Y595448D01*
X1266310D01*
G03X1266061Y594735I0J-400D01*
G02X1266165Y594644I-903J-1137D01*
G03X1266728Y594652I277J288D01*
G02X1268855Y594669I1072J-1052D01*
G03X1269409Y594661I281J284D01*
G02X1269852Y592255I991J-1061D01*
G03X1269302Y591885I-150J-370D01*
G01Y591070D01*
X1268360Y590128D01*
Y587998D01*
X1263856D01*
Y588498D01*
X1262356D01*
Y591502D01*
X1263856D01*
Y592018D01*
G03X1264049Y592660I-112J384D01*
G02X1264253Y594735I1108J939D01*
G03X1264004Y595448I-249J313D01*
G01X1263658D01*
Y599060D01*
X1263650Y599086D01*
G02X1263595Y599499I1509J411D01*
G01X1263593Y604475D01*
G02X1263655Y604913I1564J2D01*
G03X1263385Y605409I-384J112D01*
G02X1265216Y606477I415J1391D01*
G03X1265514Y605999I390J-89D01*
G02X1266721Y604477I-357J-1523D01*
G37*
G36*
G01Y566677D02*
X1266723Y561701D01*
G02X1266668Y561286I-1564J-4D01*
G01X1266660Y561260D01*
Y557648D01*
X1266310D01*
G03X1266061Y556935I0J-400D01*
G02X1266569Y556139I-904J-1137D01*
G01X1266582Y556085D01*
X1266763Y555904D01*
X1267123Y556264D01*
X1267139Y556305D01*
G02X1269005Y554439I1361J-505D01*
G01X1268964Y554423D01*
X1268760Y554219D01*
Y549998D01*
X1264256D01*
Y550498D01*
X1262756D01*
Y553502D01*
X1264256D01*
Y554002D01*
X1264936D01*
Y554356D01*
X1264787Y554395D01*
G02X1264253Y556935I370J1404D01*
G03X1264004Y557648I-249J313D01*
G01X1263658D01*
Y561260D01*
X1263650Y561286D01*
G02X1263595Y561699I1509J411D01*
G01X1263593Y566675D01*
G02X1266721Y566677I1564J1D01*
G37*
G36*
G01X1279031Y546635D02*
G02X1277895Y545499I287J-1423D01*
G03X1277424Y545970I-393J78D01*
G02X1278560Y547106I-287J1423D01*
G03X1279031Y546635I393J-78D01*
G37*
G36*
G01X1266721Y528877D02*
X1266723Y523901D01*
G02X1266668Y523486I-1564J-4D01*
G01X1266660Y523460D01*
Y519848D01*
X1266310D01*
G03X1266061Y519135I0J-400D01*
G02X1264253I-904J-1136D01*
G03X1264004Y519848I-249J313D01*
G01X1263658D01*
Y523460D01*
X1263650Y523486D01*
G02X1263595Y523899I1509J411D01*
G01X1263593Y528875D01*
G02X1266721Y528877I1564J1D01*
G37*
G36*
G01X1323498Y146408D02*
X1323013Y147580D01*
X1322628Y147965D01*
X1317918Y149917D01*
X1317047Y150788D01*
X1317006Y150803D01*
G02X1319190Y153218I612J1642D01*
G01X1319205Y153188D01*
X1319780Y152613D01*
X1324442Y150681D01*
X1325729Y149394D01*
X1326702Y147044D01*
Y145000D01*
G02X1323498I-1602J0D01*
G01Y146408D01*
G37*
G36*
G01X1318698Y148846D02*
X1319395Y148149D01*
Y146967D01*
X1319756Y146606D01*
X1321185D01*
X1322103Y145688D01*
Y145050D01*
X1322102D01*
Y141499D01*
X1320438Y139836D01*
X1317455D01*
X1315698Y141592D01*
Y147127D01*
G02X1315955Y147996I1602J-1D01*
G02X1318622Y148880I1663J-551D01*
G01X1318670Y148847D01*
X1318698Y148846D01*
G37*
G36*
G01X1366494Y391564D02*
Y388572D01*
X1364090D01*
Y391576D01*
X1365384D01*
Y395366D01*
X1367388D01*
Y391564D01*
X1366494D01*
G37*
G36*
G01X1364186Y32696D02*
Y29704D01*
X1361784D01*
Y32708D01*
X1363078D01*
Y36498D01*
X1365080D01*
Y32696D01*
X1364186D01*
G37*
G36*
G01X1363876Y672D02*
Y-2320D01*
X1361472D01*
Y684D01*
X1362766D01*
Y4474D01*
X1364770D01*
Y672D01*
X1363876D01*
G37*
G36*
G01X1368186Y610752D02*
Y607760D01*
X1365784D01*
Y610764D01*
X1367078D01*
Y614554D01*
X1369080D01*
Y610752D01*
X1368186D01*
G37*
G36*
G01Y579552D02*
Y576560D01*
X1365784D01*
Y579564D01*
X1367078D01*
Y583354D01*
X1369080D01*
Y579552D01*
X1368186D01*
G37*
G36*
G01X1512762Y605226D02*
Y602822D01*
X1509760D01*
Y604116D01*
X1505968D01*
Y606120D01*
X1509772D01*
Y605226D01*
X1512762D01*
G37*
G36*
G01X1477224Y603958D02*
Y601554D01*
X1474222D01*
Y602848D01*
X1470430D01*
Y604852D01*
X1474234D01*
Y603958D01*
X1477224D01*
G37*
G36*
G01X1492602Y576416D02*
X1490081Y573896D01*
X1475212D01*
X1473597Y575510D01*
X1468528D01*
X1465059D01*
X1464901Y575668D01*
Y583874D01*
X1464509Y584266D01*
Y587805D01*
X1464884Y588180D01*
X1468412D01*
X1468947Y587645D01*
Y584269D01*
X1468259Y583581D01*
Y578784D01*
X1468529Y578514D01*
X1473690D01*
Y589044D01*
X1471982Y590752D01*
Y593736D01*
X1472878Y594632D01*
X1490574D01*
X1492602Y592605D01*
Y576416D01*
G37*
G36*
G01X1522472Y571955D02*
X1521315Y570798D01*
X1506185D01*
X1504898Y572085D01*
Y580892D01*
X1503402D01*
X1500528D01*
X1500329Y581091D01*
Y589350D01*
X1499798Y589881D01*
Y593339D01*
X1500253Y593794D01*
X1503679D01*
X1504247Y593226D01*
Y589874D01*
X1503548Y589175D01*
Y583966D01*
X1503618Y583896D01*
X1504898D01*
Y592815D01*
X1507985Y595902D01*
X1526590D01*
X1528092Y594399D01*
Y588855D01*
X1522472Y583234D01*
Y571955D01*
G37*
G36*
G01X1482720Y530129D02*
G03X1482180I-270J-295D01*
G02Y532271I-980J1071D01*
G03X1482720I270J295D01*
G02Y530129I980J-1071D01*
G37*
G36*
G01X1467633Y571049D02*
G02X1467353Y569357I1016J-1037D01*
G03X1466716Y569463I-357J-180D01*
G02X1466996Y571155I-1016J1037D01*
G03X1467633Y571049I357J180D01*
G37*
G36*
G01X1451809Y571194D02*
G02X1450491I-659J-1294D01*
G03Y571906I-182J356D01*
G02X1451809I659J1294D01*
G03Y571194I182J-356D01*
G37*
G36*
G01X1482920Y538629D02*
G03X1482380I-270J-295D01*
G02Y540771I-980J1071D01*
G03X1482920I270J295D01*
G02Y538629I980J-1071D01*
G37*
G36*
G01X1506830Y419153D02*
G02X1506529Y417983I795J-828D01*
G03X1505870Y418152I-382J-119D01*
G02X1506171Y419322I-795J828D01*
G03X1506830Y419153I382J119D01*
G37*
G36*
G01X1588930Y251180D02*
G03X1588360Y250919I-182J-356D01*
G02X1587612Y252559I-1410J348D01*
G03X1588182Y252820I182J356D01*
G02X1588930Y251180I1410J-348D01*
G37*
G36*
G01X1638925Y145241D02*
X1639332Y145649D01*
X1639346Y145702D01*
G02X1640802Y144246I1166J-290D01*
G01X1640749Y144232D01*
X1640353Y143837D01*
X1640749Y143442D01*
X1640802Y143428D01*
G02X1639346Y141972I-290J-1166D01*
G01X1639332Y142025D01*
X1638925Y142433D01*
X1638849Y142438D01*
G02X1638786Y142443I79J1400D01*
G03X1638565Y142247I-21J-199D01*
G02X1636197Y141972I-1202J16D01*
G01X1636183Y142025D01*
X1635788Y142421D01*
X1635393Y142025D01*
X1635379Y141972D01*
G02X1633923Y143428I-1166J290D01*
G01X1633976Y143442D01*
X1634372Y143837D01*
X1633976Y144232D01*
X1633923Y144246D01*
G02X1635379Y145702I290J1166D01*
G01X1635393Y145649D01*
X1635788Y145253D01*
X1636183Y145649D01*
X1636197Y145702D01*
G02X1638565Y145427I1166J-291D01*
G03X1638786Y145231I200J3D01*
G02X1638849Y145236I142J-1395D01*
G01X1638925Y145241D01*
G37*
G36*
G01X1631301Y144232D02*
X1630905Y143837D01*
X1631301Y143442D01*
X1631354Y143428D01*
G02X1629898Y141972I-290J-1166D01*
G01X1629884Y142025D01*
X1629489Y142421D01*
X1629094Y142025D01*
X1629080Y141972D01*
G02X1627624Y143428I-1166J290D01*
G01X1627677Y143442D01*
X1628073Y143837D01*
X1627677Y144232D01*
X1627624Y144246D01*
G02X1629080Y145702I290J1166D01*
G01X1629094Y145649D01*
X1629489Y145253D01*
X1629884Y145649D01*
X1629898Y145702D01*
G02X1631354Y144246I1166J-290D01*
G01X1631301Y144232D01*
G37*
G36*
G01X1638925Y138942D02*
X1639332Y139350D01*
X1639346Y139403D01*
G02X1640802Y137947I1166J-290D01*
G01X1640749Y137933D01*
X1640353Y137538D01*
X1640749Y137143D01*
X1640802Y137129D01*
G02X1639346Y135673I-290J-1166D01*
G01X1639332Y135726D01*
X1638925Y136134D01*
X1638849Y136139D01*
G02X1638786Y136144I79J1400D01*
G03X1638565Y135948I-21J-199D01*
G02X1636197Y135673I-1202J16D01*
G01X1636183Y135726D01*
X1635788Y136122D01*
X1635393Y135726D01*
X1635379Y135673D01*
G02X1633923Y137129I-1166J290D01*
G01X1633976Y137143D01*
X1634372Y137538D01*
X1633976Y137933D01*
X1633923Y137947D01*
G02X1635379Y139403I290J1166D01*
G01X1635393Y139350D01*
X1635788Y138954D01*
X1636183Y139350D01*
X1636197Y139403D01*
G02X1638565Y139128I1166J-291D01*
G03X1638786Y138932I200J3D01*
G02X1638849Y138937I142J-1395D01*
G01X1638925Y138942D01*
G37*
G36*
G01X1631301Y137933D02*
X1630905Y137538D01*
X1631301Y137143D01*
X1631354Y137129D01*
G02X1629898Y135673I-290J-1166D01*
G01X1629884Y135726D01*
X1629489Y136122D01*
X1629094Y135726D01*
X1629080Y135673D01*
G02X1627624Y137129I-1166J290D01*
G01X1627677Y137143D01*
X1628073Y137538D01*
X1627677Y137933D01*
X1627624Y137947D01*
G02X1629080Y139403I290J1166D01*
G01X1629094Y139350D01*
X1629489Y138954D01*
X1629884Y139350D01*
X1629898Y139403D01*
G02X1631354Y137947I1166J-290D01*
G01X1631301Y137933D01*
G37*
G36*
G01X1638925Y132643D02*
X1639332Y133051D01*
X1639346Y133104D01*
G02X1640802Y131648I1166J-290D01*
G01X1640749Y131634D01*
X1640353Y131239D01*
X1640749Y130844D01*
X1640802Y130830D01*
G02X1639346Y129374I-290J-1166D01*
G01X1639332Y129427D01*
X1638925Y129835D01*
X1638849Y129840D01*
G02X1638786Y129845I79J1400D01*
G03X1638565Y129649I-21J-199D01*
G02X1636197Y129374I-1202J16D01*
G01X1636183Y129427D01*
X1635788Y129823D01*
X1635393Y129427D01*
X1635379Y129374D01*
G02X1633923Y130830I-1166J290D01*
G01X1633976Y130844D01*
X1634372Y131239D01*
X1633976Y131634D01*
X1633923Y131648D01*
G02X1635379Y133104I290J1166D01*
G01X1635393Y133051D01*
X1635788Y132655D01*
X1636183Y133051D01*
X1636197Y133104D01*
G02X1638565Y132829I1166J-291D01*
G03X1638786Y132633I200J3D01*
G02X1638849Y132638I142J-1395D01*
G01X1638925Y132643D01*
G37*
G36*
G01X1631301Y131634D02*
X1630905Y131239D01*
X1631301Y130844D01*
X1631354Y130830D01*
G02X1629898Y129374I-290J-1166D01*
G01X1629884Y129427D01*
X1629489Y129823D01*
X1629094Y129427D01*
X1629080Y129374D01*
G02X1627624Y130830I-1166J290D01*
G01X1627677Y130844D01*
X1628073Y131239D01*
X1627677Y131634D01*
X1627624Y131648D01*
G02X1629080Y133104I290J1166D01*
G01X1629094Y133051D01*
X1629489Y132655D01*
X1629884Y133051D01*
X1629898Y133104D01*
G02X1631354Y131648I1166J-290D01*
G01X1631301Y131634D01*
G37*
G36*
G01X1733639Y498574D02*
X1728638D01*
G02X1727558Y501141I1J1511D01*
G03X1727580Y501676I-286J280D01*
G02X1730073Y502127I1120J924D01*
G03X1730451Y501596I378J-131D01*
G01X1732097D01*
G03X1732471Y502138I0J400D01*
G02X1734831Y501599I1359J512D01*
G03X1734800Y501053I276J-290D01*
G02X1735150Y500095I-1161J-967D01*
G01Y500000D01*
X1735141Y499916D01*
G02X1733639Y498574I-1502J169D01*
G37*
G36*
G01X1750866Y514649D02*
G03X1750497Y514151I18J-399D01*
G02X1749024Y515241I-1407J-361D01*
G03X1749393Y515739I-18J399D01*
G02X1750866Y514649I1407J361D01*
G37*
G36*
G01X1805208Y543122D02*
X1805209Y541153D01*
X1795206Y541152D01*
X1795205Y543255D01*
X1795206D01*
X1795205Y545224D01*
X1805208Y545225D01*
X1805209Y543256D01*
Y543122D01*
X1805208D01*
G37*
G36*
G01X1894588Y588604D02*
X1887584D01*
Y595606D01*
X1894588D01*
Y595567D01*
X1894933D01*
X1894978Y595705D01*
G02X1895283Y594278I1380J-451D01*
G03X1894588Y594009I-295J-269D01*
G01Y588604D01*
G37*
G54D392*
X388187Y50878D03*
Y13078D03*
Y608555D03*
X1037797Y50878D03*
G54D382*
X51607Y511747D03*
X130313Y92757D03*
X153738D03*
X147045D03*
X304328Y12114D03*
Y49914D03*
Y588714D03*
Y550914D03*
X953936Y12114D03*
Y49914D03*
Y588714D03*
Y550914D03*
G54D385*
X122044Y162340D03*
X96249Y204722D03*
X98149Y399769D03*
X753098Y338316D03*
X744698Y332816D03*
X1591865Y237407D03*
X1767250Y94500D03*
Y89500D03*
Y99500D03*
G54D398*
X1392264Y23976D03*
G54D393*
X472163Y317592D03*
Y309793D03*
Y313692D03*
X1121771Y317592D03*
Y309793D03*
Y313692D03*
G54D391*
X401376Y9121D03*
X411416Y9122D03*
X421455Y9121D03*
X438187Y9120D03*
X421456Y17057D03*
X434840Y9120D03*
X424801Y17042D03*
X438187Y17059D03*
X401377Y46922D03*
X411416D03*
X438189D03*
X434842D03*
X1071064Y9122D03*
X1050985D03*
X1087797D03*
X1084450D03*
X1061024D03*
X1074409Y54842D03*
G54D402*
X1944882Y605708D03*
G54D388*
X388407Y253960D03*
Y347560D03*
X431604Y255196D03*
X424844D03*
X431604Y348796D03*
X424844D03*
X1034635Y345609D03*
X1081212Y255196D03*
X1074452D03*
X1038015Y253960D03*
X1081212Y348796D03*
X1074452D03*
X1038015Y347560D03*
G54D380*
X37550Y425400D03*
X40965Y429434D03*
X106200Y26500D03*
X104500Y-1850D03*
X102100Y73800D03*
X116200Y70387D03*
X99500Y223800D03*
X103100Y411800D03*
X106392Y527413D03*
Y537000D03*
X105392Y574800D03*
Y566000D03*
X106192Y604600D03*
X114792Y528600D03*
X113692Y566000D03*
X114792Y604600D03*
X430089Y338428D03*
X426494Y338361D03*
X354607Y292959D03*
X321334Y32100D03*
X334292D03*
X321334Y570900D03*
X334292D03*
X408184Y32100D03*
X433508D03*
X421368D03*
X380200Y-1200D03*
X408184Y570900D03*
X433508D03*
X421368D03*
X376785Y538305D03*
X376892Y577500D03*
X374039Y611186D03*
X447735Y588394D03*
X602163Y16999D03*
X605510D03*
Y9157D03*
Y92599D03*
Y54799D03*
Y46957D03*
Y84757D03*
X620192Y31978D03*
Y-5822D03*
X615549Y16999D03*
X620192Y69778D03*
X647600Y84200D03*
X652718Y93881D03*
X626040Y98281D03*
X618800Y100100D03*
X644750Y175650D03*
X615300Y457900D03*
X648500Y477400D03*
X605510Y510157D03*
Y585757D03*
Y547957D03*
X623600Y521700D03*
X620192Y532978D03*
X618292Y574300D03*
X620033Y608878D03*
X670503Y115884D03*
X649600Y391200D03*
X697200Y79500D03*
X694600Y85000D03*
X756100Y36200D03*
X751708Y73800D03*
X732734Y82626D03*
X751600Y41000D03*
X752900Y101000D03*
X742937Y218574D03*
X742897Y229573D03*
X749640Y431797D03*
X716267Y522020D03*
X763333Y400212D03*
X772300Y403520D03*
X764400Y528600D03*
X763544Y522236D03*
X763706Y514250D03*
X755000Y574800D03*
X763677Y547783D03*
X763300Y566000D03*
X755000D03*
Y614500D03*
X764400Y604600D03*
X755800D03*
X847577Y381842D03*
X970942Y32100D03*
X983900D03*
X970942Y570900D03*
X983900D03*
X1026700Y1700D03*
X1027202Y-11005D03*
X1026500Y577500D03*
X1023200Y610700D03*
X1057792Y32100D03*
X1083116D03*
X1070976D03*
X1057792Y570900D03*
X1070976D03*
X1083116D03*
X1209033Y183907D03*
X1221767Y175858D03*
X1262569Y147201D03*
X1269810Y154398D03*
X1240309Y161900D03*
X1233902Y173337D03*
X1241381Y172040D03*
X1246655Y176395D03*
X1287790Y156575D03*
X1114839Y320075D03*
X1097343Y588394D03*
X1251771Y16999D03*
X1269800Y-5822D03*
X1255118Y16999D03*
Y9157D03*
X1265157Y16999D03*
X1276346Y-10250D03*
X1267976Y73676D03*
X1255118Y92599D03*
Y46957D03*
Y84757D03*
X1270350Y98300D03*
X1275470Y99390D03*
X1298422Y74000D03*
X1295581Y94320D03*
X1304685Y78827D03*
X1298754Y83233D03*
X1301219Y89141D03*
X1301770Y101300D03*
X1281799Y193190D03*
X1267050Y169800D03*
X1263300Y169450D03*
X1300300Y169900D03*
X1305171Y164767D03*
X1255120Y510158D03*
X1269800Y532978D03*
X1267900Y574300D03*
X1273200Y582200D03*
X1277200Y539100D03*
X1308500Y540784D03*
X1305500Y542500D03*
X1304940Y32350D03*
X1296908Y36900D03*
X1304500Y40066D03*
X1327900Y142918D03*
X1397500Y51000D03*
X1389138Y58499D03*
X1382017Y367584D03*
X1377492Y516892D03*
X1369757Y517465D03*
X1503400Y524663D03*
X1478700Y533700D03*
X1474400Y517200D03*
X1489380Y546030D03*
X1525650Y248700D03*
X1532237Y247801D03*
X1521962Y278650D03*
X1527657Y278700D03*
X1533596Y273504D03*
X1587549Y192000D03*
X1582699Y252646D03*
X1584200Y462610D03*
X1597380Y495416D03*
X1600780D03*
X1824240Y83680D03*
X1766100Y521124D03*
X1762715Y521085D03*
X1779303Y497246D03*
X1802119Y56581D03*
X1799438Y44328D03*
X1788216Y59197D03*
X1895523Y586365D03*
G54D366*
X16117Y-43892D03*
X1926693Y646063D03*
G54D396*
X634033Y467638D03*
X641107Y471989D03*
G54D395*
X638541Y171945D03*
Y454425D03*
X752641Y159945D03*
X1288068Y171945D03*
G54D389*
X451883Y344896D03*
X448503Y346847D03*
X1014355Y263709D03*
X1017735Y261760D03*
X1021115Y259809D03*
X1024495Y257860D03*
X1027875Y255909D03*
X1031255Y253960D03*
X1014355Y333909D03*
X1017735Y335860D03*
X1021115Y337809D03*
X1024495Y339760D03*
X1027875Y341709D03*
X1031255Y343660D03*
X1098111Y346847D03*
X1101491Y344896D03*
G54D387*
X357987Y267609D03*
X354607Y269566D03*
Y273465D03*
Y277365D03*
Y281265D03*
Y285164D03*
Y289064D03*
Y296863D03*
Y300763D03*
Y304662D03*
Y308562D03*
X395166Y253960D03*
X401926D03*
X405306Y252009D03*
X438363Y348796D03*
X1007595Y267609D03*
X1010975Y265660D03*
X1004215Y269566D03*
Y273465D03*
Y277365D03*
Y281265D03*
X1007595Y330009D03*
X1010975Y331960D03*
X1004215Y285164D03*
Y289064D03*
Y292963D03*
Y296863D03*
Y300763D03*
Y304662D03*
Y308562D03*
Y312461D03*
Y316361D03*
Y320261D03*
Y324160D03*
Y328060D03*
X1044774Y253960D03*
X1051534D03*
X1054914Y252009D03*
X1087971Y348796D03*
X1044774Y347560D03*
X1051534D03*
G54D394*
X645192Y138250D03*
Y129250D03*
G54D381*
X15512Y434094D03*
X119980Y145531D03*
G54D400*
X1503125Y449400D03*
X1507625Y449825D03*
X1529675Y446675D03*
X1532825D03*
X1535975D03*
X1539125D03*
X1526525Y424625D03*
Y434075D03*
Y437225D03*
X1529675Y424625D03*
Y427775D03*
Y430925D03*
Y434075D03*
Y437225D03*
X1532825Y427775D03*
Y430925D03*
Y434075D03*
Y437225D03*
X1535975Y424625D03*
Y427775D03*
X1539125Y424625D03*
Y427775D03*
X1532825Y424625D03*
X1507625Y421475D03*
Y424625D03*
Y427775D03*
Y430925D03*
Y437225D03*
Y440375D03*
X1510775Y418325D03*
Y421475D03*
Y424625D03*
Y427775D03*
Y430925D03*
Y434075D03*
Y437225D03*
Y440375D03*
X1513925Y421475D03*
Y424625D03*
Y427775D03*
Y430925D03*
Y434075D03*
Y437225D03*
Y440375D03*
X1517075Y424625D03*
Y427775D03*
Y430925D03*
Y434075D03*
Y437225D03*
X1547975Y432500D03*
X1545425Y440375D03*
X1547975Y439260D03*
G54D386*
X224409Y301378D03*
X602362Y214764D03*
X874016Y301378D03*
X1251969Y214764D03*
G54D384*
X94683Y88678D03*
Y514079D03*
X637793Y69778D03*
Y50878D03*
Y88678D03*
Y532955D03*
Y514079D03*
Y570755D03*
Y589679D03*
Y551879D03*
Y608555D03*
X744293Y-5822D03*
Y13078D03*
Y69778D03*
Y88678D03*
X1287403Y69778D03*
Y88678D03*
Y532955D03*
G54D369*
X-7874Y325315D03*
G54D375*
X576200Y649750D03*
G54D370*
X-1969Y178386D03*
G54D367*
X-3937Y-43307D03*
X1956693D03*
X-3937Y646063D03*
X1956693D03*
G54D373*
X388050Y649750D03*
G54D371*
X44291Y178386D03*
G54D399*
X1454685Y338189D03*
X1600355Y527165D03*
G54D383*
X16400Y530800D03*
X13000D03*
X17700Y560800D03*
X21100D03*
X17700Y564200D03*
X21100D03*
X114624Y105143D03*
X117624D03*
X54320Y605500D03*
Y608500D03*
X136400Y206600D03*
X139800D03*
X166450Y209370D03*
X136400Y210000D03*
X139800D03*
Y239300D03*
Y242700D03*
X140200Y271200D03*
X143600D03*
X140200Y274600D03*
X143600D03*
X137100Y304400D03*
X140500D03*
X137100Y307800D03*
X140500D03*
X138909Y335700D03*
X142309D03*
X138909Y339100D03*
X142309D03*
X175450Y206370D03*
Y209370D03*
X193100Y231098D03*
X196100D03*
X193100Y250098D03*
X196100D03*
X193100Y281250D03*
X196100D03*
X365460Y290404D03*
X368460D03*
X370360D03*
X373360D03*
X375260D03*
X378260D03*
X380160D03*
X383160D03*
X385060D03*
X388060D03*
X389960D03*
X392960D03*
X394860D03*
X397860D03*
X399760D03*
X402760D03*
X404660D03*
X365460Y307404D03*
X368460D03*
X370360D03*
X373360D03*
X375260D03*
X378260D03*
X380160D03*
X383160D03*
X385060D03*
X388060D03*
X389960D03*
X392960D03*
X394860D03*
X397860D03*
X399760D03*
X402760D03*
X404660D03*
X193100Y310250D03*
X196100D03*
X383192Y311650D03*
X385092D03*
X388092D03*
X389992D03*
X392992D03*
X394892D03*
X397892D03*
X399792D03*
X402792D03*
X404692D03*
X407692D03*
X428615Y335963D03*
X193100Y342980D03*
X196100D03*
X193100Y361850D03*
X196100D03*
X193100Y370850D03*
X196100D03*
X346250Y11250D03*
Y15150D03*
X331892Y11250D03*
X319692Y49050D03*
X331892D03*
X346250D03*
Y52950D03*
Y550050D03*
Y553950D03*
X331892Y550050D03*
X319622Y553950D03*
Y550050D03*
X346250Y587850D03*
Y591750D03*
X331892Y587850D03*
X319692D03*
X435258Y15150D03*
X422900D03*
X409900D03*
X422900Y11250D03*
X409900D03*
X368042Y11128D03*
Y15028D03*
X422900Y52950D03*
Y49050D03*
X409900D03*
Y52950D03*
X435258D03*
X368428Y52442D03*
X384306Y271741D03*
X384298Y273641D03*
X405589Y276404D03*
X408589D03*
X410489D03*
X413489D03*
X415389D03*
X418389D03*
X420289D03*
X423289D03*
X398756Y276591D03*
X400648D03*
X403648D03*
X384298Y276641D03*
X409360Y281250D03*
X412360D03*
X414360D03*
X417360D03*
X419360D03*
X422360D03*
X368460Y281404D03*
X370360D03*
X373360D03*
X375260D03*
X378260D03*
X380160D03*
X383160D03*
X385060D03*
X388060D03*
X389960D03*
X392960D03*
X394860D03*
X397860D03*
X399760D03*
X402760D03*
X404660D03*
X407660D03*
X424360D03*
X427360D03*
X429360D03*
X432360D03*
X434360D03*
X437360D03*
X439360D03*
X442360D03*
X405589Y267404D03*
X408589D03*
X410489D03*
X413489D03*
X415389D03*
X418389D03*
X420289D03*
X423289D03*
X395756Y267591D03*
X398756D03*
X400648D03*
X403648D03*
X393306Y268741D03*
Y271741D03*
X393298Y273641D03*
X446798Y289591D03*
X449798D03*
X451798D03*
X440163Y297404D03*
X443163D03*
X445063D03*
X448063D03*
X449963D03*
X452963D03*
X425148Y297591D03*
X428148D03*
X430148D03*
X433148D03*
X435148D03*
X438148D03*
X368460Y298404D03*
X370360D03*
X373360D03*
X375260D03*
X378260D03*
X380160D03*
X383160D03*
X385060D03*
X388060D03*
X389960D03*
X392960D03*
X394860D03*
X397860D03*
X399760D03*
X402760D03*
X404660D03*
X407660D03*
X409560D03*
X412560D03*
X414460D03*
X417460D03*
X419360D03*
X422360D03*
X459648Y313091D03*
X365860Y313904D03*
X368860D03*
X370560D03*
X373560D03*
X375260D03*
X383192Y320650D03*
X385092D03*
X388092D03*
X389992D03*
X392992D03*
X394892D03*
X397892D03*
X399792D03*
X402792D03*
X404692D03*
X407692D03*
X409692D03*
X412692D03*
X414692D03*
X417692D03*
X419692D03*
X422692D03*
X424692D03*
X427692D03*
X429692D03*
X432692D03*
X434692D03*
X437692D03*
X439692D03*
X442692D03*
X444692D03*
X447692D03*
X449692D03*
X383913Y322835D03*
X386392Y326250D03*
X389392D03*
X391292Y326450D03*
X394292D03*
X396192D03*
X399192D03*
X401092D03*
X404092D03*
X406007Y326963D03*
X409007D03*
X410907D03*
X413907D03*
X415807D03*
X418807D03*
X420707D03*
X423707D03*
X425615D03*
X428615D03*
X389392Y335250D03*
X391292Y335450D03*
X394292D03*
X396192D03*
X399192D03*
X401092D03*
X404092D03*
X406007Y335963D03*
X409007D03*
X410907D03*
X413907D03*
X415807D03*
X418807D03*
X420707D03*
X368860Y322904D03*
X370560D03*
X373560D03*
X375260D03*
X378260D03*
X412360Y290250D03*
X414360D03*
X417360D03*
X419360D03*
X422360D03*
X424360Y290404D03*
X427360D03*
X429360D03*
X432360D03*
X434360D03*
X437360D03*
X439360D03*
X442360D03*
X440163Y306404D03*
X425148Y306591D03*
X428148D03*
X430148D03*
X433148D03*
X435148D03*
X438148D03*
X412560Y307404D03*
X414460D03*
X417460D03*
X419360D03*
X422360D03*
X412692Y311650D03*
X414692D03*
X417692D03*
X419692D03*
X422692D03*
X424692D03*
X427692D03*
X429692D03*
X432692D03*
X434692D03*
X437692D03*
X439692D03*
X367542Y587850D03*
Y591750D03*
X422900D03*
Y587850D03*
X397450D03*
X409900D03*
Y591750D03*
Y550050D03*
Y553950D03*
X422900D03*
Y550050D03*
X397450D03*
X368442D03*
Y553950D03*
X448063Y306404D03*
X449963D03*
X452963D03*
X447692Y311650D03*
X449692D03*
X452692D03*
X435258Y591750D03*
Y553950D03*
X640873Y138250D03*
X649511D03*
X606250Y11500D03*
X609250D03*
X606250Y14500D03*
X609250D03*
X656393Y34488D03*
X652862Y38150D03*
Y41150D03*
X606250Y49500D03*
X609650D03*
X606250Y52500D03*
X609650D03*
X606200Y88050D03*
X608900D03*
Y91050D03*
X640873Y129250D03*
X649511D03*
X635500Y231750D03*
X638500D03*
X635500Y240750D03*
Y242250D03*
X645050Y296700D03*
X727846Y82530D03*
Y85530D03*
X788399Y205900D03*
X791799D03*
X788399Y209300D03*
X791799D03*
X816750Y209370D03*
X791851Y239266D03*
X795251D03*
X791851Y242666D03*
X795251D03*
X791087Y271198D03*
X794487D03*
X791087Y274598D03*
X794487D03*
X790270Y303300D03*
X793670D03*
X790270Y306700D03*
X793670D03*
X788500Y334700D03*
X791900D03*
X788500Y338100D03*
X791900D03*
X825750Y206370D03*
Y209370D03*
X843000Y231330D03*
X846000D03*
X843000Y250130D03*
X846000D03*
X843000Y278750D03*
X846000D03*
X1015068Y290404D03*
X1018068D03*
X1019968D03*
X1022968D03*
X1024868D03*
X1027868D03*
X1029768D03*
X1032768D03*
X1034668D03*
X1037668D03*
X1039568D03*
X1042568D03*
X1044468D03*
X1047468D03*
X1049368D03*
X1052368D03*
X1054268D03*
X1015068Y307404D03*
X1018068D03*
X1019968D03*
X1022968D03*
X1024868D03*
X1027868D03*
X1029768D03*
X1032768D03*
X1034668D03*
X1037668D03*
X1039568D03*
X1042568D03*
X1044468D03*
X1047468D03*
X1049368D03*
X1052368D03*
X1054268D03*
X843000Y310450D03*
X846000D03*
X1032800Y311650D03*
X1034700D03*
X1037700D03*
X1039600D03*
X1042600D03*
X1044500D03*
X1047500D03*
X1049400D03*
X1052400D03*
X1054300D03*
X1081945Y335593D03*
X843000Y342000D03*
X846000D03*
X844400Y364550D03*
X847400D03*
X969300Y11250D03*
X969200Y553950D03*
Y550050D03*
Y591750D03*
Y587850D03*
X995858Y11250D03*
Y15150D03*
X981500Y11250D03*
X1017650Y11128D03*
Y15028D03*
X1018150Y52750D03*
X981500Y49050D03*
X995858D03*
Y52950D03*
X1033906Y271741D03*
Y273641D03*
X1055197Y276404D03*
X1058197D03*
X1060097D03*
X1063097D03*
X1064997D03*
X1067997D03*
X1069897D03*
X1072897D03*
X1048356Y276591D03*
X1050256D03*
X1053256D03*
X1033906Y276641D03*
X1058968Y281250D03*
X1061968D03*
X1063968D03*
X1066968D03*
X1068968D03*
X1071968D03*
X1018068Y281404D03*
X1019968D03*
X1022968D03*
X1024868D03*
X1027868D03*
X1029768D03*
X1032768D03*
X1034668D03*
X1037668D03*
X1039568D03*
X1042568D03*
X1044468D03*
X1047468D03*
X1049368D03*
X1052368D03*
X1054268D03*
X1057268D03*
X1073968D03*
X1076968D03*
X1078968D03*
X1081968D03*
X1083968D03*
X1086968D03*
X1088968D03*
X1091968D03*
X1096406Y289591D03*
X1099406D03*
X1101406D03*
X1089771Y297404D03*
X1092771D03*
X1094671D03*
X1097671D03*
X1099571D03*
X1102571D03*
X1074756Y297591D03*
X1077756D03*
X1079756D03*
X1082756D03*
X1084756D03*
X1087756D03*
X1018068Y298404D03*
X1019968D03*
X1022968D03*
X1024868D03*
X1027868D03*
X1029768D03*
X1032768D03*
X1034668D03*
X1037668D03*
X1039568D03*
X1042568D03*
X1044468D03*
X1047468D03*
X1049368D03*
X1052368D03*
X1054268D03*
X1057268D03*
X1059168D03*
X1062168D03*
X1064068D03*
X1067068D03*
X1068968D03*
X1071968D03*
X1106000Y300000D03*
Y301500D03*
X1015068Y313854D03*
X1018068D03*
X1019968Y313904D03*
X1022968D03*
X1024868D03*
X1032800Y320650D03*
X1034700D03*
X1037700D03*
X1039600D03*
X1042600D03*
X1044500D03*
X1047500D03*
X1049400D03*
X1052400D03*
X1054300D03*
X1057300D03*
X1059300D03*
X1062300D03*
X1064300D03*
X1067300D03*
X1069300D03*
X1072300D03*
X1074300D03*
X1077300D03*
X1079300D03*
X1082300D03*
X1084300D03*
X1087300D03*
X1089300D03*
X1092300D03*
X1094300D03*
X1097300D03*
X1099300D03*
X1033521Y322835D03*
X1036000Y326250D03*
X1039000D03*
X1040900Y326450D03*
X1043900D03*
X1045800D03*
X1048800D03*
X1050700D03*
X1053700D03*
X1078945Y326593D03*
X1081945D03*
X1055615Y326963D03*
X1058615D03*
X1060515D03*
X1063515D03*
X1065415D03*
X1068415D03*
X1070315D03*
X1073315D03*
X1018068Y322854D03*
X1019968Y322904D03*
X1022968D03*
X1024868D03*
X1027868D03*
X1016950Y591450D03*
X1017750Y549750D03*
X981600Y550050D03*
X995858D03*
Y553950D03*
X981500Y587850D03*
X995858D03*
Y591750D03*
X1072508Y15150D03*
Y11250D03*
X1059508D03*
Y15150D03*
X1084866D03*
X1072508Y52950D03*
Y49050D03*
X1084866Y52950D03*
X1059508Y49050D03*
Y52950D03*
X1096406Y280591D03*
X1099406D03*
X1101406D03*
X1055197Y267404D03*
X1058197D03*
X1060097D03*
X1063097D03*
X1064997D03*
X1067997D03*
X1069897D03*
X1072897D03*
X1045356Y267591D03*
X1048356D03*
X1050256D03*
X1053256D03*
X1042906Y268741D03*
Y271741D03*
Y273641D03*
X1097671Y306404D03*
X1099571D03*
X1102571D03*
X1097300Y311650D03*
X1099300D03*
X1102300D03*
X1039000Y335250D03*
X1040900Y335450D03*
X1043900D03*
X1045800D03*
X1048800D03*
X1050700D03*
X1053700D03*
X1055615Y335963D03*
X1058615D03*
X1060515D03*
X1063515D03*
X1065415D03*
X1068415D03*
X1070315D03*
X1061968Y290250D03*
X1063968D03*
X1066968D03*
X1068968D03*
X1071968D03*
X1073968Y290404D03*
X1076968D03*
X1078968D03*
X1081968D03*
X1083968D03*
X1086968D03*
X1088968D03*
X1091968D03*
X1089771Y306404D03*
X1074756Y306591D03*
X1077756D03*
X1079756D03*
X1082756D03*
X1084756D03*
X1087756D03*
X1062168Y307404D03*
X1064068D03*
X1067068D03*
X1068968D03*
X1071968D03*
X1062300Y311650D03*
X1064300D03*
X1067300D03*
X1069300D03*
X1072300D03*
X1074300D03*
X1077300D03*
X1079300D03*
X1082300D03*
X1084300D03*
X1087300D03*
X1089300D03*
X1072508Y591750D03*
Y587850D03*
X1084866Y591750D03*
X1047058Y587850D03*
X1059508D03*
Y591750D03*
X1072508Y553950D03*
Y550050D03*
X1084866Y553950D03*
X1047058Y550050D03*
X1059508D03*
Y553950D03*
X1255858Y11500D03*
X1258858D03*
X1255858Y14500D03*
X1258858D03*
X1255858Y49500D03*
X1259258D03*
X1255858Y52500D03*
X1259258D03*
X1255858Y88028D03*
X1258858D03*
Y91028D03*
X1311950Y97950D03*
Y100950D03*
X1322900Y509250D03*
X1318549Y511516D03*
X1258250Y511700D03*
X1256250Y514700D03*
X1258250D03*
X1255858Y550500D03*
X1259258D03*
Y553500D03*
X1255858Y588500D03*
X1258858D03*
Y591500D03*
X1362500Y366500D03*
X1364000Y368139D03*
X1359100Y369900D03*
X1362500D03*
X1364000Y370139D03*
X1343450Y402800D03*
Y405800D03*
Y407700D03*
Y410700D03*
X1334450Y402800D03*
Y405800D03*
Y407700D03*
Y410700D03*
X1318549Y502516D03*
X1340000Y539050D03*
X1370500Y530500D03*
X1372500D03*
X1353500Y539050D03*
Y541050D03*
X1372500Y525000D03*
X1358900Y554300D03*
Y557700D03*
X1364182Y616900D03*
Y620300D03*
X1451900Y520750D03*
X1454100D03*
X1457100D03*
X1463100Y525950D03*
X1466100D03*
X1468100D03*
X1471100D03*
X1477000Y527250D03*
X1480000D03*
X1485950Y532550D03*
X1488950D03*
X1514220Y550260D03*
X1509050Y551400D03*
X1514220Y553260D03*
X1509050Y554400D03*
X1514079Y555474D03*
X1509050Y556550D03*
X1514079Y558474D03*
X1509050Y559550D03*
X1465033Y589853D03*
X1468433D03*
X1465033Y593253D03*
X1468433D03*
X1465500Y603750D03*
X1467500D03*
X1463100Y516950D03*
X1466100D03*
X1468100D03*
X1471100D03*
X1477000Y518250D03*
X1480000D03*
X1485950Y541550D03*
X1488950D03*
X1500050Y551400D03*
Y554400D03*
Y556550D03*
Y559550D03*
X1523220Y550260D03*
Y553260D03*
X1523079Y555474D03*
Y558474D03*
X1551700Y577300D03*
X1552295Y272725D03*
X1561295D03*
X1593500Y464000D03*
Y462000D03*
X1601000Y498000D03*
X1598000D03*
X1595800D03*
X1613500Y489750D03*
X1610500D03*
X1608500D03*
X1605500D03*
X1581200Y510650D03*
X1578200D03*
X1576200D03*
X1573200D03*
X1601000Y507000D03*
X1598000D03*
X1595800D03*
X1592800D03*
X1590600D03*
X1587600D03*
X1583420Y569704D03*
X1560700Y577300D03*
X1592420Y572704D03*
Y569704D03*
X1585500Y607750D03*
X1597754Y602696D03*
X1588754Y599696D03*
X1585500Y598750D03*
X1582500D03*
X1599250Y370448D03*
Y368748D03*
X1602500Y464000D03*
Y462000D03*
X1616750Y500700D03*
X1613500Y498750D03*
X1610500D03*
X1608500D03*
X1799000Y96300D03*
Y99300D03*
X1790000Y96300D03*
Y99300D03*
X1833500Y155250D03*
X1804598Y165437D03*
Y168437D03*
X1795598Y165437D03*
Y168437D03*
X1830500Y164250D03*
X1833500D03*
G54D377*
X1203800Y649750D03*
G54D376*
X942600D03*
G54D378*
X1256850D03*
G54D368*
X-7875Y216181D03*
G54D401*
X1960433Y224724D03*
G54D379*
X1518450Y649750D03*
G54D374*
X440050D03*
G54D372*
X253700D03*
%LPD*%
G75*
G36*
G01X165500Y233000D02*
Y216800D01*
X163563Y214863D01*
X143800D01*
X143600Y215063D01*
Y234763D01*
X143700Y234863D01*
X163637D01*
X165500Y233000D01*
G37*
G36*
G01Y265130D02*
Y248930D01*
X163563Y246993D01*
X143800D01*
X143600Y247193D01*
Y266893D01*
X143700Y266993D01*
X163637D01*
X165500Y265130D01*
G37*
G36*
G01Y297130D02*
Y280930D01*
X163563Y278993D01*
X143800D01*
X143600Y279193D01*
Y298893D01*
X143700Y298993D01*
X163637D01*
X165500Y297130D01*
G37*
G36*
G01X164800Y329000D02*
Y312700D01*
X162963Y310863D01*
X143600D01*
Y330863D01*
X162937D01*
X164800Y329000D01*
G37*
G36*
G01X144093Y362149D02*
X164351D01*
X165200Y361300D01*
Y344900D01*
X163222Y342922D01*
X143662D01*
X143500Y343084D01*
Y361556D01*
X144093Y362149D01*
G37*
G36*
G01X191330Y236600D02*
X190430Y237500D01*
Y243700D01*
X191330Y244600D01*
X193098D01*
Y244596D01*
X196102D01*
Y244600D01*
X197700D01*
X198700Y243600D01*
Y237400D01*
X197900Y236600D01*
X191330D01*
G37*
G36*
G01X197600Y269100D02*
X191500D01*
X190700Y269900D01*
Y274900D01*
X191500Y275700D01*
X197700D01*
X198400Y275000D01*
Y269900D01*
X197600Y269100D01*
G37*
G36*
G01Y330830D02*
X191500D01*
X190700Y331630D01*
Y336630D01*
X191500Y337430D01*
X197700D01*
X198400Y336730D01*
Y331630D01*
X197600Y330830D01*
G37*
G36*
G01Y298100D02*
X191500D01*
X190700Y298900D01*
Y303900D01*
X191500Y304700D01*
X197700D01*
X198400Y304000D01*
Y298900D01*
X197600Y298100D01*
G37*
G36*
G01X814479Y233939D02*
Y215732D01*
X813608Y214861D01*
X809676D01*
X809674Y214863D01*
X794137D01*
X793300Y215700D01*
Y233463D01*
X794700Y234863D01*
X813555D01*
X814479Y233939D01*
G37*
G36*
G01X847700Y266700D02*
X842500D01*
X841600Y267600D01*
Y272200D01*
X842400Y273000D01*
X847200D01*
X848600Y271600D01*
Y267600D01*
X847700Y266700D01*
G37*
G36*
G01X847900Y236900D02*
X840900D01*
X840200Y237600D01*
Y243900D01*
X840900Y244600D01*
X847300D01*
X848600Y243300D01*
Y237600D01*
X847900Y236900D01*
G37*
G36*
G01X814507Y265464D02*
Y248718D01*
X812652Y246863D01*
X794237D01*
X793200Y247900D01*
Y265363D01*
X794700Y266863D01*
X813108D01*
X814507Y265464D01*
G37*
G36*
G01Y297580D02*
Y280075D01*
X813295Y278863D01*
X794400D01*
X793200Y280063D01*
Y297763D01*
X794300Y298863D01*
X813224D01*
X814507Y297580D01*
G37*
G36*
G01X847700Y330000D02*
X842500D01*
X841600Y330900D01*
Y335500D01*
X842400Y336300D01*
X847200D01*
X848600Y334900D01*
Y330900D01*
X847700Y330000D01*
G37*
G36*
G01Y298400D02*
X842500D01*
X841600Y299300D01*
Y303900D01*
X842400Y304700D01*
X847200D01*
X848600Y303300D01*
Y299300D01*
X847700Y298400D01*
G37*
G36*
G01X814619Y330341D02*
Y311796D01*
X813686Y310863D01*
X793637D01*
X793300Y311200D01*
Y330163D01*
X794000Y330863D01*
X814097D01*
X814619Y330341D01*
G37*
G36*
G01X814450Y361979D02*
Y344951D01*
X812362Y342863D01*
X794500D01*
X793200Y344163D01*
Y361663D01*
X794400Y362863D01*
X813566D01*
X814450Y361979D01*
G37*
G36*
G01X1389138Y58799D02*
G02X1389438Y58499I0J-300D01*
G02X1389138Y58199I-300J0D01*
G02X1388838Y58499I0J300D01*
G02X1389138Y58799I300J0D01*
G37*
G36*
G01X1397500Y51300D02*
G02X1397800Y51000I0J-300D01*
G02X1397500Y50700I-300J0D01*
G02X1397200Y51000I0J300D01*
G02X1397500Y51300I300J0D01*
G37*
G36*
G01X1365719Y497845D02*
G02X1366019Y497545I0J-300D01*
G02X1365719Y497245I-300J0D01*
G02X1365419Y497545I0J300D01*
G02X1365719Y497845I300J0D01*
G37*
G36*
G01X1445800Y574600D02*
G02X1446100Y574300I0J-300D01*
G02X1445800Y574000I-300J0D01*
G02X1445500Y574300I0J300D01*
G02X1445800Y574600I300J0D01*
G37*
G36*
G01X1515482Y281100D02*
G02X1515782Y280800I0J-300D01*
G02X1515482Y280500I-300J0D01*
G02X1515182Y280800I0J300D01*
G02X1515482Y281100I300J0D01*
G37*
G36*
G01X1526175Y594900D02*
X1527091Y593984D01*
Y589270D01*
X1521470Y583649D01*
Y572370D01*
X1520900Y571800D01*
X1506600D01*
X1505900Y572500D01*
Y592400D01*
X1508400Y594900D01*
X1526175D01*
G37*
G36*
G01X1489666Y574897D02*
X1475627D01*
X1474691Y575833D01*
Y589459D01*
X1472983Y591167D01*
Y593321D01*
X1473293Y593631D01*
X1490159D01*
X1491600Y592190D01*
Y576831D01*
X1489666Y574897D01*
G37*
G36*
G01X1781510Y546662D02*
G02X1781810Y546362I0J-300D01*
G02X1781510Y546062I-300J0D01*
G02X1781210Y546362I0J300D01*
G02X1781510Y546662I300J0D01*
G37*
%LPC*%
G75*
G54D397*
X843000Y240730D03*
X846000D03*
G54D390*
X193100Y240598D03*
X196100D03*
G54D383*
X193100Y272250D03*
X196100D03*
X193100Y333980D03*
X196100D03*
X193100Y301250D03*
X196100D03*
X843000Y269750D03*
X846000D03*
X843000Y333000D03*
X846000D03*
X843000Y301450D03*
X846000D03*
%LPD*%
G75*
G54D100*
X85161Y352600D03*
X83587D03*
X82012D03*
X80437D03*
X78862D03*
X77287D03*
X75713D03*
X74138D03*
X72563D03*
X70988D03*
X69413D03*
X67839D03*
X724713Y263600D03*
X723138D03*
X721563D03*
X719988D03*
X718413D03*
X716839D03*
X734161D03*
X732587D03*
X731012D03*
X729437D03*
X727862D03*
X726287D03*
G54D200*
X1282412Y386838D03*
X1291431Y382075D03*
X1284195Y379437D03*
X1288657Y392100D03*
G54D101*
X65100Y355339D03*
Y356913D03*
Y358488D03*
Y360063D03*
Y361638D03*
Y363213D03*
Y364787D03*
Y366362D03*
Y367937D03*
Y369512D03*
Y371087D03*
Y372661D03*
X714100Y266339D03*
Y267913D03*
Y269488D03*
Y271063D03*
Y272638D03*
Y274213D03*
Y275787D03*
Y277362D03*
Y278937D03*
Y280512D03*
Y282087D03*
Y283661D03*
G54D110*
X149920Y137452D03*
Y108452D03*
G54D300*
X1846100Y92325D03*
Y90750D03*
Y89175D03*
G54D102*
X76500Y364000D03*
X725500Y275000D03*
X1906500Y173100D03*
G54D120*
X306092Y100800D03*
X309981Y104689D03*
X955700Y100800D03*
X959589Y104689D03*
G54D111*
X111093Y122603D03*
X118935D03*
Y126345D03*
Y118861D03*
X111093D03*
Y126345D03*
X718916Y92446D03*
X711074D03*
Y96188D03*
X718916D03*
Y99930D03*
X711074D03*
X727916Y499895D03*
X735758D03*
Y503637D03*
Y496153D03*
X727916D03*
Y503637D03*
G54D201*
X1287176Y385127D03*
X1290105Y374700D03*
G54D210*
X1442000Y-15000D03*
X1505000D03*
X1703503D03*
X1769504D03*
G54D112*
X210427Y649635D03*
X398011Y649515D03*
X585479Y649245D03*
X901122Y649224D03*
X1214648Y649213D03*
X1528146Y649243D03*
G54D301*
X1838400Y92325D03*
Y89175D03*
Y90750D03*
G54D130*
X600150Y122700D03*
Y117700D03*
Y112700D03*
X589650Y117700D03*
Y112700D03*
Y122700D03*
X1241406Y119155D03*
Y114155D03*
Y109155D03*
X1230906Y114155D03*
Y109155D03*
Y119155D03*
G54D211*
X1407422Y17283D03*
Y30669D03*
X1410571Y17283D03*
Y30669D03*
X1413721Y17283D03*
Y30669D03*
X1416871Y17283D03*
Y30669D03*
X1420020Y17283D03*
Y30669D03*
X1423170Y17283D03*
Y30669D03*
X1426319Y17283D03*
Y30669D03*
X1429469Y17283D03*
Y30669D03*
X1432619Y17283D03*
Y30669D03*
X1435768Y17283D03*
Y30669D03*
X1438918Y17283D03*
Y30669D03*
X1442067Y17283D03*
Y30669D03*
X1445217Y17283D03*
Y30669D03*
X1448367Y17283D03*
Y30669D03*
X1451516Y17283D03*
Y30669D03*
X1454666Y17283D03*
Y30669D03*
X1457815Y17283D03*
Y30669D03*
X1460965Y17283D03*
Y30669D03*
X1464115Y17283D03*
Y30669D03*
X1486162D03*
X1489311Y17283D03*
Y30669D03*
X1492461Y17283D03*
Y30669D03*
X1495611Y17283D03*
Y30669D03*
X1467264Y17283D03*
Y30669D03*
X1470414Y17283D03*
X1498760D03*
X1470414Y30669D03*
X1473563Y17283D03*
Y30669D03*
X1476713Y17283D03*
Y30669D03*
X1479863Y17283D03*
Y30669D03*
X1483012Y17283D03*
Y30669D03*
X1486162Y17283D03*
X1498760Y30669D03*
G54D310*
X1869250Y112630D03*
Y124450D03*
Y130360D03*
Y114600D03*
Y116570D03*
Y128390D03*
Y126420D03*
Y120510D03*
Y118540D03*
Y122480D03*
G54D103*
X105712Y375972D03*
X1535557Y350894D03*
X1657144Y241740D03*
X1661766Y235420D03*
X1850498Y87606D03*
X1882548Y174684D03*
X1903566Y146090D03*
G54D202*
X1392264Y23976D03*
X1513918D03*
G54D10*
G01X408069Y-1742D02*
X408068Y-1743D01*
G01X357910Y566814D02*
X357872Y566776D01*
G01X428149Y28022D02*
X428147Y28020D01*
G01X428149Y54857D02*
X428147Y54859D01*
G01X434842Y54857D02*
X434840Y54859D01*
G01X997441Y-7108D02*
X1000787Y-4536D01*
G01X977362Y-7108D02*
X979600Y-5388D01*
X980708Y-4536D01*
G01X1007480Y555855D02*
X1007505D01*
X1007518Y555842D01*
G01X1077755Y54859D02*
X1077757Y54857D01*
G01X1084448Y54859D02*
X1084450Y54857D01*
X-17936Y-49379D03*
Y-53779D03*
Y-44979D03*
Y-40579D03*
X-18079Y-35764D03*
Y-58764D03*
X-14186Y196989D03*
Y199989D03*
X-14839Y445588D03*
X-14753Y448601D03*
X-17179Y643156D03*
X-17194Y638753D03*
X-17179Y647556D03*
Y660756D03*
Y651956D03*
Y656356D03*
X-13636Y-40479D03*
Y-44879D03*
Y-53679D03*
X-9079Y-50164D03*
X-4679D03*
X-279D03*
X-9079Y-54264D03*
X-4679D03*
X-279D03*
X22964Y-40379D03*
Y-44779D03*
Y-53579D03*
Y-49179D03*
X18964Y-53579D03*
Y-49179D03*
X13964Y-53579D03*
Y-49179D03*
X8964Y-40379D03*
Y-44779D03*
Y-53579D03*
Y-49179D03*
X3964Y-40379D03*
Y-44779D03*
Y-53579D03*
Y-49179D03*
X25921Y-35764D03*
X30321D03*
X43521D03*
X39121D03*
X34721D03*
X8321D03*
X12721D03*
X21521D03*
X17121D03*
X-13679D03*
X-9279D03*
X3921D03*
X-4879D03*
X-479D03*
X17121Y-58764D03*
X21521D03*
X12721D03*
X8321D03*
X34721D03*
X39121D03*
X43521D03*
X30321D03*
X25921D03*
X-479D03*
X-13679D03*
X-4879D03*
X3921D03*
X-13636Y-49279D03*
X-9279Y-58764D03*
X875Y211336D03*
X6074Y211293D03*
X3474Y211263D03*
X875Y208352D03*
X36200Y208600D03*
X33200D03*
X20700D03*
X17700Y211600D03*
X20700D03*
X17700Y208600D03*
X23700Y211600D03*
Y208600D03*
X33200Y211600D03*
X30200D03*
Y208600D03*
X36200Y211600D03*
X6074Y208321D03*
X3474Y208263D03*
X5500Y218500D03*
X-5300Y200191D03*
X-7900D03*
X-2700Y200202D03*
X-11586Y196989D03*
Y199989D03*
X-2600Y232300D03*
X-5246Y232351D03*
X-7846D03*
X20500Y221000D03*
Y224000D03*
X17500Y221000D03*
Y224000D03*
X23500D03*
Y221000D03*
X33300Y224000D03*
Y221000D03*
X30300D03*
Y224000D03*
X36300D03*
Y221000D03*
X-14129Y235221D03*
X-11484Y235215D03*
Y232215D03*
X-14084D03*
X2678Y221018D03*
X5277Y221110D03*
X5173Y224042D03*
X2574Y223963D03*
X-26Y223982D03*
X19800Y257900D03*
X28868Y457576D03*
Y454576D03*
X28988Y460876D03*
X23718Y460866D03*
X26318D03*
X21118D03*
X20998Y457566D03*
Y454566D03*
X23598D03*
X26198D03*
Y457566D03*
X23598D03*
X8343Y446875D03*
X1108Y455879D03*
X5743Y446875D03*
Y444275D03*
X-261Y450873D03*
X-11652Y445530D03*
Y448530D03*
X-261Y453473D03*
X2339Y448273D03*
Y450873D03*
Y453473D03*
X-261Y445673D03*
X2339D03*
X-261Y448273D03*
X22421Y647556D03*
X26821D03*
X31221D03*
X18021D03*
Y643156D03*
X31221D03*
X26821D03*
X22421D03*
X18006Y638753D03*
X9221Y647556D03*
X13621D03*
Y643156D03*
X9221D03*
X4821D03*
Y647556D03*
X22406Y638753D03*
X26806D03*
X31206D03*
X-12794D03*
X-12779Y647556D03*
Y643156D03*
X40006Y638753D03*
X44406D03*
X35606D03*
X35621Y647556D03*
Y643156D03*
X-9599Y610630D03*
X-3301Y619643D03*
Y601615D03*
X4549Y620682D03*
X4548Y600577D03*
X13801Y624130D03*
Y597130D03*
X23360Y620172D03*
X23352Y601079D03*
X27301Y610630D03*
X18021Y660756D03*
X35621Y656356D03*
X26821Y660756D03*
X18021Y651956D03*
X31221D03*
X22421Y660756D03*
X26821Y651956D03*
X22421D03*
X4821D03*
X13621D03*
X9221D03*
X-8379Y660756D03*
X4821Y656356D03*
X9221D03*
X13621D03*
X-3979D03*
X421D03*
X13621Y660756D03*
X-3979D03*
X421D03*
X4821D03*
X-12779Y651956D03*
X22421Y656356D03*
X26821D03*
X31221D03*
X18021D03*
X-8379D03*
X-12779D03*
X31221Y660756D03*
X35621Y651956D03*
Y660756D03*
X44421D03*
X40021D03*
X-12779D03*
X9221D03*
X107921Y-58764D03*
X102921D03*
X97921D03*
X92921D03*
X87921D03*
X82921D03*
X77921D03*
X72921D03*
X67921D03*
X62921D03*
X57921D03*
X52921D03*
X47921Y-35764D03*
Y-58764D03*
X107921Y-35764D03*
X102921D03*
X97921D03*
X92921D03*
X87921D03*
X82921D03*
X77921D03*
X72921D03*
X67921D03*
X62921D03*
X57921D03*
X52921D03*
X91536Y78481D03*
X95041Y78451D03*
X98633Y78481D03*
X96249Y204722D03*
X64700Y210100D03*
Y212800D03*
X64778Y218062D03*
X58000Y206500D03*
X50500Y205696D03*
X56900Y197800D03*
X93870Y199131D03*
X97730Y188584D03*
X108174Y164127D03*
X58200Y230400D03*
Y233400D03*
X55600Y230400D03*
X53000Y230300D03*
Y233300D03*
X55600Y233400D03*
X58200Y227400D03*
X53000Y227300D03*
X55600Y227400D03*
X58200Y239400D03*
X99000Y230450D03*
Y227450D03*
Y233450D03*
X93800Y236450D03*
X96400D03*
Y230450D03*
Y227450D03*
X93800D03*
Y230450D03*
X96400Y233450D03*
X93800D03*
X99000Y236450D03*
X91200Y227450D03*
Y230450D03*
Y236450D03*
Y233450D03*
X88600D03*
Y236450D03*
Y230450D03*
Y227450D03*
X53000Y239300D03*
X55600Y239400D03*
X58200Y236400D03*
X55600D03*
X53000Y236300D03*
X71500Y263300D03*
X68800D03*
X53004Y244632D03*
X55275Y245900D03*
X57875D03*
X57457Y248537D03*
Y251237D03*
X88200Y250400D03*
Y247400D03*
Y244400D03*
Y253400D03*
Y256300D03*
Y258900D03*
X57444Y257456D03*
X57600Y262800D03*
X57500Y260200D03*
X62800Y265500D03*
X71500Y266000D03*
X65500Y265500D03*
X68800Y266000D03*
X60000Y265500D03*
X90800Y244400D03*
Y250400D03*
Y247400D03*
X98600Y250400D03*
Y247400D03*
Y244400D03*
X93400Y250400D03*
Y247400D03*
Y244400D03*
X96000D03*
Y250400D03*
Y247400D03*
X90800Y253400D03*
Y256300D03*
Y258900D03*
X93400Y253400D03*
X96000D03*
X98600D03*
X96000Y258900D03*
X93400D03*
Y256300D03*
X96000D03*
X98600D03*
Y258900D03*
X76540Y397355D03*
X81900Y398300D03*
X79140Y397355D03*
X103700Y397200D03*
X106400D03*
X101000D03*
X109100D03*
Y399900D03*
X101000D03*
X106400D03*
X103700D03*
X98149Y399769D03*
X102456Y393756D03*
X76052Y420935D03*
X78000Y423100D03*
X80100Y425000D03*
X81500Y427400D03*
X79700Y409700D03*
X77400Y407800D03*
X81500Y412100D03*
X84913Y434471D03*
X87013Y436371D03*
X104517Y406279D03*
X105761Y409208D03*
X108010Y411479D03*
X107571Y406291D03*
X93040Y496810D03*
X92990Y494210D03*
X93040Y499410D03*
X98240Y496810D03*
X95640D03*
X98240Y499410D03*
X95640D03*
X87790Y494210D03*
X90390D03*
X90440Y496810D03*
X87840D03*
X90390Y491610D03*
X87790D03*
X90440Y499410D03*
X87840D03*
X95777Y494213D03*
X48806Y638753D03*
X75206D03*
X106006D03*
X70806D03*
X53206D03*
X66406D03*
X92806D03*
X97206D03*
X101606D03*
X57606D03*
X62006D03*
X79606D03*
X84006D03*
X88406D03*
X53221Y660756D03*
X101621D03*
X97221D03*
X92821D03*
X106021D03*
X48821D03*
X70821D03*
X66421D03*
X62021D03*
X57621D03*
X75221D03*
X88421D03*
X84021D03*
X79621D03*
X167921Y-58764D03*
X162921D03*
X157921D03*
X152921D03*
X147921D03*
X142921D03*
X137921D03*
X132921D03*
X127921D03*
X122921D03*
X117921D03*
X112921D03*
X162921Y-35764D03*
X157921D03*
X152921D03*
X147921D03*
X142921D03*
X137921D03*
X132921D03*
X127921D03*
X122921D03*
X117921D03*
X112921D03*
X167921D03*
X166000Y212900D03*
X168600D03*
X164300Y207870D03*
X160800Y212900D03*
X163400D03*
X157800Y207300D03*
X161216Y209533D03*
Y206933D03*
X154500Y205500D03*
X150600Y212900D03*
X151000Y205500D03*
X140889Y211972D03*
X137615Y212039D03*
X143900Y204600D03*
X147500Y205500D03*
X137300Y204500D03*
X140200Y204400D03*
X153200Y212900D03*
X122044Y162340D03*
X123624Y164600D03*
X139815Y268974D03*
X137900Y272800D03*
X139800Y237000D03*
X165825Y239543D03*
X168425Y236943D03*
Y239543D03*
X165825Y236943D03*
X163225D03*
X152825D03*
X145025D03*
X147625D03*
X150225D03*
X142425D03*
X122231Y234716D03*
X125564Y237816D03*
X122632D03*
X163225Y239543D03*
X158025Y236943D03*
X155425D03*
X160625D03*
X142371Y244384D03*
X122231Y266716D03*
X122531Y269816D03*
X125463D03*
X142466Y268982D03*
X142700Y276200D03*
X136729Y276386D03*
X139683Y276174D03*
X163225Y242143D03*
X168425Y244743D03*
X165825D03*
X163225D03*
X168425Y242143D03*
X165825D03*
X150700Y276800D03*
X169150Y259470D03*
Y255470D03*
X157633Y268727D03*
X162833D03*
X160233D03*
X165433D03*
X168033Y271327D03*
X162833Y276527D03*
Y273927D03*
Y271327D03*
X165433Y276527D03*
Y273927D03*
Y271327D03*
X159983Y276507D03*
X168033Y276527D03*
Y273927D03*
Y268727D03*
X153300Y276800D03*
X139866Y333016D03*
X160233Y306257D03*
Y308857D03*
Y303657D03*
X157518Y335391D03*
X157745Y332800D03*
X139900Y302400D03*
X142433Y301057D03*
X147633D03*
X150233D03*
X145033D03*
X125500Y333500D03*
X122231Y330716D03*
X122731Y333916D03*
X145200Y341300D03*
X148200D03*
X142465Y332940D03*
X152833Y301057D03*
X163233Y306257D03*
Y308857D03*
X168433Y306257D03*
Y308857D03*
Y301057D03*
X165833D03*
X163233D03*
X160633D03*
X158033D03*
X155433D03*
X169150Y287600D03*
Y291600D03*
X165833Y306257D03*
X163233Y303657D03*
X168433D03*
X165833D03*
Y308857D03*
X151000Y341300D03*
X169150Y323600D03*
Y319600D03*
X160501Y332965D03*
X160274Y335556D03*
X165701Y338165D03*
Y335565D03*
X163101Y332965D03*
X168301D03*
X165701D03*
X163101Y335565D03*
X168301Y340765D03*
Y338165D03*
Y335565D03*
X163101Y338165D03*
Y340765D03*
X165701D03*
X154200Y341100D03*
X125663Y301716D03*
X122231Y298716D03*
X122731Y301716D03*
X139767Y364883D03*
X147833Y364457D03*
X125600Y364900D03*
X122600Y365500D03*
X122331Y362716D03*
X142421Y364908D03*
X145033Y364457D03*
X142863Y402829D03*
X140219Y402894D03*
X137619Y402900D03*
X134992D03*
X142818Y400163D03*
X143073Y397194D03*
X140475Y397310D03*
X140218Y400163D03*
X137529Y400296D03*
X134929D03*
X114084Y399937D03*
X122840Y400827D03*
X111561Y398819D03*
X122000Y397600D03*
X125300Y397700D03*
X122231Y394716D03*
X150633Y364457D03*
X167433Y369657D03*
X169150Y355600D03*
Y351600D03*
X167700Y363900D03*
X161833Y364457D03*
X164633D03*
X159033D03*
X156233D03*
X153433D03*
X164633Y369657D03*
X161833D03*
X161933Y372357D03*
X164733D03*
X167533D03*
X166340Y374785D03*
X167670Y383993D03*
Y387993D03*
X130613Y429647D03*
X123648Y425041D03*
X125328Y427269D03*
X127932Y428571D03*
X110519Y410307D03*
X110199Y413852D03*
X110406Y638753D03*
X145606D03*
X141206D03*
X136806D03*
X132406D03*
X158806D03*
X119206D03*
X123606D03*
X114806D03*
X128006D03*
X163206D03*
X154406D03*
X167606D03*
X150006D03*
X132421Y660756D03*
X145621D03*
X141221D03*
X136821D03*
X123621D03*
X114821D03*
X128021D03*
X110421D03*
X119221D03*
X150021D03*
X167621D03*
X163221D03*
X158821D03*
X154421D03*
X182921Y-58764D03*
X177921D03*
X172921D03*
X227921Y-35764D03*
X222921D03*
X217921D03*
X212921D03*
X207921D03*
X202921D03*
X197921D03*
X192921D03*
X187921D03*
X182921D03*
X177921D03*
X227921Y-58764D03*
X222921D03*
X217921D03*
X212921D03*
X207921D03*
X202921D03*
X197921D03*
X192921D03*
X187921D03*
X172921Y-35764D03*
X176300Y211900D03*
X182300Y216108D03*
X179300D03*
Y213208D03*
X176300Y217308D03*
Y214500D03*
X173300Y217700D03*
Y214800D03*
Y211900D03*
X176400Y234300D03*
X176508Y231609D03*
X179400Y234300D03*
X182400D03*
X176400Y239900D03*
X182400D03*
X179400D03*
X173400D03*
Y231400D03*
Y234300D03*
Y237000D03*
X176400D03*
X182400D03*
X179400D03*
X188200Y236800D03*
X188300Y234000D03*
X185250Y239850D03*
X204200Y249500D03*
X201100Y246500D03*
X198200Y249500D03*
Y246500D03*
X201200Y249500D03*
X203900Y246500D03*
X207200Y249500D03*
X185768Y270065D03*
X173835Y277804D03*
X198082Y277995D03*
X203847Y274933D03*
X203947Y277933D03*
X188510Y272666D03*
X176835Y277804D03*
X182935Y278204D03*
Y275604D03*
X191400Y278400D03*
X188475Y270065D03*
X185735Y275604D03*
X188600Y278300D03*
X188535Y275604D03*
X185735Y278204D03*
X195300Y229250D03*
X188100Y239800D03*
X185250Y234250D03*
Y236950D03*
X176835Y275204D03*
X185754Y272689D03*
X179835Y277804D03*
Y275204D03*
X195100Y252000D03*
X201200Y252500D03*
X198200D03*
X204200D03*
X207200D03*
X200947Y277933D03*
X200847Y274933D03*
X200947Y280933D03*
X173835Y275204D03*
X230800Y265200D03*
X224390Y258920D03*
X219500Y254500D03*
X190800Y295500D03*
X196956Y295583D03*
X193800Y295500D03*
X190665Y306877D03*
X198119Y339710D03*
X191792Y327743D03*
X197792Y327643D03*
X194792D03*
X184800Y295500D03*
X187956Y295583D03*
X181800Y295500D03*
X201177Y330728D03*
Y333728D03*
Y336728D03*
X201163Y339476D03*
Y342476D03*
X204177Y336728D03*
X204060Y342527D03*
X204163Y339476D03*
X188654Y330973D03*
Y327973D03*
X197684Y307227D03*
X200251Y306548D03*
X188630Y333923D03*
X190570Y309539D03*
X185630Y333923D03*
X172800Y295500D03*
Y298400D03*
X198182Y280995D03*
X178956Y295583D03*
X175800Y295500D03*
X187900Y306900D03*
X191300Y339800D03*
X172800Y304000D03*
X175800D03*
X178800D03*
X187800D03*
X181800D03*
X184800D03*
X172800Y301100D03*
X175800D03*
X178800D03*
X181800D03*
X187800D03*
X184800D03*
Y298400D03*
X181800D03*
X175800D03*
X178800D03*
X187800D03*
X185300Y336900D03*
X173300Y337000D03*
Y339900D03*
X188300D03*
Y336900D03*
X179300Y337000D03*
X176300Y339900D03*
X179300D03*
X182300D03*
Y337000D03*
X198223Y342430D03*
X176300Y337000D03*
X185300Y339900D03*
X224000Y330900D03*
X229100Y325900D03*
X219000Y335900D03*
X214000Y340900D03*
X197730Y309959D03*
X204060Y345527D03*
X191300Y343248D03*
X173300Y343448D03*
X188300Y343348D03*
X201045Y345449D03*
X198233Y345402D03*
X195233D03*
X176300Y343448D03*
X201045Y348449D03*
X198233Y348402D03*
Y351402D03*
X195233D03*
X173424Y359621D03*
X188424D03*
X188400Y369787D03*
X176400D03*
X179400Y366787D03*
Y369787D03*
X176400Y366787D03*
X173400Y369787D03*
Y366787D03*
X199900Y370400D03*
X182400Y366787D03*
Y369787D03*
X185400Y366787D03*
Y369787D03*
X188400Y366787D03*
X182424Y359621D03*
X185424D03*
X176424D03*
X179424D03*
X182300Y343448D03*
X173471Y363281D03*
X188471D03*
X182471D03*
X185471D03*
X176471D03*
X179471D03*
X174750Y386308D03*
Y383308D03*
X171158Y382768D03*
Y385768D03*
Y388768D03*
X187100Y394000D03*
X190100Y393000D03*
X197411Y374812D03*
X199754Y376090D03*
X174750Y389308D03*
X199900Y373400D03*
X179300Y343448D03*
X185300Y343348D03*
X211606Y638753D03*
X224806D03*
X220406D03*
X216006D03*
X189606D03*
X198406D03*
X202806D03*
X207206D03*
X176406D03*
X172006D03*
X185206D03*
X180806D03*
X194006D03*
X226500Y649900D03*
X229206Y638753D03*
X224821Y660756D03*
X220421D03*
X198421D03*
X211621D03*
X189621D03*
X202821D03*
X207221D03*
X194021D03*
X185221D03*
X172021D03*
X176421D03*
X180821D03*
X229221D03*
X216021D03*
X292921Y-35764D03*
X287921D03*
X282921D03*
X277921D03*
X272921D03*
X267921D03*
X262921D03*
X257921D03*
X252921D03*
X247921D03*
X242921D03*
X237921D03*
X232921D03*
X292921Y-58764D03*
X287921D03*
X282921D03*
X277921D03*
X272921D03*
X267921D03*
X262921D03*
X257921D03*
X252921D03*
X247921D03*
X242921D03*
X237921D03*
X232921D03*
X234501Y270392D03*
X234000Y320900D03*
X261125Y646784D03*
X251213D03*
X290806Y638753D03*
X268806D03*
X273206D03*
X277606D03*
X282006D03*
X260006D03*
X264406D03*
X255606D03*
X251206D03*
X286406D03*
X242406D03*
X246806D03*
X233606D03*
X238006D03*
X261125Y652784D03*
X251213D03*
X286421Y660756D03*
X268821D03*
X282021D03*
X273221D03*
X277621D03*
X264421D03*
X251221D03*
X255621D03*
X260021D03*
X246821D03*
X242421D03*
X238021D03*
X233621D03*
X290821D03*
X352921Y-58764D03*
Y-35764D03*
X347921Y-58764D03*
Y-35764D03*
X342921Y-58764D03*
Y-35764D03*
X337921Y-58764D03*
Y-35764D03*
X332921Y-58764D03*
Y-35764D03*
X327921Y-58764D03*
Y-35764D03*
X322921Y-58764D03*
Y-35764D03*
X317921Y-58764D03*
Y-35764D03*
X312921Y-58764D03*
X307921D03*
Y-35764D03*
X302921Y-58764D03*
Y-35764D03*
X297921D03*
Y-58764D03*
X312921Y-35764D03*
X330406Y638753D03*
X348006D03*
X326006D03*
X312806D03*
X317206D03*
X321606D03*
X352406D03*
X295206D03*
X299606D03*
X308406D03*
X304006D03*
X334806D03*
X339206D03*
X343606D03*
X312821Y660756D03*
X317221D03*
X308421D03*
X304021D03*
X352421D03*
X295221D03*
X326021D03*
X321621D03*
X339221D03*
X299621D03*
X334821D03*
X330421D03*
X343621D03*
X348021D03*
X392921Y-35764D03*
X387921Y-58764D03*
Y-35764D03*
X382921Y-58764D03*
Y-35764D03*
X377921Y-58764D03*
Y-35764D03*
X372921Y-58764D03*
Y-35764D03*
X367921Y-58764D03*
Y-35764D03*
X362921Y-58764D03*
Y-35764D03*
X357921Y-58764D03*
Y-35764D03*
X392921Y-58764D03*
X402921Y-35764D03*
X397921Y-58764D03*
Y-35764D03*
X412921Y-58764D03*
Y-35764D03*
X407921Y-58764D03*
Y-35764D03*
X402921Y-58764D03*
X404594Y264899D03*
X407594D03*
X411188D03*
X414188D03*
X417190D03*
X380885Y273876D03*
Y270876D03*
X382494Y278904D03*
X371094D03*
X378294D03*
X375294D03*
X368094D03*
X389694D03*
X392694D03*
X385945Y278480D03*
X407094Y278910D03*
X414207D03*
X411288D03*
X404094D03*
X400842Y278914D03*
X368094Y295904D03*
X371094D03*
X385494D03*
X375294D03*
X378294D03*
X382494D03*
X389694D03*
X392694D03*
X365693Y311893D03*
X385494Y309904D03*
X367914Y309910D03*
X371237Y309846D03*
X389502Y309910D03*
X389528Y292910D03*
X392694Y292904D03*
X368116Y293087D03*
X371094Y292904D03*
X373736Y293068D03*
X382625Y293207D03*
X378294Y292904D03*
X385494D03*
X392694Y309904D03*
X374994Y309910D03*
X382497D03*
X378577Y309795D03*
X366822Y324459D03*
X377894Y326777D03*
X378785Y329580D03*
X375223Y326798D03*
X369748Y326902D03*
X367121Y327057D03*
X372391Y326746D03*
X375848Y329512D03*
X391144Y324173D03*
X388394D03*
X385494D03*
X407094Y292904D03*
X396897Y293058D03*
X399894Y292904D03*
X404266Y293030D03*
X407094Y309904D03*
X396709Y309910D03*
X399894Y309904D03*
X404117Y309910D03*
X411294Y295904D03*
X414294D03*
X407094D03*
X404094D03*
X399894D03*
X396894D03*
Y324173D03*
X408894D03*
X411894D03*
X405894D03*
X414894D03*
X393894D03*
X402894D03*
X399894D03*
X389473Y646508D03*
X379561D03*
X383206Y638753D03*
X387606D03*
X392006D03*
X396406D03*
X400806D03*
X405206D03*
X409606D03*
X414006D03*
X370006D03*
X365606D03*
X374406D03*
X378806D03*
X356806D03*
X361206D03*
X379561Y652508D03*
X389473D03*
X374421Y660756D03*
X387621D03*
X383221D03*
X400821D03*
X396421D03*
X392021D03*
X405221D03*
X409621D03*
X414021D03*
X361221D03*
X365621D03*
X356821D03*
X370021D03*
X378821D03*
X477921Y-58764D03*
Y-35764D03*
X472921Y-58764D03*
Y-35764D03*
X467921Y-58764D03*
Y-35764D03*
X462921Y-58764D03*
Y-35764D03*
X457921Y-58764D03*
Y-35764D03*
X452921Y-58764D03*
Y-35764D03*
X447921Y-58764D03*
Y-35764D03*
X442921Y-58764D03*
Y-35764D03*
X437921Y-58764D03*
Y-35764D03*
X432921Y-58764D03*
X422921Y-35764D03*
X417921Y-58764D03*
Y-35764D03*
X432921D03*
X427921Y-58764D03*
Y-35764D03*
X422921Y-58764D03*
X425911Y264710D03*
X420188Y264899D03*
X423092Y264697D03*
X436519Y262232D03*
X436329Y264826D03*
X432643Y264508D03*
X418523Y278910D03*
X428694D03*
X432894D03*
X425694D03*
X435894Y278938D03*
X443094Y278904D03*
X440094D03*
X421523Y278944D03*
X451675Y291739D03*
X449148Y292841D03*
X446209Y292842D03*
X451816Y295904D03*
X435894D03*
X418494D03*
X443094D03*
X440094D03*
X446383Y295841D03*
X428694Y295904D03*
X432894D03*
X425694D03*
X421494D03*
X418494Y324173D03*
X451267Y324476D03*
X448694Y323949D03*
X421494Y324173D03*
X446094Y323904D03*
X425694Y324173D03*
X428694D03*
X432894D03*
X435894D03*
X455226Y291686D03*
X454922Y295841D03*
X438681Y646514D03*
X448593D03*
X466806Y638753D03*
X462406D03*
X475606D03*
X471206D03*
X418406D03*
X422806D03*
X427206D03*
X440406D03*
X436006D03*
X431606D03*
X449206D03*
X458006D03*
X453606D03*
X444806D03*
X448593Y652514D03*
X458021Y660756D03*
X449221D03*
X462421D03*
X466821D03*
X471221D03*
X418421D03*
X438681Y652514D03*
X475621Y660756D03*
X453621D03*
X422821D03*
X427221D03*
X440421D03*
X431621D03*
X436021D03*
X444821D03*
X537921Y-58764D03*
Y-35764D03*
X532921Y-58764D03*
Y-35764D03*
X527921Y-58764D03*
Y-35764D03*
X522921Y-58764D03*
Y-35764D03*
X517921Y-58764D03*
Y-35764D03*
X512921Y-58764D03*
Y-35764D03*
X507921Y-58764D03*
Y-35764D03*
X502921Y-58764D03*
Y-35764D03*
X497921Y-58764D03*
Y-35764D03*
X492921Y-58764D03*
Y-35764D03*
X487921Y-58764D03*
Y-35764D03*
X482921Y-58764D03*
Y-35764D03*
X480006Y638753D03*
X484406D03*
X488806D03*
X493206D03*
X497606D03*
X510806D03*
X537206D03*
X519606D03*
X524006D03*
X532806D03*
X528406D03*
X515206D03*
X502006D03*
X506406D03*
X524021Y660756D03*
X480021D03*
X484421D03*
X497621D03*
X493221D03*
X488821D03*
X519621D03*
X532821D03*
X537221D03*
X528421D03*
X515221D03*
X510821D03*
X506421D03*
X502021D03*
X597921Y-35764D03*
Y-58764D03*
X592921Y-35764D03*
Y-58764D03*
X587921Y-35764D03*
Y-58764D03*
X582921Y-35764D03*
Y-58764D03*
X577921Y-35764D03*
Y-58764D03*
X572921Y-35764D03*
Y-58764D03*
X567921Y-35764D03*
Y-58764D03*
X562921Y-35764D03*
Y-58764D03*
X557921Y-35764D03*
Y-58764D03*
X552921Y-35764D03*
Y-58764D03*
X547921D03*
Y-35764D03*
X542921Y-58764D03*
Y-35764D03*
X576941Y646238D03*
X567029D03*
X590006Y638753D03*
X572406D03*
X559206D03*
X568006D03*
X563606D03*
X550406D03*
X581206D03*
X585606D03*
X576806D03*
X598806D03*
X594406D03*
X601500Y649500D03*
X554806Y638753D03*
X541606D03*
X546006D03*
X576941Y652238D03*
X567029D03*
X559221Y660756D03*
X546021D03*
X554821D03*
X598821D03*
X572421D03*
X568021D03*
X563621D03*
X585621D03*
X541621D03*
X594421D03*
X576821D03*
X590021D03*
X581221D03*
X550421D03*
X637921Y-58764D03*
X632921Y-35764D03*
Y-58764D03*
X627921Y-35764D03*
Y-58764D03*
X622921Y-35764D03*
Y-58764D03*
X617921Y-35764D03*
Y-58764D03*
X612921Y-35764D03*
Y-58764D03*
X607921Y-35764D03*
Y-58764D03*
X602921Y-35764D03*
Y-58764D03*
X652921Y-35764D03*
Y-58764D03*
X647921Y-35764D03*
Y-58764D03*
X642921Y-35764D03*
Y-58764D03*
X637921Y-35764D03*
X662921D03*
Y-58764D03*
X657921Y-35764D03*
Y-58764D03*
X653750Y225500D03*
X641600Y221400D03*
Y226600D03*
Y224000D03*
Y229200D03*
X644500D03*
Y224000D03*
Y226600D03*
X641600Y231800D03*
X644500D03*
X650700Y224000D03*
X647600D03*
X650700Y226600D03*
X647600D03*
X650700Y231800D03*
X647600D03*
Y229200D03*
X650700D03*
X641541Y236028D03*
Y238628D03*
X637001Y227337D03*
Y222137D03*
Y224737D03*
Y229937D03*
X641541Y243828D03*
Y241228D03*
X638406Y638753D03*
X634006D03*
X642806D03*
X629606D03*
X616406D03*
X612006D03*
X603206D03*
X625206D03*
X651606D03*
X647206D03*
X660406D03*
X620806D03*
X656006D03*
X607606D03*
X607621Y660756D03*
X638421D03*
X647221D03*
X616421D03*
X634021D03*
X612021D03*
X620821D03*
X625221D03*
X629621D03*
X642821D03*
X603221D03*
X656021D03*
X660421D03*
X651621D03*
X692921Y-58764D03*
X687921Y-35764D03*
Y-58764D03*
X682921Y-35764D03*
Y-58764D03*
X677921Y-35764D03*
Y-58764D03*
X672921Y-35764D03*
Y-58764D03*
X667921Y-35764D03*
Y-58764D03*
X697921Y-35764D03*
Y-58764D03*
X692921Y-35764D03*
X722921D03*
Y-58764D03*
X717921Y-35764D03*
Y-58764D03*
X712921Y-35764D03*
Y-58764D03*
X707921Y-35764D03*
Y-58764D03*
X702921Y-35764D03*
Y-58764D03*
X704466Y-7874D03*
X690966Y-21374D03*
X700525Y1668D03*
X700517Y-17425D03*
X681713Y-17927D03*
X690966Y5626D03*
X681714Y2178D03*
X673864Y-16889D03*
X667566Y-7874D03*
X673864Y1139D03*
X706164Y390143D03*
X708975Y390174D03*
X711575Y390150D03*
Y393150D03*
X706164Y393143D03*
X708975Y393174D03*
X703160Y392939D03*
X700391Y389737D03*
X703160Y390139D03*
X700291Y392637D03*
X700458Y395503D03*
X703169Y395986D03*
X711575Y396150D03*
X708975Y396174D03*
X706164Y396143D03*
X705673Y387012D03*
Y384412D03*
X711173Y387012D03*
X708373D03*
Y384412D03*
X700204Y386610D03*
X702973Y387012D03*
X700204Y384010D03*
X702973Y384412D03*
X711173Y384312D03*
X695606Y638753D03*
X673606D03*
X708806D03*
X704406D03*
X700006D03*
X722006D03*
X717606D03*
X713206D03*
X664806D03*
X669206D03*
X686806D03*
X682406D03*
X678006D03*
X691206D03*
X690966Y624130D03*
Y597130D03*
X700525Y620172D03*
X700517Y601079D03*
X704466Y610630D03*
X667566D03*
X673864Y619643D03*
Y601615D03*
X681714Y620682D03*
X681713Y600577D03*
X664821Y660756D03*
X695621D03*
X708821D03*
X700021D03*
X704421D03*
X669221D03*
X686821D03*
X691221D03*
X678021D03*
X673621D03*
X682421D03*
X722021D03*
X717621D03*
X713221D03*
X777921Y-58764D03*
X772921Y-35764D03*
Y-58764D03*
X767921Y-35764D03*
Y-58764D03*
X762921Y-35764D03*
Y-58764D03*
X757921Y-35764D03*
Y-58764D03*
X752921Y-35764D03*
Y-58764D03*
X787921Y-35764D03*
Y-58764D03*
X782921Y-35764D03*
Y-58764D03*
X777921Y-35764D03*
X747921D03*
Y-58764D03*
X742921Y-35764D03*
Y-58764D03*
X737921Y-35764D03*
Y-58764D03*
X732921Y-35764D03*
Y-58764D03*
X727921Y-35764D03*
Y-58764D03*
X786674Y211463D03*
X785920Y204763D03*
X786300Y207400D03*
X787200Y244200D03*
Y271900D03*
X787100Y241100D03*
X770632Y234833D03*
X770965Y237519D03*
X773800Y237700D03*
X768382Y237861D03*
X769637Y266647D03*
X770485Y269489D03*
X772630Y266810D03*
X773419Y270414D03*
X787200Y276400D03*
X787100Y303900D03*
X775200Y301200D03*
X770900Y301800D03*
X768290Y301780D03*
X753098Y338316D03*
X747498Y335516D03*
X750298Y338316D03*
Y335516D03*
X744698Y338316D03*
Y335516D03*
X747498Y338316D03*
X744698Y332816D03*
X769440Y298735D03*
X772400Y299400D03*
X787000Y308300D03*
X771730Y330665D03*
X775732Y332989D03*
X770278Y333272D03*
X772949Y333009D03*
X787400Y340400D03*
X747000Y386000D03*
X743500D03*
X750500D03*
X754000D03*
X750298Y344833D03*
X744698Y347833D03*
X747498D03*
X750298D03*
X747673Y364009D03*
X745073D03*
X750273D03*
X747573Y366909D03*
X744973D03*
X750173D03*
X744698Y344833D03*
X747498D03*
X747000Y380000D03*
X743500D03*
X753874Y379863D03*
X750500Y380000D03*
Y374000D03*
X754000D03*
X747000D03*
X743500D03*
X741774Y376463D03*
X769380Y366440D03*
X775070Y365070D03*
X772290Y365020D03*
X769440Y363810D03*
X785400Y372400D03*
X757500Y374000D03*
X775420Y397110D03*
X772742Y397209D03*
X766860Y396240D03*
X769770Y396070D03*
X770406Y638753D03*
X779206D03*
X774806D03*
X730806D03*
X726406D03*
X739606D03*
X735206D03*
X748406D03*
X744006D03*
X766006D03*
X761606D03*
X757206D03*
X752806D03*
X783606D03*
X744021Y660756D03*
X735221D03*
X779221D03*
X770421D03*
X774821D03*
X726421D03*
X730821D03*
X739621D03*
X748421D03*
X783621D03*
X757221D03*
X761621D03*
X752821D03*
X766021D03*
X842921Y-35764D03*
X837921Y-58764D03*
Y-35764D03*
X832921Y-58764D03*
X847921D03*
Y-35764D03*
X842921Y-58764D03*
X832921Y-35764D03*
X827921Y-58764D03*
Y-35764D03*
X822921Y-58764D03*
Y-35764D03*
X817921Y-58764D03*
Y-35764D03*
X812921Y-58764D03*
Y-35764D03*
X807921Y-58764D03*
Y-35764D03*
X802921Y-58764D03*
Y-35764D03*
X797921D03*
Y-58764D03*
X792921Y-35764D03*
Y-58764D03*
X816900Y216300D03*
X816874Y212863D03*
X814274D03*
X811674D03*
X808818Y211179D03*
X808618Y208579D03*
X803200Y213100D03*
X800600D03*
X794474Y211463D03*
X791874D03*
X789274D03*
X788522Y204343D03*
X791122Y204339D03*
X829327Y214740D03*
X832276Y214754D03*
X827322Y217430D03*
X826700Y214802D03*
X824072Y214865D03*
X824446Y217476D03*
X821775Y217617D03*
X821466Y214925D03*
X789432Y236947D03*
X789400Y273700D03*
X811983Y244843D03*
Y242243D03*
X814583Y239643D03*
X815432Y237000D03*
X814583Y244843D03*
Y242243D03*
X812832Y237000D03*
X811983Y239643D03*
X802432Y237000D03*
X799832D03*
X792032D03*
X794632D03*
X810232D03*
X797232D03*
X805032D03*
X807632D03*
X791000Y244400D03*
X793600D03*
X816800Y234300D03*
X816900Y230900D03*
X817000Y252500D03*
X789800Y276400D03*
X792400D03*
X801991Y276557D03*
X804591D03*
X792191Y269101D03*
X789591D03*
X814891Y271657D03*
Y274257D03*
Y276857D03*
Y269057D03*
X812291D03*
Y274257D03*
Y276857D03*
Y271657D03*
X817000Y255100D03*
Y257700D03*
X848282Y251727D03*
X828180Y231748D03*
X828682Y237027D03*
X831682D03*
X828682Y234327D03*
X837500Y239500D03*
X845050Y229400D03*
X837500Y234050D03*
Y236650D03*
X834682Y236877D03*
X840155Y234245D03*
X834700Y234200D03*
X831682Y234327D03*
X834682Y239627D03*
X831682D03*
X828682D03*
X848282Y246427D03*
Y249027D03*
X825682Y239627D03*
Y234327D03*
Y237027D03*
X825313Y231753D03*
X848382Y279727D03*
Y277027D03*
Y274427D03*
X825464Y277510D03*
Y274910D03*
Y280110D03*
X822464D03*
Y277510D03*
Y274910D03*
X834464Y280110D03*
X831464D03*
X828464Y277510D03*
Y274910D03*
Y280110D03*
X834464Y277510D03*
X831464D03*
X834464Y274910D03*
X845050Y252250D03*
X817491Y276857D03*
Y274257D03*
Y271657D03*
Y269057D03*
X837264Y274910D03*
Y280110D03*
Y277510D03*
X840064D03*
Y280110D03*
X817183Y242243D03*
Y239643D03*
Y244843D03*
X818032Y237000D03*
X822682Y234327D03*
Y231727D03*
Y237027D03*
Y239627D03*
X831464Y274910D03*
X844400Y280500D03*
X848282Y254327D03*
X788600Y306100D03*
X789500Y301200D03*
X797300D03*
X799900D03*
X810300D03*
X802500D03*
X812900D03*
X807700D03*
X805100D03*
X815500D03*
X811991Y308957D03*
Y306357D03*
Y303757D03*
X814591Y306357D03*
Y308957D03*
Y303757D03*
X792900Y308400D03*
X789900D03*
X794700Y301200D03*
X792100D03*
X793000Y340400D03*
X790300Y340300D03*
X816991Y337357D03*
Y334757D03*
Y339957D03*
X814391D03*
Y337357D03*
Y334757D03*
X811791Y337357D03*
Y339957D03*
Y334757D03*
X791879Y332798D03*
X794600Y332600D03*
X816938Y319888D03*
Y323888D03*
X817100Y317000D03*
X848382Y282327D03*
X834682Y298527D03*
X828682D03*
X825682D03*
Y295527D03*
Y301227D03*
Y303927D03*
X822682D03*
Y301227D03*
Y295527D03*
Y298527D03*
X844300Y312450D03*
X831682Y298527D03*
X837782Y298127D03*
Y301027D03*
Y303927D03*
X818100Y301200D03*
X817191Y303757D03*
Y306357D03*
Y308957D03*
X834682Y301227D03*
X831682D03*
X828682D03*
X831682Y303927D03*
X834682D03*
X822482Y339827D03*
Y337027D03*
X831482D03*
X834482D03*
X828482Y339827D03*
X831482D03*
X834482D03*
X840282Y340227D03*
X840382Y337427D03*
X837382Y339877D03*
Y337077D03*
X847682Y314627D03*
X847982Y338327D03*
Y341327D03*
X828482Y337027D03*
X828682Y303927D03*
X847682Y309327D03*
Y312027D03*
Y306727D03*
X825482Y339827D03*
Y337027D03*
X789860Y364947D03*
X820218Y385950D03*
Y382950D03*
X826097Y385923D03*
X816591Y369857D03*
Y372457D03*
X811391Y369857D03*
X813991D03*
Y372457D03*
X811391D03*
X790900Y372300D03*
X788300Y372400D03*
X802759Y364575D03*
X816672Y358809D03*
X795310Y364721D03*
X816593Y356210D03*
X807959Y364575D03*
X805359D03*
X810559D03*
X815759D03*
X813159D03*
X816900Y361400D03*
X792610Y364821D03*
X816591Y375057D03*
X792238Y396753D03*
X789600Y396809D03*
X811515Y397289D03*
X808915D03*
X813648Y395557D03*
X815472Y390442D03*
X814877Y393138D03*
X792000Y399409D03*
X789400D03*
X822089Y362782D03*
Y359782D03*
X822482Y342827D03*
X828482D03*
X831482D03*
X834482D03*
X828089Y359841D03*
X834089D03*
X831089D03*
X844350Y344000D03*
X840262Y343011D03*
X837382Y342877D03*
X821658Y369463D03*
X832058Y366863D03*
Y369463D03*
X834658D03*
Y366863D03*
X837363Y366829D03*
X826858Y366863D03*
Y369463D03*
X824258Y366863D03*
Y369463D03*
X829458D03*
Y366863D03*
X821658D03*
X847982Y344327D03*
X834089Y362782D03*
X831089D03*
X826216Y383108D03*
X823218Y382950D03*
X848608Y376068D03*
Y378668D03*
X846008Y376068D03*
Y378668D03*
X848932Y373257D03*
X823218Y385950D03*
X828089Y362782D03*
X825482Y342827D03*
X825089Y359841D03*
Y362782D03*
X849606Y638753D03*
X836406D03*
X832006D03*
X796806D03*
X801206D03*
X792406D03*
X827606D03*
X818806D03*
X823206D03*
X810006D03*
X788006D03*
X845206D03*
X814406D03*
X805606D03*
X840806D03*
X849621Y660756D03*
X832021D03*
X810021D03*
X818821D03*
X836421D03*
X788021D03*
X814421D03*
X801221D03*
X805621D03*
X823221D03*
X827621D03*
X840821D03*
X796821D03*
X792421D03*
X845221D03*
X907921Y-58764D03*
Y-35764D03*
X902921Y-58764D03*
Y-35764D03*
X897921Y-58764D03*
Y-35764D03*
X892921Y-58764D03*
Y-35764D03*
X887921Y-58764D03*
Y-35764D03*
X882921Y-58764D03*
Y-35764D03*
X877921Y-58764D03*
Y-35764D03*
X872921Y-58764D03*
Y-35764D03*
X867921Y-58764D03*
Y-35764D03*
X862921Y-58764D03*
Y-35764D03*
X857921Y-58764D03*
Y-35764D03*
X852921Y-58764D03*
Y-35764D03*
X854282Y251727D03*
X857282D03*
X851282D03*
X857282Y249027D03*
Y246427D03*
X851282D03*
Y249027D03*
X854282D03*
Y246427D03*
X851382Y277027D03*
Y274427D03*
X857382Y277027D03*
X854382Y279727D03*
X857382D03*
X854382Y274427D03*
X857382D03*
X854382Y277027D03*
X874586Y259278D03*
X854282Y254327D03*
X857282D03*
X869586Y254278D03*
X851282Y254327D03*
X851382Y279727D03*
X884586Y269278D03*
X879586Y264278D03*
X889586Y274278D03*
X851382Y282327D03*
X854382D03*
X857382D03*
X851075Y335405D03*
X857075D03*
X856982Y338327D03*
X853982D03*
X856682Y314627D03*
X853682D03*
X850682D03*
X856982Y341327D03*
X853982D03*
X862008Y341100D03*
X850982Y338327D03*
Y341327D03*
X872008Y331100D03*
X867008Y336100D03*
X850682Y306727D03*
Y309327D03*
Y312027D03*
X856682Y309327D03*
X853682D03*
X856682Y306727D03*
X853682D03*
X856682Y312027D03*
X853682D03*
X877008Y326100D03*
X854075Y335405D03*
X856982Y344327D03*
X853982D03*
X850982D03*
X851208Y376068D03*
Y378668D03*
X851727Y373197D03*
X858406Y638753D03*
X854006D03*
X884806D03*
X880406D03*
X876006D03*
X871606D03*
X867206D03*
X911206D03*
X906806D03*
X889206D03*
X898006D03*
X902406D03*
X893606D03*
X862806D03*
X854021Y660756D03*
X858421D03*
X862821D03*
X898021D03*
X902421D03*
X871621D03*
X884821D03*
X893621D03*
X867221D03*
X889221D03*
X911221D03*
X906821D03*
X880421D03*
X876021D03*
X937921Y-35764D03*
X932921Y-58764D03*
Y-35764D03*
X927921Y-58764D03*
Y-35764D03*
X922921Y-58764D03*
Y-35764D03*
X917921Y-58764D03*
Y-35764D03*
X912921Y-58764D03*
Y-35764D03*
X942921D03*
X967921D03*
X962921Y-58764D03*
Y-35764D03*
X957921Y-58764D03*
Y-35764D03*
X952921Y-58764D03*
Y-35764D03*
X947921Y-58764D03*
Y-35764D03*
X942921Y-58764D03*
X972921D03*
Y-35764D03*
X967921Y-58764D03*
X937921D03*
X941883Y646234D03*
X951795D03*
X924406Y638753D03*
X920006D03*
X915606D03*
X972806D03*
X968406D03*
X964006D03*
X917100Y649300D03*
X942006Y638753D03*
X937606D03*
X933206D03*
X928806D03*
X959606D03*
X955206D03*
X950806D03*
X946406D03*
X941883Y652234D03*
X951795D03*
X959621Y660756D03*
X964021D03*
X968421D03*
X972821D03*
X920021D03*
X915621D03*
X924421D03*
X946421D03*
X942021D03*
X937621D03*
X933221D03*
X928821D03*
X955221D03*
X950821D03*
X1002921Y-58764D03*
Y-35764D03*
X997921Y-58764D03*
Y-35764D03*
X992921Y-58764D03*
Y-35764D03*
X987921Y-58764D03*
Y-35764D03*
X982921Y-58764D03*
Y-35764D03*
X977921Y-58764D03*
Y-35764D03*
X1032921Y-58764D03*
Y-35764D03*
X1027921Y-58764D03*
Y-35764D03*
X1022921Y-58764D03*
Y-35764D03*
X1017921Y-58764D03*
Y-35764D03*
X1012921Y-58764D03*
Y-35764D03*
X1007921Y-58764D03*
Y-35764D03*
X1030489Y270889D03*
Y273889D03*
X1027902Y278904D03*
X1020702D03*
X1017702D03*
X1024902D03*
X1032102D03*
X1024994Y292918D03*
X1017630Y292910D03*
X1020702Y292904D03*
X1027902D03*
X1031953Y292910D03*
X1024140Y309910D03*
X1021065Y309759D03*
X1017083Y309910D03*
X1032042D03*
X1028136Y309815D03*
X1017567Y295859D03*
X1024767D03*
X1020567D03*
X1031967D03*
X1027767D03*
X1015293Y311955D03*
X1003606Y638753D03*
X1012406D03*
X977206D03*
X990406D03*
X986006D03*
X994806D03*
X1016806D03*
X1021206D03*
X981606D03*
X999206D03*
X1025606D03*
X1008006D03*
X1030006D03*
X1034406D03*
X999221Y660756D03*
X1034421D03*
X1030021D03*
X1008021D03*
X1012421D03*
X1003621D03*
X1016821D03*
X977221D03*
X981621D03*
X1021221D03*
X1025621D03*
X994821D03*
X986021D03*
X990421D03*
X1067921Y-58764D03*
Y-35764D03*
X1062921Y-58764D03*
Y-35764D03*
X1057921Y-58764D03*
Y-35764D03*
X1052921Y-58764D03*
Y-35764D03*
X1047921Y-58764D03*
Y-35764D03*
X1042921Y-58764D03*
Y-35764D03*
X1037921Y-58764D03*
Y-35764D03*
X1092921Y-58764D03*
Y-35764D03*
X1087921Y-58764D03*
Y-35764D03*
X1082921Y-58764D03*
Y-35764D03*
X1077921Y-58764D03*
Y-35764D03*
X1072921Y-58764D03*
Y-35764D03*
X1075865Y264766D03*
X1070300Y264900D03*
X1073200Y264991D03*
X1057202Y264899D03*
X1060402Y264799D03*
X1066300Y264700D03*
X1063402Y264799D03*
X1054202Y264899D03*
X1042302Y278904D03*
X1039302D03*
X1056602Y278910D03*
X1035814Y278775D03*
X1049867Y278999D03*
X1053459Y278910D03*
X1060958D03*
X1075302D03*
X1078302D03*
X1082330D03*
X1070926D03*
X1063652D03*
X1067783D03*
X1082432Y264620D03*
X1085518Y278910D03*
X1089702Y278904D03*
X1086061Y262300D03*
X1086000Y264900D03*
X1077282Y338533D03*
X1080282D03*
X1056792Y338673D03*
X1063992D03*
X1060992D03*
X1071192D03*
X1068192D03*
X1046276Y292910D03*
X1049502Y292904D03*
X1053684Y292910D03*
X1056702Y292904D03*
X1039182Y292919D03*
X1042302Y292904D03*
X1035102D03*
X1049547Y309904D03*
X1046612Y309910D03*
X1056747Y309904D03*
X1053594Y309910D03*
X1042347Y309904D03*
X1039383Y309910D03*
X1035147Y309904D03*
X1039167Y295859D03*
X1042167D03*
X1034967D03*
X1046367D03*
X1056567D03*
X1049367D03*
X1053567D03*
X1038720Y324174D03*
X1044220D03*
X1035820D03*
X1050220D03*
X1047220D03*
X1053220D03*
X1056220D03*
X1041470D03*
X1059220D03*
X1060767Y295859D03*
X1095756Y292841D03*
X1082367Y295859D03*
X1085367D03*
X1075167D03*
X1078167D03*
X1089567D03*
X1092567D03*
X1095567Y295841D03*
X1070967Y295859D03*
X1063767D03*
X1067967D03*
X1086126Y338758D03*
X1083301Y338841D03*
X1062220Y324174D03*
X1095402Y323904D03*
X1083220Y324174D03*
X1076020D03*
X1079020D03*
X1071820D03*
X1065220D03*
X1068820D03*
X1096006Y638753D03*
X1078406D03*
X1082806D03*
X1074006D03*
X1069606D03*
X1091606D03*
X1052006D03*
X1038806D03*
X1087206D03*
X1060806D03*
X1056406D03*
X1065206D03*
X1043206D03*
X1047606D03*
X1078421Y660756D03*
X1060821D03*
X1087221D03*
X1038821D03*
X1091621D03*
X1052021D03*
X1074021D03*
X1065221D03*
X1096021D03*
X1056421D03*
X1043221D03*
X1047621D03*
X1082821D03*
X1069621D03*
X1157921Y-58764D03*
Y-35764D03*
X1152921Y-58764D03*
Y-35764D03*
X1147921Y-58764D03*
Y-35764D03*
X1142921Y-58764D03*
Y-35764D03*
X1137921Y-58764D03*
Y-35764D03*
X1132921Y-58764D03*
Y-35764D03*
X1127921Y-58764D03*
Y-35764D03*
X1122921Y-58764D03*
Y-35764D03*
X1117921Y-58764D03*
Y-35764D03*
X1112921Y-58764D03*
Y-35764D03*
X1107921Y-58764D03*
Y-35764D03*
X1102921Y-58764D03*
Y-35764D03*
X1097921Y-58764D03*
Y-35764D03*
X1104256Y291841D03*
X1101615Y292447D03*
X1098756Y292841D03*
X1101567Y295859D03*
X1104221Y295696D03*
X1098567Y295841D03*
X1112490Y312723D03*
X1112515Y315369D03*
X1101200Y324013D03*
X1098402Y324017D03*
X1135606Y638753D03*
X1126806D03*
X1144406D03*
X1140006D03*
X1118006D03*
X1122406D03*
X1153206D03*
X1157606D03*
X1104806D03*
X1100406D03*
X1131206D03*
X1148806D03*
X1109206D03*
X1113606D03*
X1157621Y660756D03*
X1148821D03*
X1122421D03*
X1126821D03*
X1100421D03*
X1118021D03*
X1140021D03*
X1113621D03*
X1109221D03*
X1153221D03*
X1144421D03*
X1104821D03*
X1131221D03*
X1135621D03*
X1217921Y-58764D03*
Y-35764D03*
X1212921Y-58764D03*
Y-35764D03*
X1207921Y-58764D03*
Y-35764D03*
X1202921Y-58764D03*
Y-35764D03*
X1197921Y-58764D03*
Y-35764D03*
X1192921Y-58764D03*
Y-35764D03*
X1187921Y-58764D03*
Y-35764D03*
X1182921Y-58764D03*
Y-35764D03*
X1177921Y-58764D03*
Y-35764D03*
X1172921Y-58764D03*
Y-35764D03*
X1167921Y-58764D03*
Y-35764D03*
X1162921Y-58764D03*
Y-35764D03*
X1196198Y646206D03*
X1206110D03*
X1188406Y638753D03*
X1214806D03*
X1197206D03*
X1201606D03*
X1192806D03*
X1170806D03*
X1162006D03*
X1166406D03*
X1206006D03*
X1219206D03*
X1179606D03*
X1175206D03*
X1210406D03*
X1184006D03*
X1196198Y652206D03*
X1206110D03*
X1184021Y660756D03*
X1219221D03*
X1192821D03*
X1188421D03*
X1201621D03*
X1179621D03*
X1214821D03*
X1206021D03*
X1166421D03*
X1210421D03*
X1170821D03*
X1162021D03*
X1175221D03*
X1197221D03*
X1232921Y-58764D03*
Y-35764D03*
X1227921Y-58764D03*
Y-35764D03*
X1222921Y-58764D03*
Y-35764D03*
X1252921Y-58764D03*
Y-35764D03*
X1247921Y-58764D03*
Y-35764D03*
X1242921Y-58764D03*
Y-35764D03*
X1237921Y-58764D03*
Y-35764D03*
X1257921D03*
X1272921Y-58764D03*
Y-35764D03*
X1267921Y-58764D03*
Y-35764D03*
X1262921Y-58764D03*
Y-35764D03*
X1257921Y-58764D03*
X1277921D03*
Y-35764D03*
X1265293Y646264D03*
X1255381D03*
X1263206Y638753D03*
X1223606D03*
X1228006D03*
X1258806D03*
X1241206D03*
X1236806D03*
X1250006D03*
X1245606D03*
X1276406D03*
X1254406D03*
X1280806D03*
X1272006D03*
X1267606D03*
X1232406D03*
X1265293Y652264D03*
X1255381D03*
X1228021Y660756D03*
X1232421D03*
X1280821D03*
X1245621D03*
X1236821D03*
X1223621D03*
X1276421D03*
X1241221D03*
X1272021D03*
X1258821D03*
X1250021D03*
X1254421D03*
X1263221D03*
X1267621D03*
X1342921Y-35764D03*
Y-58764D03*
X1317921D03*
X1312921Y-35764D03*
Y-58764D03*
X1307921Y-35764D03*
Y-58764D03*
X1302921Y-35764D03*
Y-58764D03*
X1297921D03*
Y-35764D03*
X1292921Y-58764D03*
Y-35764D03*
X1287921Y-58764D03*
Y-35764D03*
X1282921Y-58764D03*
Y-35764D03*
X1322921D03*
Y-58764D03*
X1317921Y-35764D03*
X1337921D03*
Y-58764D03*
X1332921Y-35764D03*
Y-58764D03*
X1327921Y-35764D03*
Y-58764D03*
X1324806Y638753D03*
X1298406D03*
X1285206D03*
X1294006D03*
X1302806D03*
X1333606D03*
X1338006D03*
X1320406D03*
X1311606D03*
X1329206D03*
X1307206D03*
X1342406D03*
X1289606D03*
X1316006D03*
X1329221Y660756D03*
X1311621D03*
X1316021D03*
X1333621D03*
X1342421D03*
X1285221D03*
X1324821D03*
X1338021D03*
X1298421D03*
X1289621D03*
X1294021D03*
X1320421D03*
X1302821D03*
X1307221D03*
X1402921Y-58764D03*
X1397921D03*
X1402921Y-35764D03*
X1392921Y-58764D03*
X1397921Y-35764D03*
X1387921Y-58764D03*
X1392921Y-35764D03*
X1382921Y-58764D03*
X1387921Y-35764D03*
X1377921Y-58764D03*
X1382921Y-35764D03*
X1372921Y-58764D03*
X1377921Y-35764D03*
X1367921Y-58764D03*
X1362921Y-35764D03*
Y-58764D03*
X1357921Y-35764D03*
Y-58764D03*
X1352921Y-35764D03*
Y-58764D03*
X1347921Y-35764D03*
Y-58764D03*
X1395913Y-7874D03*
X1402211Y1139D03*
Y-16889D03*
X1351206Y638753D03*
X1360006D03*
X1404506Y638853D03*
X1355606Y638753D03*
X1386906Y638853D03*
X1364406Y638753D03*
X1391306Y638853D03*
X1346806Y638753D03*
X1400106Y638853D03*
X1382006Y638753D03*
X1377606D03*
X1373206D03*
X1395706Y638853D03*
X1368806Y638753D03*
X1402211Y601615D03*
Y619643D03*
X1395913Y610630D03*
X1368821Y660756D03*
X1346821D03*
X1355621D03*
X1360021D03*
X1364421D03*
X1351221D03*
X1404521Y660856D03*
X1400121D03*
X1395721D03*
X1386921D03*
X1377621Y660756D03*
X1382021D03*
X1373221D03*
X1391321Y660856D03*
X1407921Y-58764D03*
X1412921Y-35764D03*
X1407921D03*
X1442921Y-58764D03*
X1447921Y-35764D03*
X1437921Y-58764D03*
X1442921Y-35764D03*
X1432921Y-58764D03*
X1437921Y-35764D03*
X1427921Y-58764D03*
X1432921Y-35764D03*
X1422921Y-58764D03*
X1427921Y-35764D03*
X1417921Y-58764D03*
X1422921Y-35764D03*
X1412921Y-58764D03*
X1417921Y-35764D03*
X1462921Y-58764D03*
X1457921D03*
X1462921Y-35764D03*
X1452921Y-58764D03*
X1457921Y-35764D03*
X1447921Y-58764D03*
X1452921Y-35764D03*
X1410061Y2178D03*
X1410060Y-17927D03*
X1419313Y5626D03*
Y-21374D03*
X1428872Y1668D03*
X1428864Y-17425D03*
X1432813Y-7874D03*
X1431664Y190213D03*
X1456080Y547540D03*
X1463369Y561763D03*
X1446600Y563900D03*
X1449300D03*
X1454600D03*
X1451900D03*
X1457300D03*
X1452392Y544998D03*
X1453166Y547481D03*
X1422106Y638853D03*
X1466106D03*
X1448506D03*
X1457306D03*
X1417706D03*
X1413306D03*
X1461706D03*
X1452906D03*
X1408906D03*
X1444106D03*
X1435306D03*
X1426506D03*
X1430906D03*
X1439706D03*
X1432813Y610630D03*
X1428864Y601079D03*
X1428872Y620172D03*
X1419313Y597130D03*
Y624130D03*
X1410060Y600577D03*
X1410061Y620682D03*
X1457321Y660856D03*
X1417721D03*
X1413321D03*
X1408921D03*
X1422121D03*
X1426521D03*
X1435321D03*
X1444121D03*
X1439721D03*
X1430921D03*
X1448521D03*
X1452921D03*
X1466121D03*
X1461721D03*
X1502921Y-58764D03*
X1507921Y-35764D03*
X1497921Y-58764D03*
X1502921Y-35764D03*
X1492921Y-58764D03*
X1497921Y-35764D03*
X1487921Y-58764D03*
X1492921Y-35764D03*
X1482921Y-58764D03*
X1487921Y-35764D03*
X1477921Y-58764D03*
X1482921Y-35764D03*
X1472921Y-58764D03*
X1477921Y-35764D03*
X1467921Y-58764D03*
X1472921Y-35764D03*
X1467921D03*
X1527921Y-58764D03*
X1522921D03*
X1527921Y-35764D03*
X1517921Y-58764D03*
X1522921Y-35764D03*
X1512921Y-58764D03*
X1517921Y-35764D03*
X1507921Y-58764D03*
X1512921Y-35764D03*
X1514372Y248616D03*
Y243361D03*
X1514370Y246016D03*
X1475098Y493532D03*
X1478279Y496713D03*
X1473018Y562003D03*
X1470314Y561923D03*
X1467714Y561896D03*
X1526586Y559860D03*
X1527285Y562386D03*
X1524538Y562286D03*
X1495187Y561842D03*
X1497918Y561872D03*
X1492187Y561842D03*
X1489316Y561742D03*
X1500530Y561872D03*
X1492130Y545910D03*
X1495130D03*
X1497866Y545797D03*
X1519608Y646236D03*
X1509696D03*
X1496906Y638853D03*
X1492506D03*
X1501706Y638753D03*
X1506106D03*
X1514906D03*
X1483706Y638853D03*
X1523706Y638753D03*
X1510506D03*
X1488106Y638853D03*
X1474906D03*
X1519306Y638753D03*
X1479306Y638853D03*
X1528106Y638753D03*
X1470506Y638853D03*
X1519608Y652236D03*
X1509696D03*
X1496921Y660856D03*
X1483721D03*
X1488121D03*
X1492521D03*
X1479321D03*
X1510521Y660756D03*
X1528121D03*
X1523721D03*
X1501721D03*
X1506121D03*
X1514921D03*
X1519321D03*
X1474921Y660856D03*
X1470521D03*
X1587921Y-58764D03*
X1582921D03*
X1587921Y-35764D03*
X1532921D03*
X1542921D03*
X1532921Y-58764D03*
X1537921Y-35764D03*
X1577921Y-58764D03*
X1582921Y-35764D03*
X1572921Y-58764D03*
X1577921Y-35764D03*
X1567921Y-58764D03*
X1572921Y-35764D03*
X1562921Y-58764D03*
X1567921Y-35764D03*
X1557921Y-58764D03*
X1562921Y-35764D03*
X1552921Y-58764D03*
X1557921Y-35764D03*
X1547921Y-58764D03*
X1552921Y-35764D03*
X1542921Y-58764D03*
X1547921Y-35764D03*
X1537921Y-58764D03*
X1567425Y144373D03*
X1583078Y260122D03*
X1583047Y257171D03*
X1586399Y257099D03*
X1589030Y259807D03*
X1588999Y257104D03*
X1586430Y259824D03*
X1570020Y295340D03*
X1579902Y371468D03*
X1576721Y368287D03*
Y496713D03*
X1579902Y493532D03*
X1531986Y559860D03*
X1529286D03*
X1529985Y562386D03*
X1532685D03*
X1546795Y563316D03*
X1546685Y568656D03*
X1546825Y565986D03*
X1549395Y563541D03*
X1549285Y568881D03*
X1549425Y566211D03*
X1535385Y562386D03*
X1534897Y559808D03*
X1541267Y563185D03*
X1543967D03*
X1541080Y565859D03*
X1538331Y563913D03*
X1538385Y560978D03*
X1544080Y568859D03*
Y565859D03*
X1580121Y647556D03*
X1555106Y638753D03*
X1555121Y647556D03*
X1590121D03*
X1590106Y638753D03*
X1590121Y643156D03*
X1585121Y647556D03*
X1585106Y638753D03*
X1585121Y643156D03*
X1565121Y647556D03*
X1570121Y643156D03*
X1570106Y638753D03*
X1565106D03*
X1565121Y643156D03*
X1570121Y647556D03*
X1560121D03*
X1560106Y638753D03*
X1560121Y643156D03*
X1575121D03*
X1575106Y638753D03*
X1575121Y647556D03*
X1555121Y643156D03*
X1580106Y638753D03*
X1580121Y643156D03*
X1550121Y647556D03*
X1541306Y638753D03*
X1545706D03*
X1550106D03*
X1550121Y643156D03*
X1536906Y638753D03*
X1532506D03*
X1565121Y651956D03*
X1570121Y660756D03*
Y656356D03*
X1565121Y660756D03*
X1555121Y651956D03*
X1590121Y660756D03*
Y656356D03*
Y651956D03*
X1585121Y660756D03*
Y656356D03*
Y651956D03*
X1580121Y660756D03*
Y656356D03*
Y651956D03*
X1560121Y660756D03*
Y656356D03*
Y651956D03*
X1555121Y660756D03*
Y656356D03*
X1570121Y651956D03*
X1575121D03*
Y656356D03*
Y660756D03*
X1565121Y656356D03*
X1550121Y651956D03*
Y656356D03*
X1541321Y660756D03*
X1550121D03*
X1545721D03*
X1532521D03*
X1536921D03*
X1642921Y-35764D03*
Y-58764D03*
X1637921Y-35764D03*
Y-58764D03*
X1632921Y-35764D03*
Y-58764D03*
X1627921D03*
X1622921D03*
X1627921Y-35764D03*
X1617921Y-58764D03*
X1622921Y-35764D03*
X1612921Y-58764D03*
X1617921Y-35764D03*
X1607921Y-58764D03*
X1612921Y-35764D03*
X1602921Y-58764D03*
X1607921Y-35764D03*
X1597921Y-58764D03*
X1602921Y-35764D03*
X1592921Y-58764D03*
X1597921Y-35764D03*
X1592921D03*
X1647921D03*
Y-58764D03*
X1608099Y197125D03*
X1591598Y257028D03*
X1591628Y259924D03*
X1608280Y249234D03*
X1625106Y638753D03*
X1625121Y647556D03*
X1630121Y643156D03*
X1630106Y638753D03*
X1630121Y647556D03*
X1635121Y643156D03*
X1635106Y638753D03*
X1635121Y647556D03*
X1640121Y643156D03*
Y647556D03*
X1640106Y638753D03*
X1650121Y647556D03*
X1650106Y638753D03*
X1650121Y643156D03*
X1645121Y647556D03*
X1645106Y638753D03*
X1645121Y643156D03*
X1625121D03*
X1620121Y647556D03*
X1620106Y638753D03*
X1620121Y643156D03*
X1615121Y647556D03*
X1615106Y638753D03*
X1615121Y643156D03*
X1610121Y647556D03*
X1610106Y638753D03*
X1610121Y643156D03*
X1605121Y647556D03*
X1605106Y638753D03*
X1605121Y643156D03*
X1600121Y647556D03*
X1600106Y638753D03*
X1600121Y643156D03*
X1595121Y647556D03*
X1595106Y638753D03*
X1595121Y643156D03*
X1625121Y651956D03*
Y660756D03*
X1630121Y651956D03*
Y656356D03*
Y660756D03*
X1635121Y651956D03*
Y656356D03*
Y660756D03*
X1625121Y656356D03*
X1640121D03*
Y651956D03*
X1650121Y660756D03*
Y656356D03*
Y651956D03*
X1645121Y660756D03*
Y656356D03*
Y651956D03*
X1640121Y660756D03*
X1620121D03*
Y656356D03*
Y651956D03*
X1615121Y660756D03*
Y656356D03*
Y651956D03*
X1610121Y660756D03*
Y656356D03*
Y651956D03*
X1605121Y660756D03*
Y656356D03*
Y651956D03*
X1600121Y660756D03*
Y656356D03*
Y651956D03*
X1595121Y660756D03*
Y656356D03*
Y651956D03*
X1692921Y-40764D03*
X1702921Y-54764D03*
X1687921D03*
X1682921D03*
X1677921D03*
X1672921D03*
X1692921D03*
X1697921D03*
X1707921D03*
X1712921D03*
X1697921Y-40764D03*
X1692921Y-50764D03*
X1687921D03*
X1682921D03*
X1677921D03*
X1672921D03*
X1712921D03*
X1707921D03*
X1702921D03*
X1697921Y-45764D03*
X1707921D03*
X1702921D03*
X1712921D03*
X1697921Y-50764D03*
X1667921Y-35764D03*
X1712921D03*
Y-58764D03*
X1707921Y-35764D03*
Y-58764D03*
X1702921Y-35764D03*
Y-58764D03*
X1697921Y-35764D03*
Y-58764D03*
X1687921Y-40764D03*
X1672921Y-45764D03*
X1677921D03*
X1682921D03*
Y-40764D03*
X1687921Y-45764D03*
X1692921D03*
X1667921Y-58764D03*
X1662921Y-35764D03*
Y-58764D03*
X1657921Y-35764D03*
Y-58764D03*
X1652921Y-35764D03*
Y-58764D03*
X1712921Y-40764D03*
X1707921D03*
X1702921D03*
X1677921D03*
X1672921D03*
X1677921Y-35764D03*
Y-58764D03*
X1672921Y-35764D03*
Y-58764D03*
X1682921Y-35764D03*
Y-58764D03*
X1692921Y-35764D03*
Y-58764D03*
X1687921Y-35764D03*
Y-58764D03*
X1702005Y499163D03*
X1704596Y498876D03*
X1704544Y501627D03*
X1701874Y501795D03*
X1690121Y647556D03*
X1710121D03*
X1710106Y638753D03*
X1710121Y643156D03*
X1705121Y647556D03*
X1705106Y638753D03*
X1695121Y643156D03*
X1695106Y638753D03*
X1695121Y647556D03*
X1700121Y643156D03*
X1700106Y638753D03*
X1685121Y647556D03*
X1685106Y638753D03*
X1685121Y643156D03*
X1680121Y647556D03*
X1680106Y638753D03*
X1680121Y643156D03*
X1675121Y647556D03*
X1675106Y638753D03*
X1675121Y643156D03*
X1670121Y647556D03*
X1670106Y638753D03*
X1670121Y643156D03*
X1665121Y647556D03*
X1665106Y638753D03*
X1665121Y643156D03*
X1660121Y647556D03*
X1660106Y638753D03*
X1660121Y643156D03*
X1655121Y647556D03*
X1655106Y638753D03*
X1655121Y643156D03*
X1690121D03*
X1690106Y638753D03*
X1700121Y647556D03*
X1705121Y643156D03*
X1690121Y656356D03*
Y651956D03*
X1710121Y660756D03*
Y656356D03*
Y651956D03*
X1705121Y660756D03*
Y656356D03*
Y651956D03*
X1690121Y660756D03*
X1695121Y651956D03*
Y656356D03*
Y660756D03*
X1685121Y651956D03*
X1680121Y660756D03*
Y656356D03*
Y651956D03*
X1675121Y660756D03*
Y656356D03*
Y651956D03*
X1670121Y660756D03*
Y656356D03*
Y651956D03*
X1665121Y660756D03*
Y656356D03*
Y651956D03*
X1660121Y660756D03*
Y656356D03*
Y651956D03*
X1655121Y660756D03*
Y656356D03*
Y651956D03*
X1685121Y660756D03*
Y656356D03*
X1700121Y651956D03*
Y656356D03*
Y660756D03*
X1737921Y-50764D03*
X1722921Y-45764D03*
X1727921D03*
X1732921D03*
X1747921D03*
X1752921D03*
X1727921Y-54764D03*
X1757921D03*
X1717921D03*
X1722921D03*
X1767921Y-40764D03*
Y-50764D03*
X1762921D03*
X1757921D03*
X1762921Y-54764D03*
X1752921D03*
X1747921D03*
X1742921D03*
X1737921D03*
X1732921D03*
X1772921D03*
X1767921D03*
X1762921Y-40764D03*
X1772921D03*
X1722921Y-50764D03*
X1717921D03*
X1732921D03*
X1757921Y-40764D03*
X1717921Y-45764D03*
Y-58764D03*
X1742921Y-50764D03*
X1747921D03*
X1752921D03*
X1742921Y-58764D03*
X1737921Y-35764D03*
Y-58764D03*
X1732921Y-35764D03*
Y-58764D03*
X1727921Y-35764D03*
Y-58764D03*
X1722921Y-35764D03*
Y-58764D03*
X1717921Y-35764D03*
X1757921Y-45764D03*
X1762921D03*
X1742921D03*
X1752921Y-40764D03*
X1747921D03*
X1742921D03*
X1737921D03*
X1732921D03*
X1727921D03*
X1722921D03*
X1717921D03*
X1727921Y-50764D03*
X1767921Y-45764D03*
X1772921D03*
X1737921D03*
X1772921Y-35764D03*
Y-58764D03*
X1767921Y-35764D03*
Y-58764D03*
X1762921Y-35764D03*
Y-58764D03*
X1757921Y-35764D03*
Y-58764D03*
X1752921Y-35764D03*
Y-58764D03*
X1747921Y-35764D03*
Y-58764D03*
X1742921Y-35764D03*
X1772921Y-50764D03*
X1727600Y211300D03*
X1724800D03*
X1758000Y250000D03*
X1758324Y232657D03*
X1741000Y250000D03*
X1738000D03*
X1735000D03*
X1747227Y237314D03*
X1744308Y237295D03*
X1741668Y237314D03*
X1739044Y237284D03*
X1728139Y496807D03*
X1725566Y497186D03*
X1723591Y499135D03*
X1725600Y501000D03*
X1775121Y643156D03*
Y647556D03*
X1775106Y638753D03*
X1730121Y647556D03*
X1730106Y638753D03*
X1730121Y643156D03*
X1725121Y647556D03*
X1725106Y638753D03*
X1725121Y643156D03*
X1720121Y647556D03*
X1720106Y638753D03*
X1720121Y643156D03*
X1715121Y647556D03*
X1715106Y638753D03*
X1715121Y643156D03*
X1770121Y647556D03*
X1770106Y638753D03*
X1770121Y643156D03*
X1765121Y647556D03*
X1765106Y638753D03*
X1765121Y643156D03*
X1760121Y647556D03*
X1760106Y638753D03*
X1760121Y643156D03*
X1755121Y647556D03*
X1755106Y638753D03*
X1755121Y643156D03*
X1750121Y647556D03*
X1750106Y638753D03*
X1750121Y643156D03*
X1745121Y647556D03*
X1745106Y638753D03*
X1745121Y643156D03*
X1740121Y647556D03*
X1740106Y638753D03*
X1740121Y643156D03*
X1735121Y647556D03*
X1735106Y638753D03*
X1735121Y643156D03*
X1770121Y660756D03*
X1775121D03*
Y656356D03*
Y651956D03*
X1725121Y660756D03*
Y656356D03*
Y651956D03*
X1720121Y660756D03*
Y656356D03*
Y651956D03*
X1715121Y660756D03*
Y656356D03*
Y651956D03*
X1770121D03*
X1765121Y660756D03*
Y656356D03*
Y651956D03*
X1760121Y660756D03*
Y656356D03*
Y651956D03*
X1755121Y660756D03*
Y656356D03*
Y651956D03*
X1750121Y660756D03*
Y656356D03*
Y651956D03*
X1745121Y660756D03*
Y656356D03*
Y651956D03*
X1740121Y660756D03*
Y656356D03*
Y651956D03*
X1735121Y660756D03*
Y656356D03*
Y651956D03*
X1730121Y660756D03*
Y656356D03*
X1770121D03*
X1730121Y651956D03*
X1817921Y-40764D03*
X1832921Y-45764D03*
Y-54764D03*
X1827921D03*
X1822921D03*
X1817921D03*
X1812921D03*
X1807921D03*
X1802921D03*
X1797921D03*
X1792921D03*
X1787921D03*
X1782921D03*
X1777921D03*
X1832921Y-50764D03*
X1827921D03*
X1822921D03*
X1817921D03*
X1812921D03*
X1807921D03*
X1802921D03*
X1797921D03*
X1792921D03*
X1787921D03*
X1782921Y-40764D03*
X1792921D03*
X1802921D03*
X1807921D03*
X1822921D03*
X1827921D03*
X1832921D03*
X1812921D03*
X1797921D03*
X1777921Y-45764D03*
X1782921D03*
X1787921D03*
X1792921D03*
X1797921D03*
X1802921D03*
X1807921D03*
X1812921D03*
X1817921D03*
X1822921D03*
X1787921Y-40764D03*
X1832921Y-35764D03*
Y-58764D03*
X1827921Y-35764D03*
Y-58764D03*
X1822921Y-35764D03*
Y-58764D03*
X1817921Y-35764D03*
Y-58764D03*
X1812921Y-35764D03*
Y-58764D03*
X1807921Y-35764D03*
Y-58764D03*
X1802921Y-35764D03*
Y-58764D03*
X1797921Y-35764D03*
Y-58764D03*
X1792921Y-35764D03*
Y-58764D03*
X1787921Y-35764D03*
Y-58764D03*
X1782921Y-35764D03*
Y-58764D03*
X1777921Y-35764D03*
Y-58764D03*
X1782921Y-50764D03*
X1777921D03*
Y-40764D03*
X1827921Y-45764D03*
X1835121Y21532D03*
X1832071D03*
X1832771Y26818D03*
X1835921D03*
X1811967Y92168D03*
X1809267Y89468D03*
X1811967D03*
X1825930Y52900D03*
X1824410Y58030D03*
X1824350Y55180D03*
X1821270Y69470D03*
X1824180Y69460D03*
X1794992Y61342D03*
X1797664Y61334D03*
X1797645Y64153D03*
X1792382Y61363D03*
X1792363Y64182D03*
X1794973Y64161D03*
X1807891Y62180D03*
X1810563Y62172D03*
X1810693Y59493D03*
X1808021Y59501D03*
X1805411Y59522D03*
X1813393Y59493D03*
X1813363Y62172D03*
X1810578Y56866D03*
X1805282Y56880D03*
X1807916Y56895D03*
X1813278Y56866D03*
X1805281Y62201D03*
X1835714Y75029D03*
X1826900Y56500D03*
X1823830Y60700D03*
X1811967Y86868D03*
X1809267D03*
X1814667D03*
Y89468D03*
Y92168D03*
Y94868D03*
X1811967D03*
X1809267D03*
Y92168D03*
X1834059Y70501D03*
X1831460Y70600D03*
X1824060Y72460D03*
X1821070Y72480D03*
X1831460Y73300D03*
X1823155Y77329D03*
X1823188Y79943D03*
X1820488D03*
X1820455Y77329D03*
X1831148Y144592D03*
X1836200Y153424D03*
X1833000D03*
X1833600Y145900D03*
X1828390Y165600D03*
X1832000Y165800D03*
X1793205Y165531D03*
X1793268Y162774D03*
X1780121Y643156D03*
X1780106Y638753D03*
X1780121Y647556D03*
X1785121Y643156D03*
X1790121D03*
X1835121Y647556D03*
X1835106Y638753D03*
X1835121Y643156D03*
X1830121Y647556D03*
X1830106Y638753D03*
X1830121Y643156D03*
X1825121Y647556D03*
X1825106Y638753D03*
X1825121Y643156D03*
X1820121Y647556D03*
X1820106Y638753D03*
X1820121Y643156D03*
X1815121Y647556D03*
X1815106Y638753D03*
X1815121Y643156D03*
X1810121Y647556D03*
X1810106Y638753D03*
X1810121Y643156D03*
X1805121Y647556D03*
X1805106Y638753D03*
X1805121Y643156D03*
X1800121Y647556D03*
X1800106Y638753D03*
X1800121Y643156D03*
X1795121Y647556D03*
X1795106Y638753D03*
X1795121Y643156D03*
X1790121Y647556D03*
X1790106Y638753D03*
X1785121Y647556D03*
X1785106Y638753D03*
X1800121Y656356D03*
X1780121Y651956D03*
Y656356D03*
Y660756D03*
X1835121D03*
Y656356D03*
Y651956D03*
X1830121Y660756D03*
Y656356D03*
Y651956D03*
X1825121Y660756D03*
Y656356D03*
Y651956D03*
X1820121Y660756D03*
Y656356D03*
Y651956D03*
X1815121Y660756D03*
Y656356D03*
Y651956D03*
X1810121Y660756D03*
Y656356D03*
Y651956D03*
X1805121Y660756D03*
Y656356D03*
Y651956D03*
X1800121Y660756D03*
Y651956D03*
X1795121Y660756D03*
Y656356D03*
Y651956D03*
X1790121Y660756D03*
Y656356D03*
Y651956D03*
X1785121Y660756D03*
Y656356D03*
Y651956D03*
X1857921Y-45764D03*
X1837921D03*
X1897921D03*
X1892921D03*
X1887921D03*
X1882921D03*
X1877921D03*
X1872921D03*
X1867921D03*
X1862921D03*
X1842921Y-54764D03*
X1852921Y-45764D03*
X1847921D03*
X1842921D03*
X1897921Y-54764D03*
X1892921D03*
X1887921D03*
X1882921D03*
X1877921D03*
X1872921D03*
X1867921D03*
X1862921D03*
X1857921D03*
X1852921D03*
X1847921D03*
X1837921D03*
X1897921Y-50764D03*
X1892921D03*
X1887921D03*
X1882921D03*
X1877921D03*
X1872921D03*
X1867921D03*
X1862921D03*
X1857921D03*
X1852921D03*
X1847921D03*
X1842921D03*
X1837921D03*
X1892921Y-40764D03*
X1897921D03*
X1877921D03*
X1882921D03*
X1887921D03*
X1857921D03*
X1862921D03*
X1867921D03*
X1872921D03*
X1837921D03*
X1842921D03*
X1847921D03*
X1852921D03*
Y-35764D03*
Y-58764D03*
X1847921Y-35764D03*
Y-58764D03*
X1842921Y-35764D03*
Y-58764D03*
X1837921Y-35764D03*
Y-58764D03*
X1862921D03*
X1857921Y-35764D03*
Y-58764D03*
X1882921D03*
X1877921Y-35764D03*
Y-58764D03*
X1872921Y-35764D03*
Y-58764D03*
X1867921Y-35764D03*
Y-58764D03*
X1862921Y-35764D03*
X1897921D03*
Y-58764D03*
X1892921Y-35764D03*
Y-58764D03*
X1887921Y-35764D03*
Y-58764D03*
X1882921Y-35764D03*
X1838700Y26638D03*
X1838100Y21500D03*
X1847797Y26331D03*
X1847564Y21636D03*
X1862636Y26780D03*
X1851040Y24130D03*
X1855836Y21118D03*
X1852236D03*
X1859436D03*
X1862936D03*
X1865450Y22000D03*
X1860981Y23894D03*
X1857381D03*
X1853781D03*
X1864020Y24470D03*
X1851936Y26780D03*
X1859036D03*
X1855436D03*
X1844732Y-7874D03*
X1851030Y1139D03*
Y-16889D03*
X1858880Y2178D03*
X1858879Y-17927D03*
X1868132Y5626D03*
Y-21374D03*
X1877691Y1668D03*
X1877683Y-17425D03*
X1881632Y-7874D03*
X1837077Y77429D03*
X1837129Y72526D03*
X1837161Y69926D03*
X1838342Y75014D03*
X1846675Y67362D03*
X1844025D03*
X1849325D03*
X1839985Y77522D03*
X1842783Y77599D03*
X1842515Y70042D03*
X1839865D03*
X1845165D03*
X1842515Y72692D03*
X1839865D03*
X1844048Y75184D03*
X1846667Y75106D03*
X1841250Y75107D03*
X1845165Y72692D03*
X1847654Y164624D03*
X1852654D03*
X1883723Y263029D03*
Y260029D03*
X1880633Y260109D03*
Y263109D03*
X1886200Y454280D03*
X1882669Y454368D03*
X1886330Y448010D03*
X1892118Y454383D03*
X1888968D03*
X1888976Y448054D03*
X1892126D03*
X1895275D03*
X1895121Y647556D03*
X1895106Y638753D03*
X1895121Y643156D03*
X1890121Y647556D03*
X1890106Y638753D03*
X1890121Y643156D03*
X1885121Y647556D03*
X1885106Y638753D03*
X1885121Y643156D03*
X1880121Y647556D03*
X1880106Y638753D03*
X1880121Y643156D03*
X1875121Y647556D03*
X1875106Y638753D03*
X1875121Y643156D03*
X1870121Y647556D03*
X1870106Y638753D03*
X1870121Y643156D03*
X1865121Y647556D03*
X1865106Y638753D03*
X1865121Y643156D03*
X1860121Y647556D03*
X1860106Y638753D03*
X1860121Y643156D03*
X1855121Y647556D03*
X1855106Y638753D03*
X1855121Y643156D03*
X1850121Y647556D03*
X1850106Y638753D03*
X1850121Y643156D03*
X1845121Y647556D03*
X1845106Y638753D03*
X1845121Y643156D03*
X1840121Y647556D03*
X1840106Y638753D03*
X1840121Y643156D03*
X1844732Y610630D03*
X1851030Y619643D03*
Y601615D03*
X1858880Y620682D03*
X1858879Y600577D03*
X1868132Y624130D03*
Y597130D03*
X1877691Y620172D03*
X1877683Y601079D03*
X1881632Y610630D03*
X1895121Y660756D03*
Y656356D03*
Y651956D03*
X1890121Y660756D03*
Y656356D03*
Y651956D03*
X1885121Y660756D03*
Y656356D03*
Y651956D03*
X1880121Y660756D03*
Y656356D03*
Y651956D03*
X1875121Y660756D03*
Y656356D03*
Y651956D03*
X1870121Y660756D03*
Y656356D03*
Y651956D03*
X1865121Y660756D03*
Y656356D03*
Y651956D03*
X1860121Y660756D03*
Y656356D03*
Y651956D03*
X1855121Y660756D03*
Y656356D03*
Y651956D03*
X1850121Y660756D03*
Y656356D03*
Y651956D03*
X1845121Y660756D03*
Y656356D03*
Y651956D03*
X1840121Y660756D03*
Y656356D03*
Y651956D03*
X1927921Y-40764D03*
X1947921Y-45764D03*
X1942921D03*
X1937921D03*
X1932921D03*
X1927921D03*
X1922921D03*
X1917921D03*
X1912921D03*
X1907921D03*
X1902921D03*
X1927921Y-50764D03*
X1932921D03*
Y-40764D03*
X1937921D03*
X1942921D03*
X1947921D03*
X1907921Y-50764D03*
X1902921D03*
X1922921Y-40764D03*
X1917921D03*
X1912921D03*
X1907921D03*
X1902921D03*
X1922921Y-54764D03*
X1917921D03*
X1912921D03*
X1907921D03*
X1902921D03*
X1927921D03*
X1932921D03*
X1937921D03*
X1942921D03*
X1947921D03*
X1952921D03*
X1957921D03*
Y-50764D03*
X1952921D03*
X1947921D03*
X1942921D03*
X1937921D03*
X1922921D03*
X1917921D03*
X1912921D03*
X1957921Y-35764D03*
Y-58764D03*
X1952921Y-35764D03*
Y-58764D03*
X1947921Y-35764D03*
Y-58764D03*
X1942921Y-35764D03*
Y-58764D03*
X1937921Y-35764D03*
Y-58764D03*
X1932921Y-35764D03*
Y-58764D03*
X1927921Y-35764D03*
Y-58764D03*
X1922921Y-35764D03*
Y-58764D03*
X1917921Y-35764D03*
Y-58764D03*
X1912921Y-35764D03*
Y-58764D03*
X1907921Y-35764D03*
Y-58764D03*
X1902921Y-35764D03*
Y-58764D03*
X1938150Y70447D03*
X1937950Y73247D03*
X1940750Y73347D03*
X1929961Y73247D03*
X1935350D03*
X1932730Y73310D03*
X1942390Y76040D03*
X1943550Y73347D03*
X1946350Y73447D03*
X1948951Y73448D03*
X1945020Y76060D03*
X1954271Y80449D03*
X1936706Y75987D03*
X1939470Y76000D03*
X1930150Y70447D03*
X1932950D03*
X1935550D03*
X1940950Y70547D03*
X1943750D03*
X1907385Y93926D03*
X1904678Y93845D03*
X1907428Y91133D03*
X1904742Y96552D03*
X1907448Y96615D03*
X1908400Y101010D03*
X1940847Y227984D03*
X1938127Y228016D03*
X1910153Y226090D03*
X1910219Y223358D03*
X1914037Y243646D03*
X1917298Y466999D03*
X1914173Y467000D03*
X1910999D03*
X1960106Y638753D03*
X1955106D03*
X1950106D03*
X1945121Y647556D03*
Y643156D03*
X1945106Y638753D03*
X1940121Y647556D03*
Y643156D03*
X1940106Y638753D03*
X1935121Y647556D03*
Y643156D03*
X1935106Y638753D03*
X1930106D03*
X1925106D03*
X1920121Y647556D03*
X1910121Y643156D03*
X1910106Y638753D03*
X1905121Y647556D03*
Y643156D03*
X1905106Y638753D03*
X1900121Y647556D03*
X1900106Y638753D03*
X1900121Y643156D03*
X1920106Y638753D03*
X1915121Y647556D03*
X1920121Y643156D03*
X1910121Y647556D03*
X1915106Y638753D03*
X1915121Y643156D03*
X1960121Y656356D03*
Y660756D03*
X1955121Y656356D03*
Y660756D03*
X1950121Y651956D03*
Y656356D03*
Y660756D03*
X1945121Y651956D03*
Y656356D03*
Y660756D03*
X1940121Y651956D03*
Y656356D03*
Y660756D03*
X1935121Y651956D03*
Y656356D03*
Y660756D03*
X1930121Y651956D03*
Y656356D03*
Y660756D03*
X1925121Y651956D03*
Y656356D03*
Y660756D03*
X1920121Y651956D03*
Y656356D03*
X1905121Y651956D03*
Y656356D03*
Y660756D03*
X1900121D03*
Y656356D03*
Y651956D03*
X1915121D03*
Y656356D03*
Y660756D03*
X1920121D03*
X1910121D03*
Y656356D03*
Y651956D03*
X1967921Y-45764D03*
X1962921D03*
Y-40764D03*
X1967921D03*
Y-54764D03*
X1962921D03*
X1967921Y-50764D03*
X1962921D03*
X1967921Y-35764D03*
Y-58764D03*
X1962921Y-35764D03*
Y-58764D03*
X1969500Y229600D03*
X1966300D03*
X1970121Y647556D03*
Y643156D03*
X1970106Y638753D03*
X1965121Y647556D03*
Y643156D03*
X1965106Y638753D03*
X1970121Y651956D03*
Y656356D03*
Y660756D03*
X1965121Y651956D03*
Y656356D03*
Y660756D03*
G54D220*
X1430584Y467544D03*
G54D121*
X317428Y205060D03*
X324188D03*
X330948D03*
X334328Y203110D03*
X317428Y201159D03*
X337708D03*
X341088Y199210D03*
X297149Y197259D03*
X303909D03*
X310668D03*
X317428D03*
X344468D03*
X351228D03*
X357987D03*
X364747D03*
X371507D03*
X378267D03*
X385027D03*
X391787D03*
X428224Y202397D03*
X434983D03*
X441743D03*
X448503D03*
X455263D03*
X462023D03*
X468783D03*
X475542D03*
X482302Y210196D03*
X489062D03*
X495822D03*
X502582D03*
X482302Y206297D03*
X502582D03*
X539761Y204346D03*
X505962D03*
X536381Y202397D03*
X482302D03*
X509342D03*
X516102D03*
X522861D03*
X529621D03*
X543141Y206297D03*
X967036Y205060D03*
Y201159D03*
X946757Y197259D03*
X953517D03*
X960276D03*
X967036D03*
X973796Y205060D03*
X980556D03*
X983936Y203110D03*
X987316Y201159D03*
X990696Y199210D03*
X994076Y197259D03*
X1000836D03*
X1007595D03*
X1014355D03*
X1021115D03*
X1027875D03*
X1034635D03*
X1041395D03*
X1077832Y202397D03*
X1084591D03*
X1091351D03*
X1131910Y210196D03*
X1138670D03*
X1145430D03*
X1152190D03*
X1131910Y206297D03*
X1152190D03*
X1155570Y204346D03*
X1098111Y202397D03*
X1104871D03*
X1111631D03*
X1118391D03*
X1125150D03*
X1131910D03*
X1192749Y206297D03*
X1189369Y204346D03*
X1185989Y202397D03*
X1158950D03*
X1165710D03*
X1172469D03*
X1179229D03*
G54D140*
X652252Y335948D03*
X654221D03*
X656190D03*
X658159D03*
X660128D03*
X662097D03*
X664066D03*
X666035D03*
X668004D03*
X669973D03*
X671942D03*
X673911D03*
X675880D03*
X677849D03*
X679818D03*
X681787D03*
G54D311*
X1880510Y133750D03*
X1886420D03*
X1884450D03*
X1882480D03*
X1876570D03*
X1874600D03*
X1872630D03*
X1878540D03*
X1890360D03*
X1888390D03*
G54D11*
X0Y0D03*
G54D212*
X1446179Y95353D03*
Y90353D03*
Y85353D03*
Y80353D03*
Y75353D03*
Y70353D03*
X1445232Y153080D03*
Y143080D03*
Y148080D03*
X1446179Y105353D03*
Y100353D03*
X1445232Y173080D03*
Y168080D03*
Y158080D03*
Y163080D03*
Y178080D03*
X1483779Y75353D03*
Y80353D03*
Y85353D03*
Y90353D03*
Y95353D03*
Y70353D03*
X1482832Y143080D03*
Y153080D03*
Y148080D03*
X1483779Y105353D03*
Y100353D03*
X1482832Y168080D03*
Y163080D03*
Y158080D03*
Y173080D03*
Y178080D03*
X1529699Y195920D03*
Y200920D03*
Y205920D03*
Y210920D03*
Y215920D03*
Y190920D03*
Y185920D03*
Y220920D03*
X1567299Y190920D03*
Y195920D03*
Y210920D03*
Y205920D03*
Y200920D03*
Y185920D03*
Y215920D03*
Y220920D03*
X1599200Y207000D03*
Y217000D03*
Y212000D03*
X1620800D03*
Y207000D03*
Y202000D03*
X1599200D03*
X1620800Y217000D03*
G54D230*
X1520972Y300937D03*
Y293257D03*
Y308617D03*
Y295817D03*
Y298377D03*
Y303497D03*
Y306057D03*
X1544472Y308617D03*
Y300937D03*
Y293257D03*
Y295817D03*
Y298377D03*
Y303497D03*
Y306057D03*
X1773471Y564015D03*
X1749971Y556335D03*
Y564015D03*
Y571695D03*
X1773471D03*
Y556335D03*
Y569135D03*
Y566575D03*
Y561455D03*
Y558895D03*
X1749971Y569135D03*
Y566575D03*
Y561455D03*
Y558895D03*
X1748800Y581750D03*
X1772300D03*
Y586870D03*
Y584310D03*
X1748800Y586870D03*
Y584310D03*
X1772300Y589430D03*
X1748800D03*
Y597110D03*
X1772300D03*
Y594550D03*
Y591990D03*
X1748800Y594550D03*
Y591990D03*
G54D20*
X-16362Y462160D03*
Y478340D03*
X-11242Y462160D03*
X-13802D03*
X-8682D03*
X-11242Y478340D03*
X-13802D03*
X-8682D03*
X1700080Y68600D03*
X1697520D03*
X1694960D03*
X1692400D03*
X1689840D03*
X1687280D03*
X1684720D03*
X1682160D03*
Y46400D03*
X1684720D03*
X1687280D03*
X1689840D03*
X1692400D03*
X1694960D03*
X1697520D03*
X1700080D03*
X1652160Y437500D03*
Y421320D03*
X1657280Y437500D03*
Y421320D03*
X1654720Y437500D03*
Y421320D03*
X1659840D03*
Y437500D03*
G54D302*
X1842250Y90750D03*
X1965000Y561500D03*
Y583000D03*
Y604500D03*
G54D320*
X1952756Y-14760D03*
Y58068D03*
G54D113*
X270109Y216909D03*
X276869D03*
X283629D03*
X290389D03*
X273489Y214960D03*
X280249D03*
X287009D03*
X270109Y213009D03*
X276869D03*
X283629D03*
X290389D03*
X273489Y211060D03*
X280249D03*
X287009D03*
X276869Y209109D03*
X283629D03*
X290389D03*
X280249Y207159D03*
X287009D03*
X283629Y205210D03*
X290389D03*
X287009Y203260D03*
X290389Y201309D03*
X270109Y232509D03*
X276869D03*
X283629D03*
X290389D03*
X273489Y230559D03*
X280249D03*
X287009D03*
X270109Y228610D03*
X276869D03*
X283629D03*
X290389D03*
X273489Y226660D03*
X280249D03*
X287009D03*
X270109Y224709D03*
X276869D03*
X283629D03*
X290389D03*
X270109Y220809D03*
X276869D03*
X283629D03*
X290389D03*
X273489Y218860D03*
X280249D03*
X287009D03*
X276869Y279310D03*
X283629D03*
X290389D03*
X273489Y277360D03*
X280249D03*
X287009D03*
X276869Y275409D03*
X283629D03*
X290389D03*
X273489Y273460D03*
X280249D03*
X287009D03*
X270109Y271509D03*
X276869D03*
X283629D03*
X290389D03*
X273489Y269560D03*
X280249D03*
X287009D03*
X270109Y267609D03*
X276869D03*
X283629D03*
X290389D03*
X273489Y265660D03*
X280249D03*
X287009D03*
X270109Y263709D03*
X276869D03*
X283629D03*
X290389D03*
X273489Y261760D03*
X280249D03*
X287009D03*
X270109Y259809D03*
X276869D03*
X283629D03*
X290389D03*
X273489Y257860D03*
X280249D03*
X287009D03*
X270109Y255909D03*
X276869D03*
X283629D03*
X290389D03*
X273489Y253960D03*
X280249D03*
X287009D03*
X270109Y252009D03*
X276869D03*
X283629D03*
X290389D03*
X273489Y250060D03*
X280249D03*
X287009D03*
X270109Y248109D03*
X276869D03*
X283629D03*
X290389D03*
X273489Y246160D03*
X280249D03*
X287009D03*
X270109Y244209D03*
X276869D03*
X283629D03*
X290389D03*
X273489Y242260D03*
X280249D03*
X287009D03*
X270109Y240309D03*
X276869D03*
X283629D03*
X290389D03*
X273489Y238360D03*
X280249D03*
X287009D03*
X270109Y236409D03*
X276869D03*
X283629D03*
X290389D03*
X273489Y234460D03*
X280249D03*
X287009D03*
X273489Y222760D03*
X280249D03*
X287009D03*
X270109Y341709D03*
X276869D03*
X283629D03*
X290389D03*
X273489Y339760D03*
X280249D03*
X287009D03*
X270109Y337809D03*
X276869D03*
X283629D03*
X290389D03*
X273489Y335860D03*
X280249D03*
X287009D03*
X270109Y333909D03*
X276869D03*
X283629D03*
X290389D03*
X273489Y331960D03*
X280249D03*
X287009D03*
X270109Y330009D03*
X276869D03*
X283629D03*
X290389D03*
X273489Y328060D03*
X280249D03*
X287009D03*
X276869Y326110D03*
X283629D03*
X290389D03*
X273489Y324160D03*
X280249D03*
X287009D03*
X276869Y322209D03*
X283629D03*
X290389D03*
X273489Y320260D03*
X280249D03*
X287009D03*
X276869Y318309D03*
X283629D03*
X290389D03*
X280249Y316360D03*
X287009D03*
X276869Y314409D03*
X283629D03*
X290389D03*
X280249Y312460D03*
X287009D03*
X276869Y310509D03*
X283629D03*
X290389D03*
X280249Y308560D03*
X287009D03*
X276869Y306609D03*
X283629D03*
X290389D03*
X280249Y304660D03*
X287009D03*
X276869Y302709D03*
X283629D03*
X290389D03*
X280249Y300760D03*
X287009D03*
X276869Y298809D03*
X283629D03*
X290389D03*
X280249Y296860D03*
X287009D03*
X276869Y294909D03*
X283629D03*
X290389D03*
X280249Y292959D03*
X287009D03*
X276869Y291009D03*
X283629D03*
X290389D03*
X280249Y289060D03*
X287009D03*
X276869Y287109D03*
X283629D03*
X290389D03*
X280249Y285160D03*
X287009D03*
X276869Y283209D03*
X283629D03*
X290389D03*
X273489Y281260D03*
X280249D03*
X287009D03*
X290389Y396309D03*
X287009Y394359D03*
X283629Y392410D03*
X290389D03*
X280249Y390460D03*
X287009D03*
X276869Y388509D03*
X283629D03*
X290389D03*
X273489Y386560D03*
X280249D03*
X287009D03*
X276869Y384609D03*
X283629D03*
X290389D03*
X273489Y382660D03*
X280249D03*
X287009D03*
X276869Y380709D03*
X283629D03*
X290389D03*
X273489Y378760D03*
X280249D03*
X287009D03*
X276869Y376809D03*
X283629D03*
X290389D03*
X273489Y374860D03*
X280249D03*
X287009D03*
X273489Y370959D03*
X280249D03*
X287009D03*
X276869Y369010D03*
X283629D03*
X290389D03*
X273489Y367060D03*
X280249D03*
X287009D03*
X276869Y365109D03*
X283629D03*
X290389D03*
X273489Y363160D03*
X280249D03*
X287009D03*
X276869Y361209D03*
X283629D03*
X290389D03*
X273489Y359260D03*
X280249D03*
X287009D03*
X276869Y357309D03*
X283629D03*
X290389D03*
X273489Y355360D03*
X280249D03*
X287009D03*
X270109Y353409D03*
X276869D03*
X283629D03*
X290389D03*
X273489Y351460D03*
X280249D03*
X287009D03*
X270109Y349509D03*
X276869D03*
X283629D03*
X290389D03*
X273489Y347560D03*
X280249D03*
X287009D03*
X270109Y345609D03*
X276869D03*
X283629D03*
X290389D03*
X273489Y343660D03*
X280249D03*
X287009D03*
X276869Y372909D03*
X283629D03*
X290389D03*
X297149Y216909D03*
X303909D03*
X310668D03*
X317428D03*
X324188D03*
X330948D03*
X337708D03*
X344468D03*
X351228D03*
X293769Y214960D03*
X300529D03*
X307289D03*
X314048D03*
X320808D03*
X327568D03*
X334328D03*
X341088D03*
X347848D03*
X354607D03*
X297149Y213009D03*
X303909D03*
X310668D03*
X317428D03*
X324188D03*
X330948D03*
X337708D03*
X344468D03*
X351228D03*
X293769Y211060D03*
X300529D03*
X307289D03*
X314048D03*
X320808D03*
X327568D03*
X334328D03*
X341088D03*
X347848D03*
X354607D03*
X297149Y209109D03*
X303909D03*
X310668D03*
X317428D03*
X324188D03*
X330948D03*
X337708D03*
X344468D03*
X351228D03*
X293769Y207159D03*
X300529D03*
X307289D03*
X314048D03*
X320808D03*
X327568D03*
X334328D03*
X341088D03*
X347848D03*
X354607D03*
X297149Y205210D03*
X303909D03*
X310668D03*
X337708D03*
X344468D03*
X351228D03*
X293769Y203260D03*
X300529D03*
X307289D03*
X314048D03*
X341088D03*
X347848D03*
X354607D03*
X297149Y201309D03*
X303909D03*
X310668D03*
X344468D03*
X351228D03*
X293769Y199360D03*
X300529D03*
X307289D03*
X314048D03*
X347848D03*
X354607D03*
X297149Y232509D03*
X303909D03*
X310668D03*
X317428D03*
X324188D03*
X330948D03*
X337708D03*
X344468D03*
X351228D03*
X293769Y230559D03*
X300529D03*
X307289D03*
X314048D03*
X320808D03*
X327568D03*
X334328D03*
X341088D03*
X347848D03*
X354607D03*
X297149Y228610D03*
X303909D03*
X310668D03*
X317428D03*
X324188D03*
X330948D03*
X337708D03*
X344468D03*
X351228D03*
X293769Y226660D03*
X300529D03*
X307289D03*
X314048D03*
X320808D03*
X327568D03*
X334328D03*
X341088D03*
X347848D03*
X354607D03*
X297149Y224709D03*
X303909D03*
X310668D03*
X317428D03*
X324188D03*
X330948D03*
X337708D03*
X344468D03*
X351228D03*
X297149Y220809D03*
X303909D03*
X310668D03*
X317428D03*
X324188D03*
X330948D03*
X337708D03*
X344468D03*
X351228D03*
X293769Y218860D03*
X300529D03*
X307289D03*
X314048D03*
X320808D03*
X327568D03*
X334328D03*
X341088D03*
X347848D03*
X354607D03*
X297149Y279310D03*
X303909D03*
X310668D03*
X317428D03*
X324188D03*
X330948D03*
X337708D03*
X344468D03*
X351228D03*
X293769Y277360D03*
X300529D03*
X307289D03*
X314048D03*
X320808D03*
X327568D03*
X334328D03*
X341088D03*
X347848D03*
X297149Y275409D03*
X303909D03*
X310668D03*
X317428D03*
X324188D03*
X330948D03*
X337708D03*
X344468D03*
X351228D03*
X293769Y273460D03*
X300529D03*
X307289D03*
X314048D03*
X320808D03*
X327568D03*
X334328D03*
X341088D03*
X347848D03*
X297149Y271509D03*
X303909D03*
X310668D03*
X317428D03*
X324188D03*
X330948D03*
X337708D03*
X344468D03*
X351228D03*
X293769Y269560D03*
X300529D03*
X307289D03*
X314048D03*
X320808D03*
X327568D03*
X334328D03*
X341088D03*
X347848D03*
X297149Y267609D03*
X303909D03*
X310668D03*
X317428D03*
X324188D03*
X330948D03*
X337708D03*
X344468D03*
X351228D03*
X293769Y265660D03*
X300529D03*
X307289D03*
X314048D03*
X320808D03*
X327568D03*
X334328D03*
X341088D03*
X347848D03*
X354607D03*
X297149Y263709D03*
X303909D03*
X310668D03*
X317428D03*
X324188D03*
X330948D03*
X337708D03*
X344468D03*
X351228D03*
X293769Y261760D03*
X300529D03*
X307289D03*
X314048D03*
X327568D03*
X334328D03*
X341088D03*
X347848D03*
X354607D03*
X297149Y259809D03*
X303909D03*
X310668D03*
X324188D03*
X330948D03*
X337708D03*
X344468D03*
X351228D03*
X293769Y257860D03*
X300529D03*
X307289D03*
X327568D03*
X334328D03*
X341088D03*
X347848D03*
X354607D03*
X297149Y255909D03*
X303909D03*
X310668D03*
X324188D03*
X330948D03*
X337708D03*
X344468D03*
X351228D03*
X293769Y253960D03*
X300529D03*
X307289D03*
X327568D03*
X334328D03*
X341088D03*
X347848D03*
X354607D03*
X297149Y252009D03*
X303909D03*
X310668D03*
X324188D03*
X330948D03*
X337708D03*
X344468D03*
X351228D03*
X293769Y250060D03*
X300529D03*
X307289D03*
X320808D03*
X327568D03*
X334328D03*
X341088D03*
X347848D03*
X354607D03*
X297149Y248109D03*
X303909D03*
X310668D03*
X317428D03*
X324188D03*
X330948D03*
X337708D03*
X344468D03*
X351228D03*
X293769Y246160D03*
X300529D03*
X307289D03*
X314048D03*
X320808D03*
X327568D03*
X334328D03*
X341088D03*
X347848D03*
X354607D03*
X297149Y244209D03*
X303909D03*
X310668D03*
X317428D03*
X324188D03*
X330948D03*
X337708D03*
X344468D03*
X351228D03*
X293769Y242260D03*
X300529D03*
X307289D03*
X314048D03*
X320808D03*
X327568D03*
X334328D03*
X341088D03*
X347848D03*
X354607D03*
X297149Y240309D03*
X303909D03*
X310668D03*
X317428D03*
X324188D03*
X330948D03*
X337708D03*
X344468D03*
X351228D03*
X293769Y238360D03*
X300529D03*
X307289D03*
X314048D03*
X320808D03*
X327568D03*
X334328D03*
X341088D03*
X347848D03*
X354607D03*
X297149Y236409D03*
X303909D03*
X310668D03*
X317428D03*
X324188D03*
X330948D03*
X337708D03*
X344468D03*
X351228D03*
X293769Y234460D03*
X300529D03*
X307289D03*
X314048D03*
X320808D03*
X327568D03*
X334328D03*
X341088D03*
X347848D03*
X354607D03*
X293769Y222760D03*
X300529D03*
X307289D03*
X314048D03*
X320808D03*
X327568D03*
X334328D03*
X341088D03*
X347848D03*
X354607D03*
X297149Y341709D03*
X303909D03*
X310668D03*
X324188D03*
X330948D03*
X337708D03*
X344468D03*
X351228D03*
X293769Y339760D03*
X300529D03*
X307289D03*
X327568D03*
X334328D03*
X341088D03*
X347848D03*
X354607D03*
X297149Y337809D03*
X303909D03*
X310668D03*
X324188D03*
X330948D03*
X337708D03*
X344468D03*
X351228D03*
X293769Y335860D03*
X300529D03*
X307289D03*
X320808D03*
X327568D03*
X334328D03*
X341088D03*
X347848D03*
X354607D03*
X297149Y333909D03*
X303909D03*
X310668D03*
X317428D03*
X324188D03*
X330948D03*
X337708D03*
X344468D03*
X351228D03*
X293769Y331960D03*
X300529D03*
X307289D03*
X314048D03*
X320808D03*
X327568D03*
X334328D03*
X341088D03*
X347848D03*
X354607D03*
X297149Y330009D03*
X303909D03*
X310668D03*
X317428D03*
X324188D03*
X330948D03*
X337708D03*
X344468D03*
X351228D03*
X293769Y328060D03*
X300529D03*
X307289D03*
X314048D03*
X320808D03*
X327568D03*
X334328D03*
X341088D03*
X347848D03*
X297149Y326110D03*
X303909D03*
X310668D03*
X317428D03*
X324188D03*
X330948D03*
X337708D03*
X344468D03*
X351228D03*
X293769Y324160D03*
X300529D03*
X307289D03*
X314048D03*
X320808D03*
X327568D03*
X334328D03*
X341088D03*
X347848D03*
X297149Y322209D03*
X303909D03*
X310668D03*
X317428D03*
X324188D03*
X330948D03*
X337708D03*
X344468D03*
X351228D03*
X293769Y320260D03*
X300529D03*
X307289D03*
X314048D03*
X320808D03*
X327568D03*
X334328D03*
X341088D03*
X347848D03*
X297149Y318309D03*
X303909D03*
X310668D03*
X317428D03*
X324188D03*
X330948D03*
X337708D03*
X344468D03*
X351228D03*
X293769Y316360D03*
X300529D03*
X307289D03*
X314048D03*
X320808D03*
X327568D03*
X334328D03*
X341088D03*
X347848D03*
X297149Y314409D03*
X303909D03*
X310668D03*
X317428D03*
X324188D03*
X330948D03*
X337708D03*
X344468D03*
X351228D03*
X293769Y312460D03*
X300529D03*
X307289D03*
X314048D03*
X320808D03*
X327568D03*
X334328D03*
X341088D03*
X347848D03*
X297149Y310509D03*
X303909D03*
X310668D03*
X317428D03*
X324188D03*
X330948D03*
X337708D03*
X344468D03*
X351228D03*
X293769Y308560D03*
X300529D03*
X307289D03*
X314048D03*
X320808D03*
X327568D03*
X334328D03*
X341088D03*
X347848D03*
X297149Y306609D03*
X303909D03*
X310668D03*
X317428D03*
X324188D03*
X330948D03*
X337708D03*
X344468D03*
X351228D03*
X293769Y304660D03*
X300529D03*
X307289D03*
X314048D03*
X320808D03*
X327568D03*
X334328D03*
X341088D03*
X347848D03*
X297149Y302709D03*
X303909D03*
X310668D03*
X317428D03*
X324188D03*
X330948D03*
X337708D03*
X344468D03*
X351228D03*
X293769Y300760D03*
X300529D03*
X307289D03*
X314048D03*
X320808D03*
X327568D03*
X334328D03*
X341088D03*
X347848D03*
X297149Y298809D03*
X303909D03*
X310668D03*
X317428D03*
X324188D03*
X330948D03*
X337708D03*
X344468D03*
X351228D03*
X293769Y296860D03*
X300529D03*
X307289D03*
X314048D03*
X320808D03*
X327568D03*
X334328D03*
X341088D03*
X347848D03*
X297149Y294909D03*
X303909D03*
X310668D03*
X317428D03*
X324188D03*
X330948D03*
X337708D03*
X344468D03*
X351228D03*
X293769Y292959D03*
X300529D03*
X307289D03*
X314048D03*
X320808D03*
X327568D03*
X334328D03*
X341088D03*
X347848D03*
X297149Y291009D03*
X303909D03*
X310668D03*
X317428D03*
X324188D03*
X330948D03*
X337708D03*
X344468D03*
X351228D03*
X293769Y289060D03*
X300529D03*
X307289D03*
X314048D03*
X320808D03*
X327568D03*
X334328D03*
X341088D03*
X347848D03*
X297149Y287109D03*
X303909D03*
X310668D03*
X317428D03*
X324188D03*
X330948D03*
X337708D03*
X344468D03*
X351228D03*
X293769Y285160D03*
X300529D03*
X307289D03*
X314048D03*
X320808D03*
X327568D03*
X334328D03*
X341088D03*
X347848D03*
X297149Y283209D03*
X303909D03*
X310668D03*
X317428D03*
X324188D03*
X330948D03*
X337708D03*
X344468D03*
X351228D03*
X293769Y281260D03*
X300529D03*
X307289D03*
X314048D03*
X320808D03*
X327568D03*
X334328D03*
X341088D03*
X347848D03*
X293769Y398260D03*
X300529D03*
X307289D03*
X314048D03*
X347848D03*
X354607D03*
X297149Y396309D03*
X303909D03*
X310668D03*
X317428D03*
X351228D03*
X293769Y394359D03*
X300529D03*
X307289D03*
X314048D03*
X320808D03*
X347848D03*
X354607D03*
X297149Y392410D03*
X303909D03*
X310668D03*
X317428D03*
X351228D03*
X293769Y390460D03*
X300529D03*
X307289D03*
X314048D03*
X320808D03*
X327568D03*
X334328D03*
X341088D03*
X347848D03*
X354607D03*
X297149Y388509D03*
X303909D03*
X310668D03*
X317428D03*
X324188D03*
X330948D03*
X337708D03*
X344468D03*
X351228D03*
X293769Y386560D03*
X300529D03*
X307289D03*
X314048D03*
X320808D03*
X327568D03*
X334328D03*
X341088D03*
X347848D03*
X354607D03*
X297149Y384609D03*
X303909D03*
X310668D03*
X317428D03*
X324188D03*
X330948D03*
X337708D03*
X344468D03*
X351228D03*
X293769Y382660D03*
X300529D03*
X307289D03*
X314048D03*
X320808D03*
X327568D03*
X334328D03*
X341088D03*
X347848D03*
X354607D03*
X297149Y380709D03*
X303909D03*
X310668D03*
X317428D03*
X324188D03*
X330948D03*
X337708D03*
X344468D03*
X351228D03*
X293769Y378760D03*
X300529D03*
X307289D03*
X314048D03*
X320808D03*
X327568D03*
X334328D03*
X341088D03*
X347848D03*
X354607D03*
X297149Y376809D03*
X303909D03*
X310668D03*
X317428D03*
X324188D03*
X330948D03*
X337708D03*
X344468D03*
X351228D03*
X293769Y374860D03*
X300529D03*
X307289D03*
X314048D03*
X320808D03*
X327568D03*
X334328D03*
X341088D03*
X347848D03*
X354607D03*
X293769Y370959D03*
X300529D03*
X307289D03*
X314048D03*
X320808D03*
X327568D03*
X334328D03*
X341088D03*
X347848D03*
X354607D03*
X297149Y369010D03*
X303909D03*
X310668D03*
X317428D03*
X324188D03*
X330948D03*
X337708D03*
X344468D03*
X351228D03*
X293769Y367060D03*
X300529D03*
X307289D03*
X314048D03*
X320808D03*
X327568D03*
X334328D03*
X341088D03*
X347848D03*
X354607D03*
X297149Y365109D03*
X303909D03*
X310668D03*
X317428D03*
X324188D03*
X330948D03*
X337708D03*
X344468D03*
X351228D03*
X293769Y363160D03*
X300529D03*
X307289D03*
X314048D03*
X320808D03*
X327568D03*
X334328D03*
X341088D03*
X347848D03*
X354607D03*
X297149Y361209D03*
X303909D03*
X310668D03*
X317428D03*
X324188D03*
X330948D03*
X337708D03*
X344468D03*
X351228D03*
X293769Y359260D03*
X300529D03*
X307289D03*
X314048D03*
X320808D03*
X327568D03*
X334328D03*
X341088D03*
X347848D03*
X354607D03*
X297149Y357309D03*
X303909D03*
X310668D03*
X317428D03*
X324188D03*
X330948D03*
X337708D03*
X344468D03*
X351228D03*
X293769Y355360D03*
X300529D03*
X307289D03*
X314048D03*
X320808D03*
X327568D03*
X334328D03*
X341088D03*
X347848D03*
X354607D03*
X297149Y353409D03*
X303909D03*
X310668D03*
X317428D03*
X324188D03*
X330948D03*
X337708D03*
X344468D03*
X351228D03*
X293769Y351460D03*
X300529D03*
X307289D03*
X314048D03*
X320808D03*
X327568D03*
X334328D03*
X341088D03*
X347848D03*
X354607D03*
X297149Y349509D03*
X303909D03*
X310668D03*
X317428D03*
X324188D03*
X330948D03*
X337708D03*
X344468D03*
X351228D03*
X293769Y347560D03*
X300529D03*
X307289D03*
X314048D03*
X327568D03*
X334328D03*
X341088D03*
X347848D03*
X354607D03*
X297149Y345609D03*
X303909D03*
X310668D03*
X324188D03*
X330948D03*
X337708D03*
X344468D03*
X351228D03*
X293769Y343660D03*
X300529D03*
X307289D03*
X327568D03*
X334328D03*
X341088D03*
X347848D03*
X354607D03*
X297149Y372909D03*
X303909D03*
X310668D03*
X317428D03*
X324188D03*
X330948D03*
X337708D03*
X344468D03*
X351228D03*
X357987Y216909D03*
X364747D03*
X371507D03*
X378267D03*
X385027D03*
X391787D03*
X398546D03*
X361367Y214960D03*
X368127D03*
X374887D03*
X381647D03*
X388407D03*
X395166D03*
X401926D03*
X357987Y213009D03*
X364747D03*
X371507D03*
X378267D03*
X385027D03*
X391787D03*
X398546D03*
X361367Y211060D03*
X368127D03*
X374887D03*
X381647D03*
X388407D03*
X395166D03*
X401926D03*
X357987Y209109D03*
X364747D03*
X371507D03*
X378267D03*
X385027D03*
X391787D03*
X398546D03*
X361367Y207159D03*
X368127D03*
X374887D03*
X381647D03*
X388407D03*
X395166D03*
X401926D03*
X357987Y205210D03*
X364747D03*
X371507D03*
X378267D03*
X385027D03*
X391787D03*
X398546D03*
X361367Y203260D03*
X368127D03*
X374887D03*
X381647D03*
X388407D03*
X395166D03*
X401926D03*
X357987Y201309D03*
X364747D03*
X371507D03*
X378267D03*
X385027D03*
X391787D03*
X398546D03*
X361367Y199360D03*
X368127D03*
X374887D03*
X381647D03*
X388407D03*
X395166D03*
X357987Y232509D03*
X364747D03*
X371507D03*
X378267D03*
X385027D03*
X391787D03*
X398546D03*
X361367Y230559D03*
X368127D03*
X374887D03*
X381647D03*
X388407D03*
X395166D03*
X401926D03*
X357987Y228610D03*
X364747D03*
X371507D03*
X378267D03*
X385027D03*
X391787D03*
X398546D03*
X361367Y226660D03*
X368127D03*
X374887D03*
X381647D03*
X388407D03*
X395166D03*
X401926D03*
X357987Y224709D03*
X364747D03*
X371507D03*
X378267D03*
X385027D03*
X391787D03*
X398546D03*
X357987Y220809D03*
X364747D03*
X371507D03*
X378267D03*
X385027D03*
X391787D03*
X398546D03*
X361367Y218860D03*
X368127D03*
X374887D03*
X381647D03*
X388407D03*
X395166D03*
X401926D03*
X357987Y263709D03*
X361367Y261760D03*
X357987Y259809D03*
X364747D03*
X361367Y257860D03*
X368127D03*
X357987Y255909D03*
X364747D03*
X371507D03*
X361367Y253960D03*
X368127D03*
X374887D03*
X357987Y252009D03*
X364747D03*
X371507D03*
X378267D03*
X385027D03*
X391787D03*
X398546D03*
X361367Y250060D03*
X368127D03*
X374887D03*
X381647D03*
X388407D03*
X395166D03*
X401926D03*
X357987Y248109D03*
X364747D03*
X371507D03*
X378267D03*
X385027D03*
X391787D03*
X398546D03*
X361367Y246160D03*
X368127D03*
X374887D03*
X381647D03*
X388407D03*
X395166D03*
X401926D03*
X357987Y244209D03*
X364747D03*
X371507D03*
X378267D03*
X385027D03*
X391787D03*
X398546D03*
X361367Y242260D03*
X368127D03*
X374887D03*
X381647D03*
X388407D03*
X395166D03*
X401926D03*
X357987Y240309D03*
X364747D03*
X371507D03*
X378267D03*
X385027D03*
X391787D03*
X398546D03*
X361367Y238360D03*
X368127D03*
X374887D03*
X381647D03*
X388407D03*
X395166D03*
X401926D03*
X357987Y236409D03*
X364747D03*
X371507D03*
X378267D03*
X385027D03*
X391787D03*
X398546D03*
X361367Y234460D03*
X368127D03*
X374887D03*
X381647D03*
X388407D03*
X395166D03*
X401926D03*
X361367Y222760D03*
X368127D03*
X374887D03*
X381647D03*
X388407D03*
X395166D03*
X401926D03*
X357987Y341709D03*
X364747D03*
X371507D03*
X361367Y339760D03*
X368127D03*
X357987Y337809D03*
X364747D03*
X361367Y335860D03*
X357987Y333909D03*
X361367Y398260D03*
X368127D03*
X374887D03*
X381647D03*
X388407D03*
X395166D03*
X401926D03*
X357987Y396309D03*
X364747D03*
X371507D03*
X378267D03*
X385027D03*
X391787D03*
X398546D03*
X405306D03*
X361367Y394359D03*
X368127D03*
X374887D03*
X381647D03*
X388407D03*
X395166D03*
X401926D03*
X357987Y392410D03*
X364747D03*
X371507D03*
X378267D03*
X385027D03*
X391787D03*
X398546D03*
X405306D03*
X361367Y390460D03*
X368127D03*
X374887D03*
X381647D03*
X388407D03*
X395166D03*
X401926D03*
X357987Y388509D03*
X364747D03*
X371507D03*
X378267D03*
X385027D03*
X391787D03*
X398546D03*
X405306D03*
X361367Y386560D03*
X368127D03*
X374887D03*
X381647D03*
X388407D03*
X395166D03*
X401926D03*
X357987Y384609D03*
X364747D03*
X371507D03*
X378267D03*
X385027D03*
X391787D03*
X398546D03*
X405306D03*
X361367Y382660D03*
X368127D03*
X374887D03*
X381647D03*
X388407D03*
X395166D03*
X401926D03*
X357987Y380709D03*
X364747D03*
X371507D03*
X378267D03*
X385027D03*
X391787D03*
X398546D03*
X405306D03*
X361367Y378760D03*
X368127D03*
X374887D03*
X381647D03*
X388407D03*
X395166D03*
X401926D03*
X357987Y376809D03*
X364747D03*
X371507D03*
X378267D03*
X385027D03*
X391787D03*
X398546D03*
X405306D03*
X361367Y374860D03*
X368127D03*
X374887D03*
X381647D03*
X388407D03*
X395166D03*
X401926D03*
X361367Y370959D03*
X368127D03*
X374887D03*
X381647D03*
X388407D03*
X395166D03*
X401926D03*
X357987Y369010D03*
X364747D03*
X371507D03*
X378267D03*
X385027D03*
X391787D03*
X398546D03*
X405306D03*
X361367Y367060D03*
X368127D03*
X374887D03*
X381647D03*
X388407D03*
X395166D03*
X401926D03*
X357987Y365109D03*
X364747D03*
X371507D03*
X378267D03*
X385027D03*
X391787D03*
X398546D03*
X405306D03*
X361367Y363160D03*
X368127D03*
X374887D03*
X381647D03*
X388407D03*
X395166D03*
X401926D03*
X357987Y361209D03*
X364747D03*
X371507D03*
X378267D03*
X385027D03*
X391787D03*
X398546D03*
X405306D03*
X361367Y359260D03*
X368127D03*
X374887D03*
X381647D03*
X388407D03*
X395166D03*
X401926D03*
X357987Y357309D03*
X364747D03*
X371507D03*
X378267D03*
X385027D03*
X391787D03*
X398546D03*
X405306D03*
X361367Y355360D03*
X368127D03*
X374887D03*
X381647D03*
X388407D03*
X395166D03*
X401926D03*
X357987Y353409D03*
X364747D03*
X371507D03*
X378267D03*
X385027D03*
X391787D03*
X398546D03*
X405306D03*
X361367Y351460D03*
X368127D03*
X374887D03*
X381647D03*
X388407D03*
X395166D03*
X401926D03*
X357987Y349509D03*
X364747D03*
X371507D03*
X378267D03*
X385027D03*
X391787D03*
X398546D03*
X361367Y347560D03*
X368127D03*
X374887D03*
X381647D03*
X357987Y345609D03*
X364747D03*
X371507D03*
X378267D03*
X361367Y343660D03*
X368127D03*
X374887D03*
X357987Y372909D03*
X364747D03*
X371507D03*
X378267D03*
X385027D03*
X391787D03*
X398546D03*
X405306D03*
X421464Y218147D03*
X428224D03*
X434983D03*
X441743D03*
X448503D03*
X455263D03*
X462023D03*
X468783D03*
X475542D03*
X418084Y216196D03*
X424844D03*
X431604D03*
X438363D03*
X445123D03*
X451883D03*
X458643D03*
X465403D03*
X472163D03*
X421464Y214247D03*
X428224D03*
X434983D03*
X441743D03*
X448503D03*
X455263D03*
X462023D03*
X468783D03*
X475542D03*
X418084Y212296D03*
X424844D03*
X431604D03*
X438363D03*
X445123D03*
X451883D03*
X458643D03*
X465403D03*
X472163D03*
X421464Y210346D03*
X428224D03*
X434983D03*
X441743D03*
X448503D03*
X455263D03*
X462023D03*
X468783D03*
X475542D03*
X418084Y208397D03*
X424844D03*
X431604D03*
X438363D03*
X445123D03*
X451883D03*
X458643D03*
X465403D03*
X472163D03*
X421464Y206447D03*
X428224D03*
X434983D03*
X441743D03*
X448503D03*
X455263D03*
X462023D03*
X468783D03*
X475542D03*
X424844Y204496D03*
X431604D03*
X438363D03*
X445123D03*
X451883D03*
X458643D03*
X465403D03*
X472163D03*
X418084Y239596D03*
X424844D03*
X431604D03*
X438363D03*
X445123D03*
X451883D03*
X458643D03*
X465403D03*
X472163D03*
X421464Y237647D03*
X428224D03*
X434983D03*
X441743D03*
X448503D03*
X455263D03*
X462023D03*
X468783D03*
X475542D03*
X418084Y235696D03*
X424844D03*
X431604D03*
X438363D03*
X445123D03*
X451883D03*
X458643D03*
X465403D03*
X472163D03*
X421464Y233746D03*
X428224D03*
X434983D03*
X441743D03*
X448503D03*
X455263D03*
X462023D03*
X468783D03*
X475542D03*
X418084Y231797D03*
X424844D03*
X431604D03*
X438363D03*
X445123D03*
X451883D03*
X458643D03*
X465403D03*
X472163D03*
X418084Y227896D03*
X424844D03*
X431604D03*
X438363D03*
X445123D03*
X451883D03*
X458643D03*
X465403D03*
X472163D03*
X421464Y225947D03*
X428224D03*
X434983D03*
X441743D03*
X448503D03*
X455263D03*
X462023D03*
X468783D03*
X475542D03*
X418084Y223996D03*
X424844D03*
X431604D03*
X438363D03*
X445123D03*
X451883D03*
X458643D03*
X465403D03*
X472163D03*
X421464Y222047D03*
X428224D03*
X434983D03*
X441743D03*
X448503D03*
X455263D03*
X462023D03*
X468783D03*
X475542D03*
X418084Y220096D03*
X424844D03*
X431604D03*
X438363D03*
X445123D03*
X451883D03*
X458643D03*
X465403D03*
X472163D03*
Y278596D03*
X475542Y276646D03*
X472163Y274696D03*
X468783Y272747D03*
X475542D03*
X465403Y270796D03*
X472163D03*
X462023Y268847D03*
X468783D03*
X475542D03*
X458643Y266896D03*
X465403D03*
X472163D03*
X455263Y264947D03*
X462023D03*
X468783D03*
X475542D03*
X451883Y262996D03*
X458643D03*
X465403D03*
X472163D03*
X448503Y261047D03*
X455263D03*
X462023D03*
X468783D03*
X475542D03*
X445123Y259096D03*
X451883D03*
X458643D03*
X465403D03*
X472163D03*
X441743Y257147D03*
X448503D03*
X455263D03*
X462023D03*
X468783D03*
X475542D03*
X424844Y255196D03*
X431604D03*
X438363D03*
X445123D03*
X451883D03*
X458643D03*
X465403D03*
X472163D03*
X421464Y253247D03*
X428224D03*
X434983D03*
X441743D03*
X448503D03*
X455263D03*
X462023D03*
X468783D03*
X475542D03*
X418084Y251296D03*
X424844D03*
X431604D03*
X438363D03*
X445123D03*
X451883D03*
X458643D03*
X465403D03*
X472163D03*
X421464Y249347D03*
X428224D03*
X434983D03*
X441743D03*
X448503D03*
X455263D03*
X462023D03*
X468783D03*
X475542D03*
X418084Y247396D03*
X424844D03*
X431604D03*
X438363D03*
X445123D03*
X451883D03*
X458643D03*
X465403D03*
X472163D03*
X421464Y245447D03*
X428224D03*
X434983D03*
X441743D03*
X448503D03*
X455263D03*
X462023D03*
X468783D03*
X475542D03*
X418084Y243496D03*
X424844D03*
X431604D03*
X438363D03*
X445123D03*
X451883D03*
X458643D03*
X465403D03*
X472163D03*
X421464Y241547D03*
X428224D03*
X434983D03*
X441743D03*
X448503D03*
X455263D03*
X462023D03*
X468783D03*
X475542D03*
X421464Y229847D03*
X428224D03*
X434983D03*
X441743D03*
X448503D03*
X455263D03*
X462023D03*
X468783D03*
X475542D03*
X458643Y340996D03*
X465403D03*
X472163D03*
X462023Y339047D03*
X468783D03*
X475542D03*
X465403Y337096D03*
X472163D03*
X468783Y335147D03*
X475542D03*
X472163Y333196D03*
X475542Y331247D03*
X472163Y329296D03*
X475542Y327347D03*
X472163Y325396D03*
X475542Y323446D03*
X472163Y321496D03*
X475542Y319547D03*
X472163Y317596D03*
X475542Y315647D03*
X472163Y313696D03*
X475542Y311747D03*
X472163Y309797D03*
X475542Y307847D03*
X472163Y305896D03*
X475542Y303947D03*
X472163Y301996D03*
X475542Y300047D03*
X472163Y298096D03*
X475542Y296147D03*
X472163Y294196D03*
X475542Y292247D03*
X472163Y290296D03*
X475542Y288347D03*
X472163Y286396D03*
X475542Y284447D03*
X472163Y282496D03*
X475542Y280547D03*
X431604Y403396D03*
X438363D03*
X445123D03*
X451883D03*
X458643D03*
X465403D03*
X472163D03*
X428224Y401447D03*
X434983D03*
X441743D03*
X448503D03*
X455263D03*
X462023D03*
X468783D03*
X475542D03*
X424844Y399496D03*
X431604D03*
X438363D03*
X445123D03*
X451883D03*
X458643D03*
X465403D03*
X472163D03*
X421464Y397546D03*
X428224D03*
X434983D03*
X441743D03*
X448503D03*
X455263D03*
X462023D03*
X468783D03*
X475542D03*
X424844Y395597D03*
X431604D03*
X438363D03*
X445123D03*
X451883D03*
X458643D03*
X465403D03*
X472163D03*
X421464Y393647D03*
X428224D03*
X434983D03*
X441743D03*
X448503D03*
X455263D03*
X462023D03*
X468783D03*
X475542D03*
X424844Y391696D03*
X431604D03*
X438363D03*
X445123D03*
X451883D03*
X458643D03*
X465403D03*
X472163D03*
X421464Y389747D03*
X428224D03*
X434983D03*
X441743D03*
X448503D03*
X455263D03*
X462023D03*
X468783D03*
X475542D03*
X424844Y387796D03*
X431604D03*
X438363D03*
X445123D03*
X451883D03*
X458643D03*
X465403D03*
X472163D03*
X421464Y385847D03*
X428224D03*
X434983D03*
X441743D03*
X448503D03*
X455263D03*
X462023D03*
X468783D03*
X475542D03*
X424844Y383896D03*
X431604D03*
X438363D03*
X445123D03*
X451883D03*
X458643D03*
X465403D03*
X472163D03*
X421464Y381947D03*
X428224D03*
X434983D03*
X441743D03*
X448503D03*
X455263D03*
X462023D03*
X468783D03*
X475542D03*
X421464Y378047D03*
X428224D03*
X434983D03*
X441743D03*
X448503D03*
X455263D03*
X462023D03*
X468783D03*
X475542D03*
X424844Y376096D03*
X431604D03*
X438363D03*
X445123D03*
X451883D03*
X458643D03*
X465403D03*
X472163D03*
X421464Y374146D03*
X428224D03*
X434983D03*
X441743D03*
X448503D03*
X455263D03*
X462023D03*
X468783D03*
X475542D03*
X424844Y372197D03*
X431604D03*
X438363D03*
X445123D03*
X451883D03*
X458643D03*
X465403D03*
X472163D03*
X421464Y370247D03*
X428224D03*
X434983D03*
X441743D03*
X448503D03*
X455263D03*
X462023D03*
X468783D03*
X475542D03*
X424844Y368296D03*
X431604D03*
X438363D03*
X445123D03*
X451883D03*
X458643D03*
X465403D03*
X472163D03*
X421464Y366347D03*
X428224D03*
X434983D03*
X441743D03*
X448503D03*
X455263D03*
X462023D03*
X468783D03*
X475542D03*
X424844Y364396D03*
X431604D03*
X438363D03*
X445123D03*
X451883D03*
X458643D03*
X465403D03*
X472163D03*
X421464Y362447D03*
X428224D03*
X434983D03*
X441743D03*
X448503D03*
X455263D03*
X462023D03*
X468783D03*
X475542D03*
X424844Y360496D03*
X431604D03*
X438363D03*
X445123D03*
X451883D03*
X458643D03*
X465403D03*
X472163D03*
X421464Y358547D03*
X428224D03*
X434983D03*
X441743D03*
X448503D03*
X455263D03*
X462023D03*
X468783D03*
X475542D03*
X424844Y356596D03*
X431604D03*
X438363D03*
X445123D03*
X451883D03*
X458643D03*
X465403D03*
X472163D03*
X421464Y354647D03*
X428224D03*
X434983D03*
X441743D03*
X448503D03*
X455263D03*
X462023D03*
X468783D03*
X475542D03*
X424844Y352696D03*
X431604D03*
X438363D03*
X445123D03*
X451883D03*
X458643D03*
X465403D03*
X472163D03*
X421464Y350747D03*
X428224D03*
X434983D03*
X441743D03*
X448503D03*
X455263D03*
X462023D03*
X468783D03*
X475542D03*
X424844Y348796D03*
X431604D03*
X438363D03*
X445123D03*
X451883D03*
X458643D03*
X465403D03*
X472163D03*
X448503Y346847D03*
X455263D03*
X462023D03*
X468783D03*
X475542D03*
X451883Y344896D03*
X458643D03*
X465403D03*
X472163D03*
X455263Y342947D03*
X462023D03*
X468783D03*
X475542D03*
X424844Y379996D03*
X431604D03*
X438363D03*
X445123D03*
X451883D03*
X458643D03*
X465403D03*
X472163D03*
X536381Y218147D03*
X482302D03*
X489062D03*
X495822D03*
X502582D03*
X509342D03*
X516102D03*
X522861D03*
X529621D03*
X533001Y216196D03*
X539761D03*
X478922D03*
X485682D03*
X492442D03*
X499202D03*
X505962D03*
X512722D03*
X519481D03*
X526241D03*
X536381Y214247D03*
X482302D03*
X489062D03*
X495822D03*
X502582D03*
X509342D03*
X516102D03*
X522861D03*
X529621D03*
X533001Y212296D03*
X539761D03*
X478922D03*
X485682D03*
X492442D03*
X499202D03*
X505962D03*
X512722D03*
X519481D03*
X526241D03*
X536381Y210346D03*
X509342D03*
X516102D03*
X522861D03*
X529621D03*
X533001Y208397D03*
X539761D03*
X478922D03*
X505962D03*
X512722D03*
X519481D03*
X526241D03*
X536381Y206447D03*
X509342D03*
X516102D03*
X522861D03*
X529621D03*
X533001Y204496D03*
X478922D03*
X512722D03*
X519481D03*
X526241D03*
X533001Y239596D03*
X539761D03*
X478922D03*
X485682D03*
X492442D03*
X499202D03*
X505962D03*
X512722D03*
X519481D03*
X526241D03*
X536381Y237647D03*
X482302D03*
X489062D03*
X495822D03*
X502582D03*
X509342D03*
X516102D03*
X522861D03*
X529621D03*
X533001Y235696D03*
X539761D03*
X478922D03*
X485682D03*
X492442D03*
X499202D03*
X505962D03*
X512722D03*
X519481D03*
X526241D03*
X536381Y233746D03*
X482302D03*
X489062D03*
X495822D03*
X502582D03*
X509342D03*
X516102D03*
X522861D03*
X529621D03*
X533001Y231797D03*
X539761D03*
X478922D03*
X485682D03*
X492442D03*
X499202D03*
X505962D03*
X512722D03*
X519481D03*
X526241D03*
X533001Y227896D03*
X539761D03*
X478922D03*
X485682D03*
X492442D03*
X499202D03*
X505962D03*
X512722D03*
X519481D03*
X526241D03*
X536381Y225947D03*
X482302D03*
X489062D03*
X495822D03*
X502582D03*
X509342D03*
X516102D03*
X522861D03*
X529621D03*
X533001Y223996D03*
X539761D03*
X478922D03*
X485682D03*
X492442D03*
X499202D03*
X505962D03*
X512722D03*
X519481D03*
X526241D03*
X536381Y222047D03*
X482302D03*
X489062D03*
X495822D03*
X502582D03*
X509342D03*
X516102D03*
X522861D03*
X529621D03*
X533001Y220096D03*
X539761D03*
X478922D03*
X485682D03*
X492442D03*
X499202D03*
X505962D03*
X512722D03*
X519481D03*
X526241D03*
X533001Y278596D03*
X539761D03*
X478922D03*
X485682D03*
X492442D03*
X499202D03*
X505962D03*
X512722D03*
X519481D03*
X526241D03*
X536381Y276646D03*
X482302D03*
X489062D03*
X495822D03*
X502582D03*
X509342D03*
X516102D03*
X522861D03*
X529621D03*
X533001Y274696D03*
X539761D03*
X478922D03*
X485682D03*
X492442D03*
X499202D03*
X505962D03*
X512722D03*
X519481D03*
X526241D03*
X536381Y272747D03*
X482302D03*
X489062D03*
X495822D03*
X502582D03*
X509342D03*
X516102D03*
X522861D03*
X529621D03*
X533001Y270796D03*
X539761D03*
X478922D03*
X485682D03*
X492442D03*
X499202D03*
X505962D03*
X512722D03*
X519481D03*
X526241D03*
X536381Y268847D03*
X482302D03*
X489062D03*
X495822D03*
X502582D03*
X509342D03*
X516102D03*
X522861D03*
X529621D03*
X533001Y266896D03*
X539761D03*
X478922D03*
X485682D03*
X492442D03*
X499202D03*
X505962D03*
X519481D03*
X526241D03*
X536381Y264947D03*
X482302D03*
X489062D03*
X495822D03*
X502582D03*
X516102D03*
X522861D03*
X529621D03*
X533001Y262996D03*
X539761D03*
X478922D03*
X485682D03*
X492442D03*
X499202D03*
X519481D03*
X526241D03*
X536381Y261047D03*
X482302D03*
X489062D03*
X495822D03*
X502582D03*
X516102D03*
X522861D03*
X529621D03*
X533001Y259096D03*
X539761D03*
X478922D03*
X485682D03*
X492442D03*
X499202D03*
X519481D03*
X526241D03*
X536381Y257147D03*
X482302D03*
X489062D03*
X495822D03*
X502582D03*
X516102D03*
X522861D03*
X529621D03*
X533001Y255196D03*
X539761D03*
X478922D03*
X485682D03*
X492442D03*
X499202D03*
X512722D03*
X519481D03*
X526241D03*
X536381Y253247D03*
X482302D03*
X489062D03*
X495822D03*
X502582D03*
X509342D03*
X516102D03*
X522861D03*
X529621D03*
X533001Y251296D03*
X539761D03*
X478922D03*
X485682D03*
X492442D03*
X499202D03*
X505962D03*
X512722D03*
X519481D03*
X526241D03*
X536381Y249347D03*
X482302D03*
X489062D03*
X495822D03*
X502582D03*
X509342D03*
X516102D03*
X522861D03*
X529621D03*
X533001Y247396D03*
X539761D03*
X478922D03*
X485682D03*
X492442D03*
X499202D03*
X505962D03*
X512722D03*
X519481D03*
X526241D03*
X536381Y245447D03*
X482302D03*
X489062D03*
X495822D03*
X502582D03*
X509342D03*
X516102D03*
X522861D03*
X529621D03*
X533001Y243496D03*
X539761D03*
X478922D03*
X485682D03*
X492442D03*
X499202D03*
X505962D03*
X512722D03*
X519481D03*
X526241D03*
X536381Y241547D03*
X482302D03*
X489062D03*
X495822D03*
X502582D03*
X509342D03*
X516102D03*
X522861D03*
X529621D03*
X536381Y229847D03*
X482302D03*
X489062D03*
X495822D03*
X502582D03*
X509342D03*
X516102D03*
X522861D03*
X529621D03*
X533001Y340996D03*
X539761D03*
X478922D03*
X485682D03*
X492442D03*
X499202D03*
X512722D03*
X519481D03*
X526241D03*
X536381Y339047D03*
X482302D03*
X489062D03*
X495822D03*
X502582D03*
X509342D03*
X516102D03*
X522861D03*
X529621D03*
X533001Y337096D03*
X539761D03*
X478922D03*
X485682D03*
X492442D03*
X499202D03*
X505962D03*
X512722D03*
X519481D03*
X526241D03*
X536381Y335147D03*
X482302D03*
X489062D03*
X495822D03*
X502582D03*
X509342D03*
X516102D03*
X522861D03*
X529621D03*
X533001Y333196D03*
X539761D03*
X478922D03*
X485682D03*
X492442D03*
X499202D03*
X505962D03*
X512722D03*
X519481D03*
X526241D03*
X536381Y331247D03*
X482302D03*
X489062D03*
X495822D03*
X502582D03*
X509342D03*
X516102D03*
X522861D03*
X529621D03*
X533001Y329296D03*
X539761D03*
X478922D03*
X485682D03*
X492442D03*
X499202D03*
X505962D03*
X512722D03*
X519481D03*
X526241D03*
X536381Y327347D03*
X482302D03*
X489062D03*
X495822D03*
X502582D03*
X509342D03*
X516102D03*
X522861D03*
X529621D03*
X533001Y325396D03*
X539761D03*
X478922D03*
X485682D03*
X492442D03*
X499202D03*
X505962D03*
X512722D03*
X519481D03*
X526241D03*
X536381Y323446D03*
X482302D03*
X489062D03*
X495822D03*
X502582D03*
X509342D03*
X516102D03*
X522861D03*
X529621D03*
X533001Y321496D03*
X539761D03*
X478922D03*
X485682D03*
X492442D03*
X499202D03*
X505962D03*
X512722D03*
X519481D03*
X526241D03*
X536381Y319547D03*
X482302D03*
X489062D03*
X495822D03*
X502582D03*
X509342D03*
X516102D03*
X522861D03*
X529621D03*
X533001Y317596D03*
X539761D03*
X478922D03*
X485682D03*
X492442D03*
X499202D03*
X505962D03*
X512722D03*
X519481D03*
X526241D03*
X536381Y315647D03*
X482302D03*
X489062D03*
X495822D03*
X502582D03*
X509342D03*
X516102D03*
X522861D03*
X529621D03*
X533001Y313696D03*
X539761D03*
X478922D03*
X485682D03*
X492442D03*
X499202D03*
X505962D03*
X512722D03*
X519481D03*
X526241D03*
X536381Y311747D03*
X482302D03*
X489062D03*
X495822D03*
X502582D03*
X509342D03*
X516102D03*
X522861D03*
X529621D03*
X533001Y309797D03*
X539761D03*
X478922D03*
X485682D03*
X492442D03*
X499202D03*
X505962D03*
X512722D03*
X519481D03*
X526241D03*
X536381Y307847D03*
X482302D03*
X489062D03*
X495822D03*
X502582D03*
X509342D03*
X516102D03*
X522861D03*
X529621D03*
X533001Y305896D03*
X539761D03*
X478922D03*
X485682D03*
X492442D03*
X499202D03*
X505962D03*
X512722D03*
X519481D03*
X526241D03*
X536381Y303947D03*
X482302D03*
X489062D03*
X495822D03*
X502582D03*
X509342D03*
X516102D03*
X522861D03*
X529621D03*
X533001Y301996D03*
X539761D03*
X478922D03*
X485682D03*
X492442D03*
X499202D03*
X505962D03*
X512722D03*
X519481D03*
X526241D03*
X536381Y300047D03*
X482302D03*
X489062D03*
X495822D03*
X502582D03*
X509342D03*
X516102D03*
X522861D03*
X529621D03*
X533001Y298096D03*
X539761D03*
X478922D03*
X485682D03*
X492442D03*
X499202D03*
X505962D03*
X512722D03*
X519481D03*
X526241D03*
X536381Y296147D03*
X482302D03*
X489062D03*
X495822D03*
X502582D03*
X509342D03*
X516102D03*
X522861D03*
X529621D03*
X533001Y294196D03*
X539761D03*
X478922D03*
X485682D03*
X492442D03*
X499202D03*
X505962D03*
X512722D03*
X519481D03*
X526241D03*
X536381Y292247D03*
X482302D03*
X489062D03*
X495822D03*
X502582D03*
X509342D03*
X516102D03*
X522861D03*
X529621D03*
X533001Y290296D03*
X539761D03*
X478922D03*
X485682D03*
X492442D03*
X499202D03*
X505962D03*
X512722D03*
X519481D03*
X526241D03*
X536381Y288347D03*
X482302D03*
X489062D03*
X495822D03*
X502582D03*
X509342D03*
X516102D03*
X522861D03*
X529621D03*
X533001Y286396D03*
X539761D03*
X478922D03*
X485682D03*
X492442D03*
X499202D03*
X505962D03*
X512722D03*
X519481D03*
X526241D03*
X536381Y284447D03*
X482302D03*
X489062D03*
X495822D03*
X502582D03*
X509342D03*
X516102D03*
X522861D03*
X529621D03*
X533001Y282496D03*
X539761D03*
X478922D03*
X485682D03*
X492442D03*
X499202D03*
X505962D03*
X512722D03*
X519481D03*
X526241D03*
X536381Y280547D03*
X482302D03*
X489062D03*
X495822D03*
X502582D03*
X509342D03*
X516102D03*
X522861D03*
X529621D03*
X533001Y403396D03*
X478922D03*
X512722D03*
X519481D03*
X526241D03*
X536381Y401447D03*
X482302D03*
X516102D03*
X522861D03*
X529621D03*
X533001Y399496D03*
X539761D03*
X478922D03*
X485682D03*
X512722D03*
X519481D03*
X526241D03*
X536381Y397546D03*
X482302D03*
X489062D03*
X516102D03*
X522861D03*
X529621D03*
X533001Y395597D03*
X539761D03*
X478922D03*
X485682D03*
X492442D03*
X499202D03*
X505962D03*
X512722D03*
X519481D03*
X526241D03*
X536381Y393647D03*
X482302D03*
X489062D03*
X495822D03*
X502582D03*
X509342D03*
X516102D03*
X522861D03*
X529621D03*
X533001Y391696D03*
X539761D03*
X478922D03*
X485682D03*
X492442D03*
X499202D03*
X505962D03*
X512722D03*
X519481D03*
X526241D03*
X536381Y389747D03*
X482302D03*
X489062D03*
X495822D03*
X502582D03*
X509342D03*
X516102D03*
X522861D03*
X529621D03*
X533001Y387796D03*
X539761D03*
X478922D03*
X485682D03*
X492442D03*
X499202D03*
X505962D03*
X512722D03*
X519481D03*
X526241D03*
X536381Y385847D03*
X482302D03*
X489062D03*
X495822D03*
X502582D03*
X509342D03*
X516102D03*
X522861D03*
X529621D03*
X533001Y383896D03*
X539761D03*
X478922D03*
X485682D03*
X492442D03*
X499202D03*
X505962D03*
X512722D03*
X519481D03*
X526241D03*
X536381Y381947D03*
X482302D03*
X489062D03*
X495822D03*
X502582D03*
X509342D03*
X516102D03*
X522861D03*
X529621D03*
X536381Y378047D03*
X482302D03*
X489062D03*
X495822D03*
X502582D03*
X509342D03*
X516102D03*
X522861D03*
X529621D03*
X533001Y376096D03*
X539761D03*
X478922D03*
X485682D03*
X492442D03*
X499202D03*
X505962D03*
X512722D03*
X519481D03*
X526241D03*
X536381Y374146D03*
X482302D03*
X489062D03*
X495822D03*
X502582D03*
X509342D03*
X516102D03*
X522861D03*
X529621D03*
X533001Y372197D03*
X539761D03*
X478922D03*
X485682D03*
X492442D03*
X499202D03*
X505962D03*
X512722D03*
X519481D03*
X526241D03*
X536381Y370247D03*
X482302D03*
X489062D03*
X495822D03*
X502582D03*
X509342D03*
X516102D03*
X522861D03*
X529621D03*
X533001Y368296D03*
X539761D03*
X478922D03*
X485682D03*
X492442D03*
X499202D03*
X505962D03*
X512722D03*
X519481D03*
X526241D03*
X536381Y366347D03*
X482302D03*
X489062D03*
X495822D03*
X502582D03*
X509342D03*
X516102D03*
X522861D03*
X529621D03*
X533001Y364396D03*
X539761D03*
X478922D03*
X485682D03*
X492442D03*
X499202D03*
X505962D03*
X512722D03*
X519481D03*
X526241D03*
X536381Y362447D03*
X482302D03*
X489062D03*
X495822D03*
X502582D03*
X509342D03*
X516102D03*
X522861D03*
X529621D03*
X533001Y360496D03*
X539761D03*
X478922D03*
X485682D03*
X492442D03*
X499202D03*
X505962D03*
X512722D03*
X519481D03*
X526241D03*
X536381Y358547D03*
X482302D03*
X489062D03*
X495822D03*
X502582D03*
X509342D03*
X516102D03*
X522861D03*
X529621D03*
X533001Y356596D03*
X539761D03*
X478922D03*
X485682D03*
X492442D03*
X499202D03*
X505962D03*
X512722D03*
X519481D03*
X526241D03*
X536381Y354647D03*
X482302D03*
X489062D03*
X495822D03*
X502582D03*
X509342D03*
X516102D03*
X522861D03*
X529621D03*
X533001Y352696D03*
X539761D03*
X478922D03*
X485682D03*
X492442D03*
X499202D03*
X505962D03*
X519481D03*
X526241D03*
X536381Y350747D03*
X482302D03*
X489062D03*
X495822D03*
X502582D03*
X516102D03*
X522861D03*
X529621D03*
X533001Y348796D03*
X539761D03*
X478922D03*
X485682D03*
X492442D03*
X499202D03*
X519481D03*
X526241D03*
X536381Y346847D03*
X482302D03*
X489062D03*
X495822D03*
X502582D03*
X516102D03*
X522861D03*
X529621D03*
X533001Y344896D03*
X539761D03*
X478922D03*
X485682D03*
X492442D03*
X499202D03*
X519481D03*
X526241D03*
X536381Y342947D03*
X482302D03*
X489062D03*
X495822D03*
X502582D03*
X516102D03*
X522861D03*
X529621D03*
X533001Y379996D03*
X539761D03*
X478922D03*
X485682D03*
X492442D03*
X499202D03*
X505962D03*
X512722D03*
X519481D03*
X526241D03*
X543141Y218147D03*
X549901D03*
X556661D03*
X546521Y216196D03*
X553281D03*
X543141Y214247D03*
X549901D03*
X546521Y212296D03*
X543141Y210346D03*
X546521Y239596D03*
X553281D03*
X543141Y237647D03*
X549901D03*
X556661D03*
X546521Y235696D03*
X553281D03*
X543141Y233746D03*
X549901D03*
X556661D03*
X546521Y231797D03*
X553281D03*
X546521Y227896D03*
X553281D03*
X543141Y225947D03*
X549901D03*
X556661D03*
X546521Y223996D03*
X553281D03*
X543141Y222047D03*
X549901D03*
X556661D03*
X546521Y220096D03*
X553281D03*
X546521Y278596D03*
X553281D03*
X543141Y276646D03*
X549901D03*
X546521Y274696D03*
X553281D03*
X543141Y272747D03*
X549901D03*
X556661D03*
X546521Y270796D03*
X553281D03*
X543141Y268847D03*
X549901D03*
X556661D03*
X546521Y266896D03*
X553281D03*
X543141Y264947D03*
X549901D03*
X556661D03*
X546521Y262996D03*
X553281D03*
X543141Y261047D03*
X549901D03*
X556661D03*
X546521Y259096D03*
X553281D03*
X543141Y257147D03*
X549901D03*
X556661D03*
X546521Y255196D03*
X553281D03*
X543141Y253247D03*
X549901D03*
X556661D03*
X546521Y251296D03*
X553281D03*
X543141Y249347D03*
X549901D03*
X556661D03*
X546521Y247396D03*
X553281D03*
X543141Y245447D03*
X549901D03*
X556661D03*
X546521Y243496D03*
X553281D03*
X543141Y241547D03*
X549901D03*
X556661D03*
X543141Y229847D03*
X549901D03*
X556661D03*
X546521Y340996D03*
X553281D03*
X543141Y339047D03*
X549901D03*
X556661D03*
X546521Y337096D03*
X553281D03*
X543141Y335147D03*
X549901D03*
X556661D03*
X546521Y333196D03*
X553281D03*
X543141Y331247D03*
X549901D03*
X546521Y329296D03*
X553281D03*
X543141Y327347D03*
X549901D03*
X546521Y325396D03*
X553281D03*
X543141Y323446D03*
X549901D03*
X546521Y321496D03*
X553281D03*
X543141Y319547D03*
X549901D03*
X546521Y317596D03*
X543141Y315647D03*
X549901D03*
X546521Y313696D03*
X543141Y311747D03*
X549901D03*
X546521Y309797D03*
X543141Y307847D03*
X549901D03*
X546521Y305896D03*
X543141Y303947D03*
X549901D03*
X546521Y301996D03*
X543141Y300047D03*
X549901D03*
X546521Y298096D03*
X543141Y296147D03*
X549901D03*
X546521Y294196D03*
X543141Y292247D03*
X549901D03*
X546521Y290296D03*
X543141Y288347D03*
X549901D03*
X546521Y286396D03*
X543141Y284447D03*
X549901D03*
X546521Y282496D03*
X553281D03*
X543141Y280547D03*
X549901D03*
X543141Y397546D03*
X546521Y395597D03*
X543141Y393647D03*
X549901D03*
X546521Y391696D03*
X553281D03*
X543141Y389747D03*
X549901D03*
X546521Y387796D03*
X553281D03*
X543141Y385847D03*
X549901D03*
X546521Y383896D03*
X553281D03*
X543141Y381947D03*
X549901D03*
X543141Y378047D03*
X549901D03*
X546521Y376096D03*
X553281D03*
X543141Y374146D03*
X549901D03*
X546521Y372197D03*
X553281D03*
X543141Y370247D03*
X549901D03*
X546521Y368296D03*
X553281D03*
X543141Y366347D03*
X549901D03*
X546521Y364396D03*
X553281D03*
X543141Y362447D03*
X549901D03*
X546521Y360496D03*
X553281D03*
X543141Y358547D03*
X549901D03*
X556661D03*
X546521Y356596D03*
X553281D03*
X543141Y354647D03*
X549901D03*
X556661D03*
X546521Y352696D03*
X553281D03*
X543141Y350747D03*
X549901D03*
X556661D03*
X546521Y348796D03*
X553281D03*
X543141Y346847D03*
X549901D03*
X556661D03*
X546521Y344896D03*
X553281D03*
X543141Y342947D03*
X549901D03*
X556661D03*
X546521Y379996D03*
X553281D03*
X919717Y216909D03*
X926477D03*
X933237D03*
X939997D03*
X946757D03*
X953517D03*
X960276D03*
X967036D03*
X923097Y214960D03*
X929857D03*
X936617D03*
X943377D03*
X950137D03*
X956897D03*
X963656D03*
X970416D03*
X919717Y213009D03*
X926477D03*
X933237D03*
X939997D03*
X946757D03*
X953517D03*
X960276D03*
X967036D03*
X923097Y211060D03*
X929857D03*
X936617D03*
X943377D03*
X950137D03*
X956897D03*
X963656D03*
X970416D03*
X926477Y209109D03*
X933237D03*
X939997D03*
X946757D03*
X953517D03*
X960276D03*
X967036D03*
X929857Y207159D03*
X936617D03*
X943377D03*
X950137D03*
X956897D03*
X963656D03*
X970416D03*
X933237Y205210D03*
X939997D03*
X946757D03*
X953517D03*
X960276D03*
X936617Y203260D03*
X943377D03*
X950137D03*
X956897D03*
X963656D03*
X939997Y201309D03*
X946757D03*
X953517D03*
X960276D03*
X943377Y199360D03*
X950137D03*
X956897D03*
X963656D03*
X919717Y232509D03*
X926477D03*
X933237D03*
X939997D03*
X946757D03*
X953517D03*
X960276D03*
X967036D03*
X923097Y230559D03*
X929857D03*
X936617D03*
X943377D03*
X950137D03*
X956897D03*
X963656D03*
X970416D03*
X919717Y228610D03*
X926477D03*
X933237D03*
X939997D03*
X946757D03*
X953517D03*
X960276D03*
X967036D03*
X923097Y226660D03*
X929857D03*
X936617D03*
X943377D03*
X950137D03*
X956897D03*
X963656D03*
X970416D03*
X919717Y224709D03*
X926477D03*
X933237D03*
X939997D03*
X946757D03*
X953517D03*
X960276D03*
X967036D03*
X919717Y220809D03*
X926477D03*
X933237D03*
X939997D03*
X946757D03*
X953517D03*
X960276D03*
X967036D03*
X923097Y218860D03*
X929857D03*
X936617D03*
X943377D03*
X950137D03*
X956897D03*
X963656D03*
X970416D03*
X926477Y279310D03*
X933237D03*
X939997D03*
X946757D03*
X953517D03*
X960276D03*
X967036D03*
X923097Y277360D03*
X929857D03*
X936617D03*
X943377D03*
X950137D03*
X956897D03*
X963656D03*
X970416D03*
X926477Y275409D03*
X933237D03*
X939997D03*
X946757D03*
X953517D03*
X960276D03*
X967036D03*
X923097Y273460D03*
X929857D03*
X936617D03*
X943377D03*
X950137D03*
X956897D03*
X963656D03*
X970416D03*
X919717Y271509D03*
X926477D03*
X933237D03*
X939997D03*
X946757D03*
X953517D03*
X960276D03*
X967036D03*
X923097Y269560D03*
X929857D03*
X936617D03*
X943377D03*
X950137D03*
X956897D03*
X963656D03*
X970416D03*
X919717Y267609D03*
X926477D03*
X933237D03*
X939997D03*
X946757D03*
X953517D03*
X960276D03*
X967036D03*
X923097Y265660D03*
X929857D03*
X936617D03*
X943377D03*
X950137D03*
X956897D03*
X963656D03*
X970416D03*
X919717Y263709D03*
X926477D03*
X933237D03*
X939997D03*
X946757D03*
X953517D03*
X960276D03*
X967036D03*
X923097Y261760D03*
X929857D03*
X936617D03*
X943377D03*
X950137D03*
X956897D03*
X963656D03*
X919717Y259809D03*
X926477D03*
X933237D03*
X939997D03*
X946757D03*
X953517D03*
X960276D03*
X923097Y257860D03*
X929857D03*
X936617D03*
X943377D03*
X950137D03*
X956897D03*
X919717Y255909D03*
X926477D03*
X933237D03*
X939997D03*
X946757D03*
X953517D03*
X960276D03*
X923097Y253960D03*
X929857D03*
X936617D03*
X943377D03*
X950137D03*
X956897D03*
X919717Y252009D03*
X926477D03*
X933237D03*
X939997D03*
X946757D03*
X953517D03*
X960276D03*
X923097Y250060D03*
X929857D03*
X936617D03*
X943377D03*
X950137D03*
X956897D03*
X970416D03*
X919717Y248109D03*
X926477D03*
X933237D03*
X939997D03*
X946757D03*
X953517D03*
X960276D03*
X967036D03*
X923097Y246160D03*
X929857D03*
X936617D03*
X943377D03*
X950137D03*
X956897D03*
X963656D03*
X970416D03*
X919717Y244209D03*
X926477D03*
X933237D03*
X939997D03*
X946757D03*
X953517D03*
X960276D03*
X967036D03*
X923097Y242260D03*
X929857D03*
X936617D03*
X943377D03*
X950137D03*
X956897D03*
X963656D03*
X970416D03*
X919717Y240309D03*
X926477D03*
X933237D03*
X939997D03*
X946757D03*
X953517D03*
X960276D03*
X967036D03*
X923097Y238360D03*
X929857D03*
X936617D03*
X943377D03*
X950137D03*
X956897D03*
X963656D03*
X970416D03*
X919717Y236409D03*
X926477D03*
X933237D03*
X939997D03*
X946757D03*
X953517D03*
X960276D03*
X967036D03*
X923097Y234460D03*
X929857D03*
X936617D03*
X943377D03*
X950137D03*
X956897D03*
X963656D03*
X970416D03*
X923097Y222760D03*
X929857D03*
X936617D03*
X943377D03*
X950137D03*
X956897D03*
X963656D03*
X970416D03*
X919717Y341709D03*
X926477D03*
X933237D03*
X939997D03*
X946757D03*
X953517D03*
X960276D03*
X923097Y339760D03*
X929857D03*
X936617D03*
X943377D03*
X950137D03*
X956897D03*
X919717Y337809D03*
X926477D03*
X933237D03*
X939997D03*
X946757D03*
X953517D03*
X960276D03*
X923097Y335860D03*
X929857D03*
X936617D03*
X943377D03*
X950137D03*
X956897D03*
X970416D03*
X919717Y333909D03*
X926477D03*
X933237D03*
X939997D03*
X946757D03*
X953517D03*
X960276D03*
X967036D03*
X923097Y331960D03*
X929857D03*
X936617D03*
X943377D03*
X950137D03*
X956897D03*
X963656D03*
X970416D03*
X919717Y330009D03*
X926477D03*
X933237D03*
X939997D03*
X946757D03*
X953517D03*
X960276D03*
X967036D03*
X923097Y328060D03*
X929857D03*
X936617D03*
X943377D03*
X950137D03*
X956897D03*
X963656D03*
X970416D03*
X926477Y326110D03*
X933237D03*
X939997D03*
X946757D03*
X953517D03*
X960276D03*
X967036D03*
X923097Y324160D03*
X929857D03*
X936617D03*
X943377D03*
X950137D03*
X956897D03*
X963656D03*
X970416D03*
X926477Y322209D03*
X933237D03*
X939997D03*
X946757D03*
X953517D03*
X960276D03*
X967036D03*
X923097Y320260D03*
X929857D03*
X936617D03*
X943377D03*
X950137D03*
X956897D03*
X963656D03*
X970416D03*
X926477Y318309D03*
X933237D03*
X939997D03*
X946757D03*
X953517D03*
X960276D03*
X967036D03*
X929857Y316360D03*
X936617D03*
X943377D03*
X950137D03*
X956897D03*
X963656D03*
X970416D03*
X926477Y314409D03*
X933237D03*
X939997D03*
X946757D03*
X953517D03*
X960276D03*
X967036D03*
X929857Y312460D03*
X936617D03*
X943377D03*
X950137D03*
X956897D03*
X963656D03*
X970416D03*
X926477Y310509D03*
X933237D03*
X939997D03*
X946757D03*
X953517D03*
X960276D03*
X967036D03*
X929857Y308560D03*
X936617D03*
X943377D03*
X950137D03*
X956897D03*
X963656D03*
X970416D03*
X926477Y306609D03*
X933237D03*
X939997D03*
X946757D03*
X953517D03*
X960276D03*
X967036D03*
X929857Y304660D03*
X936617D03*
X943377D03*
X950137D03*
X956897D03*
X963656D03*
X970416D03*
X926477Y302709D03*
X933237D03*
X939997D03*
X946757D03*
X953517D03*
X960276D03*
X967036D03*
X929857Y300760D03*
X936617D03*
X943377D03*
X950137D03*
X956897D03*
X963656D03*
X970416D03*
X926477Y298809D03*
X933237D03*
X939997D03*
X946757D03*
X953517D03*
X960276D03*
X967036D03*
X929857Y296860D03*
X936617D03*
X943377D03*
X950137D03*
X956897D03*
X963656D03*
X970416D03*
X926477Y294909D03*
X933237D03*
X939997D03*
X946757D03*
X953517D03*
X960276D03*
X967036D03*
X929857Y292959D03*
X936617D03*
X943377D03*
X950137D03*
X956897D03*
X963656D03*
X970416D03*
X926477Y291009D03*
X933237D03*
X939997D03*
X946757D03*
X953517D03*
X960276D03*
X967036D03*
X929857Y289060D03*
X936617D03*
X943377D03*
X950137D03*
X956897D03*
X963656D03*
X970416D03*
X926477Y287109D03*
X933237D03*
X939997D03*
X946757D03*
X953517D03*
X960276D03*
X967036D03*
X929857Y285160D03*
X936617D03*
X943377D03*
X950137D03*
X956897D03*
X963656D03*
X970416D03*
X926477Y283209D03*
X933237D03*
X939997D03*
X946757D03*
X953517D03*
X960276D03*
X967036D03*
X923097Y281260D03*
X929857D03*
X936617D03*
X943377D03*
X950137D03*
X956897D03*
X963656D03*
X970416D03*
X943377Y398260D03*
X950137D03*
X956897D03*
X963656D03*
X939997Y396309D03*
X946757D03*
X953517D03*
X960276D03*
X967036D03*
X936617Y394359D03*
X943377D03*
X950137D03*
X956897D03*
X963656D03*
X970416D03*
X933237Y392410D03*
X939997D03*
X946757D03*
X953517D03*
X960276D03*
X967036D03*
X929857Y390460D03*
X936617D03*
X943377D03*
X950137D03*
X956897D03*
X963656D03*
X970416D03*
X926477Y388509D03*
X933237D03*
X939997D03*
X946757D03*
X953517D03*
X960276D03*
X967036D03*
X923097Y386560D03*
X929857D03*
X936617D03*
X943377D03*
X950137D03*
X956897D03*
X963656D03*
X970416D03*
X926477Y384609D03*
X933237D03*
X939997D03*
X946757D03*
X953517D03*
X960276D03*
X967036D03*
X923097Y382660D03*
X929857D03*
X936617D03*
X943377D03*
X950137D03*
X956897D03*
X963656D03*
X970416D03*
X926477Y380709D03*
X933237D03*
X939997D03*
X946757D03*
X953517D03*
X960276D03*
X967036D03*
X923097Y378760D03*
X929857D03*
X936617D03*
X943377D03*
X950137D03*
X956897D03*
X963656D03*
X970416D03*
X926477Y376809D03*
X933237D03*
X939997D03*
X946757D03*
X953517D03*
X960276D03*
X967036D03*
X923097Y374860D03*
X929857D03*
X936617D03*
X943377D03*
X950137D03*
X956897D03*
X963656D03*
X970416D03*
X923097Y370959D03*
X929857D03*
X936617D03*
X943377D03*
X950137D03*
X956897D03*
X963656D03*
X970416D03*
X926477Y369010D03*
X933237D03*
X939997D03*
X946757D03*
X953517D03*
X960276D03*
X967036D03*
X923097Y367060D03*
X929857D03*
X936617D03*
X943377D03*
X950137D03*
X956897D03*
X963656D03*
X970416D03*
X926477Y365109D03*
X933237D03*
X939997D03*
X946757D03*
X953517D03*
X960276D03*
X967036D03*
X923097Y363160D03*
X929857D03*
X936617D03*
X943377D03*
X950137D03*
X956897D03*
X963656D03*
X970416D03*
X926477Y361209D03*
X933237D03*
X939997D03*
X946757D03*
X953517D03*
X960276D03*
X967036D03*
X923097Y359260D03*
X929857D03*
X936617D03*
X943377D03*
X950137D03*
X956897D03*
X963656D03*
X970416D03*
X926477Y357309D03*
X933237D03*
X939997D03*
X946757D03*
X953517D03*
X960276D03*
X967036D03*
X923097Y355360D03*
X929857D03*
X936617D03*
X943377D03*
X950137D03*
X956897D03*
X963656D03*
X970416D03*
X919717Y353409D03*
X926477D03*
X933237D03*
X939997D03*
X946757D03*
X953517D03*
X960276D03*
X967036D03*
X923097Y351460D03*
X929857D03*
X936617D03*
X943377D03*
X950137D03*
X956897D03*
X963656D03*
X970416D03*
X919717Y349509D03*
X926477D03*
X933237D03*
X939997D03*
X946757D03*
X953517D03*
X960276D03*
X967036D03*
X923097Y347560D03*
X929857D03*
X936617D03*
X943377D03*
X950137D03*
X956897D03*
X963656D03*
X919717Y345609D03*
X926477D03*
X933237D03*
X939997D03*
X946757D03*
X953517D03*
X960276D03*
X923097Y343660D03*
X929857D03*
X936617D03*
X943377D03*
X950137D03*
X956897D03*
X926477Y372909D03*
X933237D03*
X939997D03*
X946757D03*
X953517D03*
X960276D03*
X967036D03*
X973796Y216909D03*
X980556D03*
X987316D03*
X994076D03*
X1000836D03*
X1007595D03*
X1014355D03*
X1021115D03*
X1027875D03*
X977176Y214960D03*
X983936D03*
X990696D03*
X997456D03*
X1004215D03*
X1010975D03*
X1017735D03*
X1024495D03*
X1031255D03*
X973796Y213009D03*
X980556D03*
X987316D03*
X994076D03*
X1000836D03*
X1007595D03*
X1014355D03*
X1021115D03*
X1027875D03*
X977176Y211060D03*
X983936D03*
X990696D03*
X997456D03*
X1004215D03*
X1010975D03*
X1017735D03*
X1024495D03*
X1031255D03*
X973796Y209109D03*
X980556D03*
X987316D03*
X994076D03*
X1000836D03*
X1007595D03*
X1014355D03*
X1021115D03*
X1027875D03*
X977176Y207159D03*
X983936D03*
X990696D03*
X997456D03*
X1004215D03*
X1010975D03*
X1017735D03*
X1024495D03*
X1031255D03*
X987316Y205210D03*
X994076D03*
X1000836D03*
X1007595D03*
X1014355D03*
X1021115D03*
X1027875D03*
X990696Y203260D03*
X997456D03*
X1004215D03*
X1010975D03*
X1017735D03*
X1024495D03*
X1031255D03*
X994076Y201309D03*
X1000836D03*
X1007595D03*
X1014355D03*
X1021115D03*
X1027875D03*
X997456Y199360D03*
X1004215D03*
X1010975D03*
X1017735D03*
X1024495D03*
X1031255D03*
X973796Y232509D03*
X980556D03*
X987316D03*
X994076D03*
X1000836D03*
X1007595D03*
X1014355D03*
X1021115D03*
X1027875D03*
X977176Y230559D03*
X983936D03*
X990696D03*
X997456D03*
X1004215D03*
X1010975D03*
X1017735D03*
X1024495D03*
X1031255D03*
X973796Y228610D03*
X980556D03*
X987316D03*
X994076D03*
X1000836D03*
X1007595D03*
X1014355D03*
X1021115D03*
X1027875D03*
X977176Y226660D03*
X983936D03*
X990696D03*
X997456D03*
X1004215D03*
X1010975D03*
X1017735D03*
X1024495D03*
X1031255D03*
X973796Y224709D03*
X980556D03*
X987316D03*
X994076D03*
X1000836D03*
X1007595D03*
X1014355D03*
X1021115D03*
X1027875D03*
X973796Y220809D03*
X980556D03*
X987316D03*
X994076D03*
X1000836D03*
X1007595D03*
X1014355D03*
X1021115D03*
X1027875D03*
X977176Y218860D03*
X983936D03*
X990696D03*
X997456D03*
X1004215D03*
X1010975D03*
X1017735D03*
X1024495D03*
X1031255D03*
X973796Y279310D03*
X980556D03*
X987316D03*
X994076D03*
X1000836D03*
X977176Y277360D03*
X983936D03*
X990696D03*
X997456D03*
X973796Y275409D03*
X980556D03*
X987316D03*
X994076D03*
X1000836D03*
X977176Y273460D03*
X983936D03*
X990696D03*
X997456D03*
X973796Y271509D03*
X980556D03*
X987316D03*
X994076D03*
X1000836D03*
X977176Y269560D03*
X983936D03*
X990696D03*
X997456D03*
X973796Y267609D03*
X980556D03*
X987316D03*
X994076D03*
X1000836D03*
X977176Y265660D03*
X983936D03*
X990696D03*
X997456D03*
X1004215D03*
X973796Y263709D03*
X980556D03*
X987316D03*
X994076D03*
X1000836D03*
X1007595D03*
X977176Y261760D03*
X983936D03*
X990696D03*
X997456D03*
X1004215D03*
X1010975D03*
X973796Y259809D03*
X980556D03*
X987316D03*
X994076D03*
X1000836D03*
X1007595D03*
X1014355D03*
X977176Y257860D03*
X983936D03*
X990696D03*
X997456D03*
X1004215D03*
X1010975D03*
X1017735D03*
X973796Y255909D03*
X980556D03*
X987316D03*
X994076D03*
X1000836D03*
X1007595D03*
X1014355D03*
X1021115D03*
X977176Y253960D03*
X983936D03*
X990696D03*
X997456D03*
X1004215D03*
X1010975D03*
X1017735D03*
X1024495D03*
X973796Y252009D03*
X980556D03*
X987316D03*
X994076D03*
X1000836D03*
X1007595D03*
X1014355D03*
X1021115D03*
X1027875D03*
X977176Y250060D03*
X983936D03*
X990696D03*
X997456D03*
X1004215D03*
X1010975D03*
X1017735D03*
X1024495D03*
X1031255D03*
X973796Y248109D03*
X980556D03*
X987316D03*
X994076D03*
X1000836D03*
X1007595D03*
X1014355D03*
X1021115D03*
X1027875D03*
X977176Y246160D03*
X983936D03*
X990696D03*
X997456D03*
X1004215D03*
X1010975D03*
X1017735D03*
X1024495D03*
X1031255D03*
X973796Y244209D03*
X980556D03*
X987316D03*
X994076D03*
X1000836D03*
X1007595D03*
X1014355D03*
X1021115D03*
X1027875D03*
X977176Y242260D03*
X983936D03*
X990696D03*
X997456D03*
X1004215D03*
X1010975D03*
X1017735D03*
X1024495D03*
X1031255D03*
X973796Y240309D03*
X980556D03*
X987316D03*
X994076D03*
X1000836D03*
X1007595D03*
X1014355D03*
X1021115D03*
X1027875D03*
X977176Y238360D03*
X983936D03*
X990696D03*
X997456D03*
X1004215D03*
X1010975D03*
X1017735D03*
X1024495D03*
X1031255D03*
X973796Y236409D03*
X980556D03*
X987316D03*
X994076D03*
X1000836D03*
X1007595D03*
X1014355D03*
X1021115D03*
X1027875D03*
X977176Y234460D03*
X983936D03*
X990696D03*
X997456D03*
X1004215D03*
X1010975D03*
X1017735D03*
X1024495D03*
X1031255D03*
X977176Y222760D03*
X983936D03*
X990696D03*
X997456D03*
X1004215D03*
X1010975D03*
X1017735D03*
X1024495D03*
X1031255D03*
X973796Y341709D03*
X980556D03*
X987316D03*
X994076D03*
X1000836D03*
X1007595D03*
X1014355D03*
X1021115D03*
X977176Y339760D03*
X983936D03*
X990696D03*
X997456D03*
X1004215D03*
X1010975D03*
X1017735D03*
X973796Y337809D03*
X980556D03*
X987316D03*
X994076D03*
X1000836D03*
X1007595D03*
X1014355D03*
X977176Y335860D03*
X983936D03*
X990696D03*
X997456D03*
X1004215D03*
X1010975D03*
X973796Y333909D03*
X980556D03*
X987316D03*
X994076D03*
X1000836D03*
X1007595D03*
X977176Y331960D03*
X983936D03*
X990696D03*
X997456D03*
X1004215D03*
X973796Y330009D03*
X980556D03*
X987316D03*
X994076D03*
X1000836D03*
X977176Y328060D03*
X983936D03*
X990696D03*
X997456D03*
X973796Y326110D03*
X980556D03*
X987316D03*
X994076D03*
X1000836D03*
X977176Y324160D03*
X983936D03*
X990696D03*
X997456D03*
X973796Y322209D03*
X980556D03*
X987316D03*
X994076D03*
X1000836D03*
X977176Y320260D03*
X983936D03*
X990696D03*
X997456D03*
X973796Y318309D03*
X980556D03*
X987316D03*
X994076D03*
X1000836D03*
X977176Y316360D03*
X983936D03*
X990696D03*
X997456D03*
X973796Y314409D03*
X980556D03*
X987316D03*
X994076D03*
X1000836D03*
X977176Y312460D03*
X983936D03*
X990696D03*
X997456D03*
X973796Y310509D03*
X980556D03*
X987316D03*
X994076D03*
X1000836D03*
X977176Y308560D03*
X983936D03*
X990696D03*
X997456D03*
X973796Y306609D03*
X980556D03*
X987316D03*
X994076D03*
X1000836D03*
X977176Y304660D03*
X983936D03*
X990696D03*
X997456D03*
X973796Y302709D03*
X980556D03*
X987316D03*
X994076D03*
X1000836D03*
X977176Y300760D03*
X983936D03*
X990696D03*
X997456D03*
X973796Y298809D03*
X980556D03*
X987316D03*
X994076D03*
X1000836D03*
X977176Y296860D03*
X983936D03*
X990696D03*
X997456D03*
X973796Y294909D03*
X980556D03*
X987316D03*
X994076D03*
X1000836D03*
X977176Y292959D03*
X983936D03*
X990696D03*
X997456D03*
X973796Y291009D03*
X980556D03*
X987316D03*
X994076D03*
X1000836D03*
X977176Y289060D03*
X983936D03*
X990696D03*
X997456D03*
X973796Y287109D03*
X980556D03*
X987316D03*
X994076D03*
X1000836D03*
X977176Y285160D03*
X983936D03*
X990696D03*
X997456D03*
X973796Y283209D03*
X980556D03*
X987316D03*
X994076D03*
X1000836D03*
X977176Y281260D03*
X983936D03*
X990696D03*
X997456D03*
Y398260D03*
X1004215D03*
X1010975D03*
X1017735D03*
X1024495D03*
X1031255D03*
X1000836Y396309D03*
X1007595D03*
X1014355D03*
X1021115D03*
X1027875D03*
X997456Y394359D03*
X1004215D03*
X1010975D03*
X1017735D03*
X1024495D03*
X1031255D03*
X1000836Y392410D03*
X1007595D03*
X1014355D03*
X1021115D03*
X1027875D03*
X977176Y390460D03*
X983936D03*
X990696D03*
X997456D03*
X1004215D03*
X1010975D03*
X1017735D03*
X1024495D03*
X1031255D03*
X973796Y388509D03*
X980556D03*
X987316D03*
X994076D03*
X1000836D03*
X1007595D03*
X1014355D03*
X1021115D03*
X1027875D03*
X977176Y386560D03*
X983936D03*
X990696D03*
X997456D03*
X1004215D03*
X1010975D03*
X1017735D03*
X1024495D03*
X1031255D03*
X973796Y384609D03*
X980556D03*
X987316D03*
X994076D03*
X1000836D03*
X1007595D03*
X1014355D03*
X1021115D03*
X1027875D03*
X977176Y382660D03*
X983936D03*
X990696D03*
X997456D03*
X1004215D03*
X1010975D03*
X1017735D03*
X1024495D03*
X1031255D03*
X973796Y380709D03*
X980556D03*
X987316D03*
X994076D03*
X1000836D03*
X1007595D03*
X1014355D03*
X1021115D03*
X1027875D03*
X977176Y378760D03*
X983936D03*
X990696D03*
X997456D03*
X1004215D03*
X1010975D03*
X1017735D03*
X1024495D03*
X1031255D03*
X973796Y376809D03*
X980556D03*
X987316D03*
X994076D03*
X1000836D03*
X1007595D03*
X1014355D03*
X1021115D03*
X1027875D03*
X977176Y374860D03*
X983936D03*
X990696D03*
X997456D03*
X1004215D03*
X1010975D03*
X1017735D03*
X1024495D03*
X1031255D03*
X977176Y370959D03*
X983936D03*
X990696D03*
X997456D03*
X1004215D03*
X1010975D03*
X1017735D03*
X1024495D03*
X1031255D03*
X973796Y369010D03*
X980556D03*
X987316D03*
X994076D03*
X1000836D03*
X1007595D03*
X1014355D03*
X1021115D03*
X1027875D03*
X977176Y367060D03*
X983936D03*
X990696D03*
X997456D03*
X1004215D03*
X1010975D03*
X1017735D03*
X1024495D03*
X1031255D03*
X973796Y365109D03*
X980556D03*
X987316D03*
X994076D03*
X1000836D03*
X1007595D03*
X1014355D03*
X1021115D03*
X1027875D03*
X977176Y363160D03*
X983936D03*
X990696D03*
X997456D03*
X1004215D03*
X1010975D03*
X1017735D03*
X1024495D03*
X1031255D03*
X973796Y361209D03*
X980556D03*
X987316D03*
X994076D03*
X1000836D03*
X1007595D03*
X1014355D03*
X1021115D03*
X1027875D03*
X977176Y359260D03*
X983936D03*
X990696D03*
X997456D03*
X1004215D03*
X1010975D03*
X1017735D03*
X1024495D03*
X1031255D03*
X973796Y357309D03*
X980556D03*
X987316D03*
X994076D03*
X1000836D03*
X1007595D03*
X1014355D03*
X1021115D03*
X1027875D03*
X977176Y355360D03*
X983936D03*
X990696D03*
X997456D03*
X1004215D03*
X1010975D03*
X1017735D03*
X1024495D03*
X1031255D03*
X973796Y353409D03*
X980556D03*
X987316D03*
X994076D03*
X1000836D03*
X1007595D03*
X1014355D03*
X1021115D03*
X1027875D03*
X977176Y351460D03*
X983936D03*
X990696D03*
X997456D03*
X1004215D03*
X1010975D03*
X1017735D03*
X1024495D03*
X1031255D03*
X973796Y349509D03*
X980556D03*
X987316D03*
X994076D03*
X1000836D03*
X1007595D03*
X1014355D03*
X1021115D03*
X1027875D03*
X977176Y347560D03*
X983936D03*
X990696D03*
X997456D03*
X1004215D03*
X1010975D03*
X1017735D03*
X1024495D03*
X1031255D03*
X973796Y345609D03*
X980556D03*
X987316D03*
X994076D03*
X1000836D03*
X1007595D03*
X1014355D03*
X1021115D03*
X1027875D03*
X977176Y343660D03*
X983936D03*
X990696D03*
X997456D03*
X1004215D03*
X1010975D03*
X1017735D03*
X1024495D03*
X973796Y372909D03*
X980556D03*
X987316D03*
X994076D03*
X1000836D03*
X1007595D03*
X1014355D03*
X1021115D03*
X1027875D03*
X1034635Y216909D03*
X1041395D03*
X1048154D03*
X1038015Y214960D03*
X1044774D03*
X1051534D03*
X1034635Y213009D03*
X1041395D03*
X1048154D03*
X1038015Y211060D03*
X1044774D03*
X1051534D03*
X1071072Y218147D03*
X1077832D03*
X1084591D03*
X1091351D03*
X1034635Y209109D03*
X1041395D03*
X1048154D03*
X1067692Y216196D03*
X1074452D03*
X1081212D03*
X1087971D03*
X1094731D03*
X1038015Y207159D03*
X1044774D03*
X1051534D03*
X1071072Y214247D03*
X1077832D03*
X1084591D03*
X1091351D03*
X1034635Y205210D03*
X1041395D03*
X1048154D03*
X1067692Y212296D03*
X1074452D03*
X1081212D03*
X1087971D03*
X1094731D03*
X1038015Y203260D03*
X1044774D03*
X1051534D03*
X1071072Y210346D03*
X1077832D03*
X1084591D03*
X1091351D03*
X1034635Y201309D03*
X1041395D03*
X1048154D03*
X1067692Y208397D03*
X1074452D03*
X1081212D03*
X1087971D03*
X1094731D03*
X1038015Y199360D03*
X1044774D03*
X1071072Y206447D03*
X1077832D03*
X1084591D03*
X1091351D03*
X1074452Y204496D03*
X1081212D03*
X1087971D03*
X1094731D03*
X1034635Y232509D03*
X1041395D03*
X1048154D03*
X1067692Y239596D03*
X1074452D03*
X1081212D03*
X1087971D03*
X1094731D03*
X1038015Y230559D03*
X1044774D03*
X1051534D03*
X1071072Y237647D03*
X1077832D03*
X1084591D03*
X1091351D03*
X1034635Y228610D03*
X1041395D03*
X1048154D03*
X1067692Y235696D03*
X1074452D03*
X1081212D03*
X1087971D03*
X1094731D03*
X1038015Y226660D03*
X1044774D03*
X1051534D03*
X1071072Y233746D03*
X1077832D03*
X1084591D03*
X1091351D03*
X1034635Y224709D03*
X1041395D03*
X1048154D03*
X1067692Y231797D03*
X1074452D03*
X1081212D03*
X1087971D03*
X1094731D03*
X1034635Y220809D03*
X1041395D03*
X1048154D03*
X1067692Y227896D03*
X1074452D03*
X1081212D03*
X1087971D03*
X1094731D03*
X1038015Y218860D03*
X1044774D03*
X1051534D03*
X1071072Y225947D03*
X1077832D03*
X1084591D03*
X1091351D03*
X1067692Y223996D03*
X1074452D03*
X1081212D03*
X1087971D03*
X1094731D03*
X1071072Y222047D03*
X1077832D03*
X1084591D03*
X1091351D03*
X1067692Y220096D03*
X1074452D03*
X1081212D03*
X1087971D03*
X1094731D03*
X1034635Y252009D03*
X1041395D03*
X1048154D03*
X1094731Y259096D03*
X1038015Y250060D03*
X1044774D03*
X1051534D03*
X1091351Y257147D03*
X1034635Y248109D03*
X1041395D03*
X1048154D03*
X1074452Y255196D03*
X1081212D03*
X1087971D03*
X1094731D03*
X1038015Y246160D03*
X1044774D03*
X1051534D03*
X1071072Y253247D03*
X1077832D03*
X1084591D03*
X1091351D03*
X1034635Y244209D03*
X1041395D03*
X1048154D03*
X1067692Y251296D03*
X1074452D03*
X1081212D03*
X1087971D03*
X1094731D03*
X1038015Y242260D03*
X1044774D03*
X1051534D03*
X1071072Y249347D03*
X1077832D03*
X1084591D03*
X1091351D03*
X1034635Y240309D03*
X1041395D03*
X1048154D03*
X1067692Y247396D03*
X1074452D03*
X1081212D03*
X1087971D03*
X1094731D03*
X1038015Y238360D03*
X1044774D03*
X1051534D03*
X1071072Y245447D03*
X1077832D03*
X1084591D03*
X1091351D03*
X1034635Y236409D03*
X1041395D03*
X1048154D03*
X1067692Y243496D03*
X1074452D03*
X1081212D03*
X1087971D03*
X1094731D03*
X1038015Y234460D03*
X1044774D03*
X1051534D03*
X1071072Y241547D03*
X1077832D03*
X1084591D03*
X1091351D03*
X1038015Y222760D03*
X1044774D03*
X1051534D03*
X1071072Y229847D03*
X1077832D03*
X1084591D03*
X1091351D03*
X1038015Y398260D03*
X1044774D03*
X1051534D03*
X1034635Y396309D03*
X1041395D03*
X1048154D03*
X1054914D03*
X1081212Y403396D03*
X1087971D03*
X1094731D03*
X1038015Y394359D03*
X1044774D03*
X1051534D03*
X1077832Y401447D03*
X1084591D03*
X1091351D03*
X1034635Y392410D03*
X1041395D03*
X1048154D03*
X1054914D03*
X1074452Y399496D03*
X1081212D03*
X1087971D03*
X1094731D03*
X1038015Y390460D03*
X1044774D03*
X1051534D03*
X1071072Y397546D03*
X1077832D03*
X1084591D03*
X1091351D03*
X1034635Y388509D03*
X1041395D03*
X1048154D03*
X1054914D03*
X1074452Y395597D03*
X1081212D03*
X1087971D03*
X1094731D03*
X1038015Y386560D03*
X1044774D03*
X1051534D03*
X1071072Y393647D03*
X1077832D03*
X1084591D03*
X1091351D03*
X1034635Y384609D03*
X1041395D03*
X1048154D03*
X1054914D03*
X1074452Y391696D03*
X1081212D03*
X1087971D03*
X1094731D03*
X1038015Y382660D03*
X1044774D03*
X1051534D03*
X1071072Y389747D03*
X1077832D03*
X1084591D03*
X1091351D03*
X1034635Y380709D03*
X1041395D03*
X1048154D03*
X1054914D03*
X1074452Y387796D03*
X1081212D03*
X1087971D03*
X1094731D03*
X1038015Y378760D03*
X1044774D03*
X1051534D03*
X1071072Y385847D03*
X1077832D03*
X1084591D03*
X1091351D03*
X1034635Y376809D03*
X1041395D03*
X1048154D03*
X1054914D03*
X1074452Y383896D03*
X1081212D03*
X1087971D03*
X1094731D03*
X1038015Y374860D03*
X1044774D03*
X1051534D03*
X1071072Y381947D03*
X1077832D03*
X1084591D03*
X1091351D03*
X1038015Y370959D03*
X1044774D03*
X1051534D03*
X1071072Y378047D03*
X1077832D03*
X1084591D03*
X1091351D03*
X1034635Y369010D03*
X1041395D03*
X1048154D03*
X1054914D03*
X1074452Y376096D03*
X1081212D03*
X1087971D03*
X1094731D03*
X1038015Y367060D03*
X1044774D03*
X1051534D03*
X1071072Y374146D03*
X1077832D03*
X1084591D03*
X1091351D03*
X1034635Y365109D03*
X1041395D03*
X1048154D03*
X1054914D03*
X1074452Y372197D03*
X1081212D03*
X1087971D03*
X1094731D03*
X1038015Y363160D03*
X1044774D03*
X1051534D03*
X1071072Y370247D03*
X1077832D03*
X1084591D03*
X1091351D03*
X1034635Y361209D03*
X1041395D03*
X1048154D03*
X1054914D03*
X1074452Y368296D03*
X1081212D03*
X1087971D03*
X1094731D03*
X1038015Y359260D03*
X1044774D03*
X1051534D03*
X1071072Y366347D03*
X1077832D03*
X1084591D03*
X1091351D03*
X1034635Y357309D03*
X1041395D03*
X1048154D03*
X1054914D03*
X1074452Y364396D03*
X1081212D03*
X1087971D03*
X1094731D03*
X1038015Y355360D03*
X1044774D03*
X1051534D03*
X1071072Y362447D03*
X1077832D03*
X1084591D03*
X1091351D03*
X1034635Y353409D03*
X1041395D03*
X1048154D03*
X1054914D03*
X1074452Y360496D03*
X1081212D03*
X1087971D03*
X1094731D03*
X1038015Y351460D03*
X1044774D03*
X1051534D03*
X1071072Y358547D03*
X1077832D03*
X1084591D03*
X1091351D03*
X1034635Y349509D03*
X1041395D03*
X1048154D03*
X1074452Y356596D03*
X1081212D03*
X1087971D03*
X1094731D03*
X1071072Y354647D03*
X1077832D03*
X1084591D03*
X1091351D03*
X1074452Y352696D03*
X1081212D03*
X1087971D03*
X1094731D03*
X1071072Y350747D03*
X1077832D03*
X1084591D03*
X1091351D03*
X1074452Y348796D03*
X1081212D03*
X1087971D03*
X1094731D03*
X1034635Y372909D03*
X1041395D03*
X1048154D03*
X1054914D03*
X1074452Y379996D03*
X1081212D03*
X1087971D03*
X1094731D03*
X1098111Y218147D03*
X1104871D03*
X1111631D03*
X1118391D03*
X1125150D03*
X1131910D03*
X1138670D03*
X1145430D03*
X1152190D03*
X1101491Y216196D03*
X1108251D03*
X1115011D03*
X1121771D03*
X1128530D03*
X1135290D03*
X1142050D03*
X1148810D03*
X1155570D03*
X1098111Y214247D03*
X1104871D03*
X1111631D03*
X1118391D03*
X1125150D03*
X1131910D03*
X1138670D03*
X1145430D03*
X1152190D03*
X1101491Y212296D03*
X1108251D03*
X1115011D03*
X1121771D03*
X1128530D03*
X1135290D03*
X1142050D03*
X1148810D03*
X1155570D03*
X1098111Y210346D03*
X1104871D03*
X1111631D03*
X1118391D03*
X1125150D03*
X1101491Y208397D03*
X1108251D03*
X1115011D03*
X1121771D03*
X1128530D03*
X1155570D03*
X1098111Y206447D03*
X1104871D03*
X1111631D03*
X1118391D03*
X1125150D03*
X1101491Y204496D03*
X1108251D03*
X1115011D03*
X1121771D03*
X1128530D03*
X1101491Y239596D03*
X1108251D03*
X1115011D03*
X1121771D03*
X1128530D03*
X1135290D03*
X1142050D03*
X1148810D03*
X1155570D03*
X1098111Y237647D03*
X1104871D03*
X1111631D03*
X1118391D03*
X1125150D03*
X1131910D03*
X1138670D03*
X1145430D03*
X1152190D03*
X1101491Y235696D03*
X1108251D03*
X1115011D03*
X1121771D03*
X1128530D03*
X1135290D03*
X1142050D03*
X1148810D03*
X1155570D03*
X1098111Y233746D03*
X1104871D03*
X1111631D03*
X1118391D03*
X1125150D03*
X1131910D03*
X1138670D03*
X1145430D03*
X1152190D03*
X1101491Y231797D03*
X1108251D03*
X1115011D03*
X1121771D03*
X1128530D03*
X1135290D03*
X1142050D03*
X1148810D03*
X1155570D03*
X1101491Y227896D03*
X1108251D03*
X1115011D03*
X1121771D03*
X1128530D03*
X1135290D03*
X1142050D03*
X1148810D03*
X1155570D03*
X1098111Y225947D03*
X1104871D03*
X1111631D03*
X1118391D03*
X1125150D03*
X1131910D03*
X1138670D03*
X1145430D03*
X1152190D03*
X1101491Y223996D03*
X1108251D03*
X1115011D03*
X1121771D03*
X1128530D03*
X1135290D03*
X1142050D03*
X1148810D03*
X1155570D03*
X1098111Y222047D03*
X1104871D03*
X1111631D03*
X1118391D03*
X1125150D03*
X1131910D03*
X1138670D03*
X1145430D03*
X1152190D03*
X1101491Y220096D03*
X1108251D03*
X1115011D03*
X1121771D03*
X1128530D03*
X1135290D03*
X1142050D03*
X1148810D03*
X1155570D03*
X1121771Y278596D03*
X1128530D03*
X1135290D03*
X1142050D03*
X1148810D03*
X1155570D03*
X1125150Y276646D03*
X1131910D03*
X1138670D03*
X1145430D03*
X1152190D03*
X1121771Y274696D03*
X1128530D03*
X1135290D03*
X1142050D03*
X1148810D03*
X1155570D03*
X1118391Y272747D03*
X1125150D03*
X1131910D03*
X1138670D03*
X1145430D03*
X1152190D03*
X1115011Y270796D03*
X1121771D03*
X1128530D03*
X1135290D03*
X1142050D03*
X1148810D03*
X1155570D03*
X1111631Y268847D03*
X1118391D03*
X1125150D03*
X1131910D03*
X1138670D03*
X1145430D03*
X1152190D03*
X1108251Y266896D03*
X1115011D03*
X1121771D03*
X1128530D03*
X1135290D03*
X1142050D03*
X1148810D03*
X1155570D03*
X1104871Y264947D03*
X1111631D03*
X1118391D03*
X1125150D03*
X1131910D03*
X1138670D03*
X1145430D03*
X1152190D03*
X1101491Y262996D03*
X1108251D03*
X1115011D03*
X1121771D03*
X1128530D03*
X1135290D03*
X1142050D03*
X1148810D03*
X1098111Y261047D03*
X1104871D03*
X1111631D03*
X1118391D03*
X1125150D03*
X1131910D03*
X1138670D03*
X1145430D03*
X1152190D03*
X1101491Y259096D03*
X1108251D03*
X1115011D03*
X1121771D03*
X1128530D03*
X1135290D03*
X1142050D03*
X1148810D03*
X1098111Y257147D03*
X1104871D03*
X1111631D03*
X1118391D03*
X1125150D03*
X1131910D03*
X1138670D03*
X1145430D03*
X1152190D03*
X1101491Y255196D03*
X1108251D03*
X1115011D03*
X1121771D03*
X1128530D03*
X1135290D03*
X1142050D03*
X1148810D03*
X1098111Y253247D03*
X1104871D03*
X1111631D03*
X1118391D03*
X1125150D03*
X1131910D03*
X1138670D03*
X1145430D03*
X1152190D03*
X1101491Y251296D03*
X1108251D03*
X1115011D03*
X1121771D03*
X1128530D03*
X1135290D03*
X1142050D03*
X1148810D03*
X1155570D03*
X1098111Y249347D03*
X1104871D03*
X1111631D03*
X1118391D03*
X1125150D03*
X1131910D03*
X1138670D03*
X1145430D03*
X1152190D03*
X1101491Y247396D03*
X1108251D03*
X1115011D03*
X1121771D03*
X1128530D03*
X1135290D03*
X1142050D03*
X1148810D03*
X1155570D03*
X1098111Y245447D03*
X1104871D03*
X1111631D03*
X1118391D03*
X1125150D03*
X1131910D03*
X1138670D03*
X1145430D03*
X1152190D03*
X1101491Y243496D03*
X1108251D03*
X1115011D03*
X1121771D03*
X1128530D03*
X1135290D03*
X1142050D03*
X1148810D03*
X1155570D03*
X1098111Y241547D03*
X1104871D03*
X1111631D03*
X1118391D03*
X1125150D03*
X1131910D03*
X1138670D03*
X1145430D03*
X1152190D03*
X1098111Y229847D03*
X1104871D03*
X1111631D03*
X1118391D03*
X1125150D03*
X1131910D03*
X1138670D03*
X1145430D03*
X1152190D03*
X1108251Y340996D03*
X1115011D03*
X1121771D03*
X1128530D03*
X1135290D03*
X1142050D03*
X1148810D03*
X1111631Y339047D03*
X1118391D03*
X1125150D03*
X1131910D03*
X1138670D03*
X1145430D03*
X1152190D03*
X1115011Y337096D03*
X1121771D03*
X1128530D03*
X1135290D03*
X1142050D03*
X1148810D03*
X1155570D03*
X1118391Y335147D03*
X1125150D03*
X1131910D03*
X1138670D03*
X1145430D03*
X1152190D03*
X1121771Y333196D03*
X1128530D03*
X1135290D03*
X1142050D03*
X1148810D03*
X1155570D03*
X1125150Y331247D03*
X1131910D03*
X1138670D03*
X1145430D03*
X1152190D03*
X1121771Y329296D03*
X1128530D03*
X1135290D03*
X1142050D03*
X1148810D03*
X1155570D03*
X1125150Y327347D03*
X1131910D03*
X1138670D03*
X1145430D03*
X1152190D03*
X1121771Y325396D03*
X1128530D03*
X1135290D03*
X1142050D03*
X1148810D03*
X1155570D03*
X1125150Y323446D03*
X1131910D03*
X1138670D03*
X1145430D03*
X1152190D03*
X1121771Y321496D03*
X1128530D03*
X1135290D03*
X1142050D03*
X1148810D03*
X1155570D03*
X1125150Y319547D03*
X1131910D03*
X1138670D03*
X1145430D03*
X1152190D03*
X1121771Y317596D03*
X1128530D03*
X1135290D03*
X1142050D03*
X1148810D03*
X1155570D03*
X1125150Y315647D03*
X1131910D03*
X1138670D03*
X1145430D03*
X1152190D03*
X1121771Y313696D03*
X1128530D03*
X1135290D03*
X1142050D03*
X1148810D03*
X1155570D03*
X1125150Y311747D03*
X1131910D03*
X1138670D03*
X1145430D03*
X1152190D03*
X1121771Y309797D03*
X1128530D03*
X1135290D03*
X1142050D03*
X1148810D03*
X1155570D03*
X1125150Y307847D03*
X1131910D03*
X1138670D03*
X1145430D03*
X1152190D03*
X1121771Y305896D03*
X1128530D03*
X1135290D03*
X1142050D03*
X1148810D03*
X1155570D03*
X1125150Y303947D03*
X1131910D03*
X1138670D03*
X1145430D03*
X1152190D03*
X1121771Y301996D03*
X1128530D03*
X1135290D03*
X1142050D03*
X1148810D03*
X1155570D03*
X1125150Y300047D03*
X1131910D03*
X1138670D03*
X1145430D03*
X1152190D03*
X1121771Y298096D03*
X1128530D03*
X1135290D03*
X1142050D03*
X1148810D03*
X1155570D03*
X1125150Y296147D03*
X1131910D03*
X1138670D03*
X1145430D03*
X1152190D03*
X1121771Y294196D03*
X1128530D03*
X1135290D03*
X1142050D03*
X1148810D03*
X1155570D03*
X1125150Y292247D03*
X1131910D03*
X1138670D03*
X1145430D03*
X1152190D03*
X1121771Y290296D03*
X1128530D03*
X1135290D03*
X1142050D03*
X1148810D03*
X1155570D03*
X1125150Y288347D03*
X1131910D03*
X1138670D03*
X1145430D03*
X1152190D03*
X1121771Y286396D03*
X1128530D03*
X1135290D03*
X1142050D03*
X1148810D03*
X1155570D03*
X1125150Y284447D03*
X1131910D03*
X1138670D03*
X1145430D03*
X1152190D03*
X1121771Y282496D03*
X1128530D03*
X1135290D03*
X1142050D03*
X1148810D03*
X1155570D03*
X1125150Y280547D03*
X1131910D03*
X1138670D03*
X1145430D03*
X1152190D03*
X1101491Y403396D03*
X1108251D03*
X1115011D03*
X1121771D03*
X1128530D03*
X1098111Y401447D03*
X1104871D03*
X1111631D03*
X1118391D03*
X1125150D03*
X1131910D03*
X1101491Y399496D03*
X1108251D03*
X1115011D03*
X1121771D03*
X1128530D03*
X1135290D03*
X1098111Y397546D03*
X1104871D03*
X1111631D03*
X1118391D03*
X1125150D03*
X1131910D03*
X1138670D03*
X1101491Y395597D03*
X1108251D03*
X1115011D03*
X1121771D03*
X1128530D03*
X1135290D03*
X1142050D03*
X1148810D03*
X1155570D03*
X1098111Y393647D03*
X1104871D03*
X1111631D03*
X1118391D03*
X1125150D03*
X1131910D03*
X1138670D03*
X1145430D03*
X1152190D03*
X1101491Y391696D03*
X1108251D03*
X1115011D03*
X1121771D03*
X1128530D03*
X1135290D03*
X1142050D03*
X1148810D03*
X1155570D03*
X1098111Y389747D03*
X1104871D03*
X1111631D03*
X1118391D03*
X1125150D03*
X1131910D03*
X1138670D03*
X1145430D03*
X1152190D03*
X1101491Y387796D03*
X1108251D03*
X1115011D03*
X1121771D03*
X1128530D03*
X1135290D03*
X1142050D03*
X1148810D03*
X1155570D03*
X1098111Y385847D03*
X1104871D03*
X1111631D03*
X1118391D03*
X1125150D03*
X1131910D03*
X1138670D03*
X1145430D03*
X1152190D03*
X1101491Y383896D03*
X1108251D03*
X1115011D03*
X1121771D03*
X1128530D03*
X1135290D03*
X1142050D03*
X1148810D03*
X1155570D03*
X1098111Y381947D03*
X1104871D03*
X1111631D03*
X1118391D03*
X1125150D03*
X1131910D03*
X1138670D03*
X1145430D03*
X1152190D03*
X1098111Y378047D03*
X1104871D03*
X1111631D03*
X1118391D03*
X1125150D03*
X1131910D03*
X1138670D03*
X1145430D03*
X1152190D03*
X1101491Y376096D03*
X1108251D03*
X1115011D03*
X1121771D03*
X1128530D03*
X1135290D03*
X1142050D03*
X1148810D03*
X1155570D03*
X1098111Y374146D03*
X1104871D03*
X1111631D03*
X1118391D03*
X1125150D03*
X1131910D03*
X1138670D03*
X1145430D03*
X1152190D03*
X1101491Y372197D03*
X1108251D03*
X1115011D03*
X1121771D03*
X1128530D03*
X1135290D03*
X1142050D03*
X1148810D03*
X1155570D03*
X1098111Y370247D03*
X1104871D03*
X1111631D03*
X1118391D03*
X1125150D03*
X1131910D03*
X1138670D03*
X1145430D03*
X1152190D03*
X1101491Y368296D03*
X1108251D03*
X1115011D03*
X1121771D03*
X1128530D03*
X1135290D03*
X1142050D03*
X1148810D03*
X1155570D03*
X1098111Y366347D03*
X1104871D03*
X1111631D03*
X1118391D03*
X1125150D03*
X1131910D03*
X1138670D03*
X1145430D03*
X1152190D03*
X1101491Y364396D03*
X1108251D03*
X1115011D03*
X1121771D03*
X1128530D03*
X1135290D03*
X1142050D03*
X1148810D03*
X1155570D03*
X1098111Y362447D03*
X1104871D03*
X1111631D03*
X1118391D03*
X1125150D03*
X1131910D03*
X1138670D03*
X1145430D03*
X1152190D03*
X1101491Y360496D03*
X1108251D03*
X1115011D03*
X1121771D03*
X1128530D03*
X1135290D03*
X1142050D03*
X1148810D03*
X1155570D03*
X1098111Y358547D03*
X1104871D03*
X1111631D03*
X1118391D03*
X1125150D03*
X1131910D03*
X1138670D03*
X1145430D03*
X1152190D03*
X1101491Y356596D03*
X1108251D03*
X1115011D03*
X1121771D03*
X1128530D03*
X1135290D03*
X1142050D03*
X1148810D03*
X1155570D03*
X1098111Y354647D03*
X1104871D03*
X1111631D03*
X1118391D03*
X1125150D03*
X1131910D03*
X1138670D03*
X1145430D03*
X1152190D03*
X1101491Y352696D03*
X1108251D03*
X1115011D03*
X1121771D03*
X1128530D03*
X1135290D03*
X1142050D03*
X1148810D03*
X1155570D03*
X1098111Y350747D03*
X1104871D03*
X1111631D03*
X1118391D03*
X1125150D03*
X1131910D03*
X1138670D03*
X1145430D03*
X1152190D03*
X1101491Y348796D03*
X1108251D03*
X1115011D03*
X1121771D03*
X1128530D03*
X1135290D03*
X1142050D03*
X1148810D03*
X1098111Y346847D03*
X1104871D03*
X1111631D03*
X1118391D03*
X1125150D03*
X1131910D03*
X1138670D03*
X1145430D03*
X1152190D03*
X1101491Y344896D03*
X1108251D03*
X1115011D03*
X1121771D03*
X1128530D03*
X1135290D03*
X1142050D03*
X1148810D03*
X1104871Y342947D03*
X1111631D03*
X1118391D03*
X1125150D03*
X1131910D03*
X1138670D03*
X1145430D03*
X1152190D03*
X1101491Y379996D03*
X1108251D03*
X1115011D03*
X1121771D03*
X1128530D03*
X1135290D03*
X1142050D03*
X1148810D03*
X1155570D03*
X1185989Y218147D03*
X1192749D03*
X1199509D03*
X1206269D03*
X1158950D03*
X1165710D03*
X1172469D03*
X1179229D03*
X1182609Y216196D03*
X1189369D03*
X1196129D03*
X1202889D03*
X1162330D03*
X1169089D03*
X1175849D03*
X1185989Y214247D03*
X1192749D03*
X1199509D03*
X1158950D03*
X1165710D03*
X1172469D03*
X1179229D03*
X1182609Y212296D03*
X1189369D03*
X1196129D03*
X1162330D03*
X1169089D03*
X1175849D03*
X1185989Y210346D03*
X1192749D03*
X1158950D03*
X1165710D03*
X1172469D03*
X1179229D03*
X1182609Y208397D03*
X1189369D03*
X1162330D03*
X1169089D03*
X1175849D03*
X1185989Y206447D03*
X1158950D03*
X1165710D03*
X1172469D03*
X1179229D03*
X1182609Y204496D03*
X1162330D03*
X1169089D03*
X1175849D03*
X1182609Y239596D03*
X1189369D03*
X1196129D03*
X1202889D03*
X1162330D03*
X1169089D03*
X1175849D03*
X1185989Y237647D03*
X1192749D03*
X1199509D03*
X1206269D03*
X1158950D03*
X1165710D03*
X1172469D03*
X1179229D03*
X1182609Y235696D03*
X1189369D03*
X1196129D03*
X1202889D03*
X1162330D03*
X1169089D03*
X1175849D03*
X1185989Y233746D03*
X1192749D03*
X1199509D03*
X1206269D03*
X1158950D03*
X1165710D03*
X1172469D03*
X1179229D03*
X1182609Y231797D03*
X1189369D03*
X1196129D03*
X1202889D03*
X1162330D03*
X1169089D03*
X1175849D03*
X1182609Y227896D03*
X1189369D03*
X1196129D03*
X1202889D03*
X1162330D03*
X1169089D03*
X1175849D03*
X1185989Y225947D03*
X1192749D03*
X1199509D03*
X1206269D03*
X1158950D03*
X1165710D03*
X1172469D03*
X1179229D03*
X1182609Y223996D03*
X1189369D03*
X1196129D03*
X1202889D03*
X1162330D03*
X1169089D03*
X1175849D03*
X1185989Y222047D03*
X1192749D03*
X1199509D03*
X1206269D03*
X1158950D03*
X1165710D03*
X1172469D03*
X1179229D03*
X1182609Y220096D03*
X1189369D03*
X1196129D03*
X1202889D03*
X1162330D03*
X1169089D03*
X1175849D03*
X1182609Y278596D03*
X1189369D03*
X1196129D03*
X1202889D03*
X1162330D03*
X1169089D03*
X1175849D03*
X1185989Y276646D03*
X1192749D03*
X1199509D03*
X1158950D03*
X1165710D03*
X1172469D03*
X1179229D03*
X1182609Y274696D03*
X1189369D03*
X1196129D03*
X1202889D03*
X1162330D03*
X1169089D03*
X1175849D03*
X1185989Y272747D03*
X1192749D03*
X1199509D03*
X1206269D03*
X1158950D03*
X1165710D03*
X1172469D03*
X1179229D03*
X1182609Y270796D03*
X1189369D03*
X1196129D03*
X1202889D03*
X1162330D03*
X1169089D03*
X1175849D03*
X1185989Y268847D03*
X1192749D03*
X1199509D03*
X1206269D03*
X1158950D03*
X1165710D03*
X1172469D03*
X1179229D03*
X1182609Y266896D03*
X1189369D03*
X1196129D03*
X1202889D03*
X1169089D03*
X1175849D03*
X1185989Y264947D03*
X1192749D03*
X1199509D03*
X1206269D03*
X1165710D03*
X1172469D03*
X1179229D03*
X1182609Y262996D03*
X1189369D03*
X1196129D03*
X1202889D03*
X1169089D03*
X1175849D03*
X1185989Y261047D03*
X1192749D03*
X1199509D03*
X1206269D03*
X1165710D03*
X1172469D03*
X1179229D03*
X1182609Y259096D03*
X1189369D03*
X1196129D03*
X1202889D03*
X1169089D03*
X1175849D03*
X1185989Y257147D03*
X1192749D03*
X1199509D03*
X1206269D03*
X1165710D03*
X1172469D03*
X1179229D03*
X1182609Y255196D03*
X1189369D03*
X1196129D03*
X1202889D03*
X1162330D03*
X1169089D03*
X1175849D03*
X1185989Y253247D03*
X1192749D03*
X1199509D03*
X1206269D03*
X1158950D03*
X1165710D03*
X1172469D03*
X1179229D03*
X1182609Y251296D03*
X1189369D03*
X1196129D03*
X1202889D03*
X1162330D03*
X1169089D03*
X1175849D03*
X1185989Y249347D03*
X1192749D03*
X1199509D03*
X1206269D03*
X1158950D03*
X1165710D03*
X1172469D03*
X1179229D03*
X1182609Y247396D03*
X1189369D03*
X1196129D03*
X1202889D03*
X1162330D03*
X1169089D03*
X1175849D03*
X1185989Y245447D03*
X1192749D03*
X1199509D03*
X1206269D03*
X1158950D03*
X1165710D03*
X1172469D03*
X1179229D03*
X1182609Y243496D03*
X1189369D03*
X1196129D03*
X1202889D03*
X1162330D03*
X1169089D03*
X1175849D03*
X1185989Y241547D03*
X1192749D03*
X1199509D03*
X1206269D03*
X1158950D03*
X1165710D03*
X1172469D03*
X1179229D03*
X1185989Y229847D03*
X1192749D03*
X1199509D03*
X1206269D03*
X1158950D03*
X1165710D03*
X1172469D03*
X1179229D03*
X1182609Y340996D03*
X1189369D03*
X1196129D03*
X1202889D03*
X1162330D03*
X1169089D03*
X1175849D03*
X1185989Y339047D03*
X1192749D03*
X1199509D03*
X1206269D03*
X1158950D03*
X1165710D03*
X1172469D03*
X1179229D03*
X1182609Y337096D03*
X1189369D03*
X1196129D03*
X1202889D03*
X1162330D03*
X1169089D03*
X1175849D03*
X1185989Y335147D03*
X1192749D03*
X1199509D03*
X1206269D03*
X1158950D03*
X1165710D03*
X1172469D03*
X1179229D03*
X1182609Y333196D03*
X1189369D03*
X1196129D03*
X1202889D03*
X1162330D03*
X1169089D03*
X1175849D03*
X1185989Y331247D03*
X1192749D03*
X1199509D03*
X1158950D03*
X1165710D03*
X1172469D03*
X1179229D03*
X1182609Y329296D03*
X1189369D03*
X1196129D03*
X1202889D03*
X1162330D03*
X1169089D03*
X1175849D03*
X1185989Y327347D03*
X1192749D03*
X1199509D03*
X1158950D03*
X1165710D03*
X1172469D03*
X1179229D03*
X1182609Y325396D03*
X1189369D03*
X1196129D03*
X1202889D03*
X1162330D03*
X1169089D03*
X1175849D03*
X1185989Y323446D03*
X1192749D03*
X1199509D03*
X1158950D03*
X1165710D03*
X1172469D03*
X1179229D03*
X1182609Y321496D03*
X1189369D03*
X1196129D03*
X1202889D03*
X1162330D03*
X1169089D03*
X1175849D03*
X1185989Y319547D03*
X1192749D03*
X1199509D03*
X1158950D03*
X1165710D03*
X1172469D03*
X1179229D03*
X1182609Y317596D03*
X1189369D03*
X1196129D03*
X1162330D03*
X1169089D03*
X1175849D03*
X1185989Y315647D03*
X1192749D03*
X1199509D03*
X1158950D03*
X1165710D03*
X1172469D03*
X1179229D03*
X1182609Y313696D03*
X1189369D03*
X1196129D03*
X1162330D03*
X1169089D03*
X1175849D03*
X1185989Y311747D03*
X1192749D03*
X1199509D03*
X1158950D03*
X1165710D03*
X1172469D03*
X1179229D03*
X1182609Y309797D03*
X1189369D03*
X1196129D03*
X1162330D03*
X1169089D03*
X1175849D03*
X1185989Y307847D03*
X1192749D03*
X1199509D03*
X1158950D03*
X1165710D03*
X1172469D03*
X1179229D03*
X1182609Y305896D03*
X1189369D03*
X1196129D03*
X1162330D03*
X1169089D03*
X1175849D03*
X1185989Y303947D03*
X1192749D03*
X1199509D03*
X1158950D03*
X1165710D03*
X1172469D03*
X1179229D03*
X1182609Y301996D03*
X1189369D03*
X1196129D03*
X1162330D03*
X1169089D03*
X1175849D03*
X1185989Y300047D03*
X1192749D03*
X1199509D03*
X1158950D03*
X1165710D03*
X1172469D03*
X1179229D03*
X1182609Y298096D03*
X1189369D03*
X1196129D03*
X1162330D03*
X1169089D03*
X1175849D03*
X1185989Y296147D03*
X1192749D03*
X1199509D03*
X1158950D03*
X1165710D03*
X1172469D03*
X1179229D03*
X1182609Y294196D03*
X1189369D03*
X1196129D03*
X1162330D03*
X1169089D03*
X1175849D03*
X1185989Y292247D03*
X1192749D03*
X1199509D03*
X1158950D03*
X1165710D03*
X1172469D03*
X1179229D03*
X1182609Y290296D03*
X1189369D03*
X1196129D03*
X1162330D03*
X1169089D03*
X1175849D03*
X1185989Y288347D03*
X1192749D03*
X1199509D03*
X1158950D03*
X1165710D03*
X1172469D03*
X1179229D03*
X1182609Y286396D03*
X1189369D03*
X1196129D03*
X1162330D03*
X1169089D03*
X1175849D03*
X1185989Y284447D03*
X1192749D03*
X1199509D03*
X1158950D03*
X1165710D03*
X1172469D03*
X1179229D03*
X1182609Y282496D03*
X1189369D03*
X1196129D03*
X1202889D03*
X1162330D03*
X1169089D03*
X1175849D03*
X1185989Y280547D03*
X1192749D03*
X1199509D03*
X1158950D03*
X1165710D03*
X1172469D03*
X1179229D03*
X1182609Y403396D03*
X1162330D03*
X1169089D03*
X1175849D03*
X1185989Y401447D03*
X1165710D03*
X1172469D03*
X1179229D03*
X1182609Y399496D03*
X1189369D03*
X1162330D03*
X1169089D03*
X1175849D03*
X1185989Y397546D03*
X1192749D03*
X1165710D03*
X1172469D03*
X1179229D03*
X1182609Y395597D03*
X1189369D03*
X1196129D03*
X1162330D03*
X1169089D03*
X1175849D03*
X1185989Y393647D03*
X1192749D03*
X1199509D03*
X1158950D03*
X1165710D03*
X1172469D03*
X1179229D03*
X1182609Y391696D03*
X1189369D03*
X1196129D03*
X1202889D03*
X1162330D03*
X1169089D03*
X1175849D03*
X1185989Y389747D03*
X1192749D03*
X1199509D03*
X1158950D03*
X1165710D03*
X1172469D03*
X1179229D03*
X1182609Y387796D03*
X1189369D03*
X1196129D03*
X1202889D03*
X1162330D03*
X1169089D03*
X1175849D03*
X1185989Y385847D03*
X1192749D03*
X1199509D03*
X1158950D03*
X1165710D03*
X1172469D03*
X1179229D03*
X1182609Y383896D03*
X1189369D03*
X1196129D03*
X1202889D03*
X1162330D03*
X1169089D03*
X1175849D03*
X1185989Y381947D03*
X1192749D03*
X1199509D03*
X1158950D03*
X1165710D03*
X1172469D03*
X1179229D03*
X1185989Y378047D03*
X1192749D03*
X1199509D03*
X1158950D03*
X1165710D03*
X1172469D03*
X1179229D03*
X1182609Y376096D03*
X1189369D03*
X1196129D03*
X1202889D03*
X1162330D03*
X1169089D03*
X1175849D03*
X1185989Y374146D03*
X1192749D03*
X1199509D03*
X1158950D03*
X1165710D03*
X1172469D03*
X1179229D03*
X1182609Y372197D03*
X1189369D03*
X1196129D03*
X1202889D03*
X1162330D03*
X1169089D03*
X1175849D03*
X1185989Y370247D03*
X1192749D03*
X1199509D03*
X1158950D03*
X1165710D03*
X1172469D03*
X1179229D03*
X1182609Y368296D03*
X1189369D03*
X1196129D03*
X1202889D03*
X1162330D03*
X1169089D03*
X1175849D03*
X1185989Y366347D03*
X1192749D03*
X1199509D03*
X1158950D03*
X1165710D03*
X1172469D03*
X1179229D03*
X1182609Y364396D03*
X1189369D03*
X1196129D03*
X1202889D03*
X1162330D03*
X1169089D03*
X1175849D03*
X1185989Y362447D03*
X1192749D03*
X1199509D03*
X1158950D03*
X1165710D03*
X1172469D03*
X1179229D03*
X1182609Y360496D03*
X1189369D03*
X1196129D03*
X1202889D03*
X1162330D03*
X1169089D03*
X1175849D03*
X1185989Y358547D03*
X1192749D03*
X1199509D03*
X1206269D03*
X1158950D03*
X1165710D03*
X1172469D03*
X1179229D03*
X1182609Y356596D03*
X1189369D03*
X1196129D03*
X1202889D03*
X1162330D03*
X1169089D03*
X1175849D03*
X1185989Y354647D03*
X1192749D03*
X1199509D03*
X1206269D03*
X1158950D03*
X1165710D03*
X1172469D03*
X1179229D03*
X1182609Y352696D03*
X1189369D03*
X1196129D03*
X1202889D03*
X1169089D03*
X1175849D03*
X1185989Y350747D03*
X1192749D03*
X1199509D03*
X1206269D03*
X1165710D03*
X1172469D03*
X1179229D03*
X1182609Y348796D03*
X1189369D03*
X1196129D03*
X1202889D03*
X1169089D03*
X1175849D03*
X1185989Y346847D03*
X1192749D03*
X1199509D03*
X1206269D03*
X1165710D03*
X1172469D03*
X1179229D03*
X1182609Y344896D03*
X1189369D03*
X1196129D03*
X1202889D03*
X1169089D03*
X1175849D03*
X1185989Y342947D03*
X1192749D03*
X1199509D03*
X1206269D03*
X1165710D03*
X1172469D03*
X1179229D03*
X1182609Y379996D03*
X1189369D03*
X1196129D03*
X1202889D03*
X1162330D03*
X1169089D03*
X1175849D03*
G54D104*
X53839Y427982D03*
X64839Y435856D03*
X53839Y443730D03*
G54D203*
X1370366Y72819D03*
X1587664Y138614D03*
X1563032Y106276D03*
X1576148Y115038D03*
X1540980Y350955D03*
X1648143Y177339D03*
X1610820Y223832D03*
X1678097Y164451D03*
X1863358Y138108D03*
G54D131*
X560191Y216196D03*
X556811Y214247D03*
X546671Y208397D03*
X560191Y239596D03*
Y235696D03*
Y231797D03*
Y227896D03*
Y223996D03*
Y220096D03*
X556811Y276646D03*
X560191Y274696D03*
Y270796D03*
Y266896D03*
Y262996D03*
Y259096D03*
Y255196D03*
Y251296D03*
Y247396D03*
Y243496D03*
Y340996D03*
Y337096D03*
Y333196D03*
X556811Y331247D03*
Y327347D03*
Y323446D03*
Y319547D03*
X553431Y317596D03*
Y313696D03*
Y309797D03*
Y305896D03*
Y301996D03*
Y298096D03*
Y294196D03*
Y290296D03*
Y286396D03*
X556811Y284447D03*
Y280547D03*
Y393647D03*
Y389747D03*
Y385847D03*
Y381947D03*
Y378047D03*
Y374146D03*
Y370247D03*
Y366347D03*
Y362447D03*
X560191Y360496D03*
Y356596D03*
Y352696D03*
Y348796D03*
Y344896D03*
X1209799Y216196D03*
X1206419Y214247D03*
X1196279Y208397D03*
X1209799Y239596D03*
Y235696D03*
Y231797D03*
Y227896D03*
Y223996D03*
Y220096D03*
X1206419Y276646D03*
X1209799Y274696D03*
Y270796D03*
Y266896D03*
Y262996D03*
Y259096D03*
Y255196D03*
Y251296D03*
Y247396D03*
Y243496D03*
Y340996D03*
Y337096D03*
Y333196D03*
X1206419Y331247D03*
Y327347D03*
Y323446D03*
Y319547D03*
X1203039Y317596D03*
Y313696D03*
Y309797D03*
Y305896D03*
Y301996D03*
Y298096D03*
Y294196D03*
Y290296D03*
Y286396D03*
X1206419Y284447D03*
Y280547D03*
Y393647D03*
Y389747D03*
Y385847D03*
Y381947D03*
Y378047D03*
Y374146D03*
Y370247D03*
Y366347D03*
Y362447D03*
X1209799Y360496D03*
Y356596D03*
Y352696D03*
Y348796D03*
Y344896D03*
G54D122*
X388187Y-5822D03*
Y31978D03*
Y13078D03*
Y69778D03*
Y50878D03*
Y88678D03*
Y514079D03*
Y532955D03*
Y570755D03*
Y589679D03*
Y551879D03*
Y608555D03*
X1037797Y-5822D03*
Y31978D03*
Y13078D03*
Y69778D03*
Y88678D03*
Y50878D03*
Y514079D03*
Y570755D03*
Y532955D03*
Y589679D03*
Y551879D03*
Y608555D03*
G54D221*
X1466733Y585953D03*
X1502030Y591554D03*
G54D150*
X704200Y46800D03*
X694800D03*
X704200Y533050D03*
X694800D03*
X1364400Y106750D03*
X1355000D03*
X1359200Y517350D03*
X1349800D03*
G54D312*
X1888390Y109250D03*
X1874600D03*
X1882480D03*
X1880510D03*
X1890360D03*
X1872630D03*
X1876570D03*
X1878540D03*
X1884450D03*
X1886420D03*
G54D240*
X1487858Y608784D03*
X1523396Y610052D03*
G54D105*
X103191Y452592D03*
Y471458D03*
G54D123*
X380892Y91500D03*
Y97000D03*
Y505756D03*
Y511256D03*
X642823Y131000D03*
Y136500D03*
X647561Y131000D03*
Y136500D03*
X1030500Y91500D03*
Y97000D03*
Y505756D03*
Y511256D03*
G54D204*
X1360253Y214274D03*
X1371373Y211018D03*
G54D141*
X662097Y301548D03*
X660128D03*
X658159D03*
X656190D03*
X654221D03*
X652252D03*
X681787D03*
X679818D03*
X677849D03*
X675880D03*
X673911D03*
X671942D03*
X669973D03*
X668004D03*
X666035D03*
X664066D03*
G54D303*
X1843825Y86900D03*
X1842250D03*
X1840675D03*
G36*
G01X1956463Y209274D02*
G02X1954500Y205493I-1963J-1381D01*
G01X1950000D01*
G02X1947600Y207893I0J2400D01*
G01Y210293D01*
G02X1952400I2400J0D01*
G01X1954500D01*
G02X1954986Y210243I-1J-2400D01*
G03X1956463Y209274I1904J1292D01*
G37*
G54D21*
X-17200Y516800D03*
Y513300D03*
X-16500Y493000D03*
Y489500D03*
X34719Y16717D03*
Y13217D03*
X43819Y13901D03*
Y17401D03*
X46845Y17442D03*
Y13942D03*
X-1347Y23809D03*
Y27309D03*
X40796Y17406D03*
Y13906D03*
X37739Y16712D03*
Y13212D03*
X34597Y24567D03*
Y28067D03*
X28871Y-20458D03*
Y-16958D03*
X-1080Y60600D03*
Y57100D03*
X34500Y51000D03*
Y54500D03*
X4522Y57858D03*
Y54358D03*
X8000Y275500D03*
Y272000D03*
X11000Y275500D03*
Y272000D03*
X41000Y271450D03*
Y267950D03*
X37000Y271450D03*
Y267950D03*
X8000Y299000D03*
Y295500D03*
X5000Y299000D03*
Y295500D03*
X-1278Y464071D03*
Y460571D03*
X-5590Y521840D03*
Y518340D03*
X-2390D03*
Y521840D03*
X-13500Y493000D03*
Y489500D03*
X-8990Y523040D03*
Y519540D03*
X-12690Y519590D03*
Y523090D03*
X23800Y516500D03*
Y513000D03*
X27300Y516500D03*
Y513000D03*
X16990Y525130D03*
Y521630D03*
X25388Y504477D03*
Y507977D03*
X20490Y525130D03*
Y521630D03*
X710Y521890D03*
Y518390D03*
X-9900Y489500D03*
Y493000D03*
X52906Y13926D03*
Y17426D03*
X55942Y17445D03*
Y13945D03*
X49880Y17415D03*
Y13915D03*
X106000Y11328D03*
Y14828D03*
X56540Y-20308D03*
Y-16808D03*
X53340Y-20296D03*
Y-16796D03*
X105898Y49250D03*
Y52750D03*
X108077Y86864D03*
Y90364D03*
X104289Y128454D03*
Y124954D03*
X103250Y265180D03*
Y261680D03*
X87500Y275500D03*
Y279000D03*
X80500Y275500D03*
Y279000D03*
X84000Y275500D03*
Y279000D03*
X77000Y275500D03*
Y279000D03*
X73500Y275500D03*
Y279000D03*
X86078Y266950D03*
Y270450D03*
X103500Y322500D03*
Y319000D03*
X100000Y322500D03*
Y319000D03*
X75600Y328600D03*
Y332100D03*
X57000Y341500D03*
X60000D03*
X66000D03*
X72000Y341800D03*
X69000D03*
X63000Y341500D03*
X92370Y327770D03*
Y331270D03*
X89220Y331230D03*
Y327730D03*
X91710Y339200D03*
X87500Y318500D03*
Y322000D03*
X91500Y317800D03*
Y321300D03*
X70800Y317050D03*
Y313550D03*
X55500Y316250D03*
Y312750D03*
X56000Y307500D03*
Y304000D03*
X66500Y313250D03*
Y316750D03*
X61000Y313250D03*
Y316750D03*
X80500Y322020D03*
Y318520D03*
X78000Y341050D03*
X75000Y341500D03*
X50900Y295300D03*
Y298800D03*
X56000Y300000D03*
Y296500D03*
X84000Y318520D03*
Y322020D03*
X74500Y317000D03*
Y313500D03*
X96000Y287700D03*
Y291200D03*
X94630Y363220D03*
Y359720D03*
X57000Y345000D03*
X60000D03*
X66000D03*
X72000Y345300D03*
X69000D03*
X63000Y345000D03*
X91710Y342700D03*
X94519Y349333D03*
Y345833D03*
X94630Y356850D03*
Y353350D03*
X94710Y370914D03*
Y367414D03*
X78000Y344550D03*
X75000Y345000D03*
X88300Y383110D03*
Y386610D03*
X93296Y387604D03*
Y384104D03*
X72000Y391500D03*
Y395000D03*
X52500Y398000D03*
Y401500D03*
X56000Y398000D03*
Y401500D03*
X59500Y398000D03*
Y401500D03*
X49000Y398100D03*
Y401600D03*
X95396Y373774D03*
Y377274D03*
X57500Y385500D03*
Y382000D03*
X77300Y386614D03*
Y383114D03*
X80800Y386614D03*
Y383114D03*
X54000Y385500D03*
Y382000D03*
X91996Y377274D03*
Y373774D03*
X70525Y465138D03*
Y468638D03*
X109500Y11328D03*
Y14828D03*
X116500D03*
Y11328D03*
X113000D03*
Y14828D03*
X109392Y49250D03*
Y52750D03*
X112500Y49150D03*
Y52650D03*
X116000D03*
Y49150D03*
X117354Y90529D03*
Y87029D03*
X114284D03*
Y90529D03*
X111189Y86821D03*
Y90321D03*
X153200Y195600D03*
Y199100D03*
X117475Y168300D03*
Y164800D03*
X119400Y271600D03*
Y275100D03*
X118164Y304915D03*
Y308415D03*
X117976Y368958D03*
Y372458D03*
X156392Y407500D03*
Y404000D03*
X442700Y271500D03*
Y275000D03*
X428000Y271500D03*
Y275000D03*
X436000Y271500D03*
Y275000D03*
X432000Y271500D03*
Y275000D03*
X439500Y271500D03*
Y275000D03*
X436100Y326800D03*
Y330300D03*
X433100Y326800D03*
Y330300D03*
X439100Y326800D03*
Y330300D03*
X442100Y326800D03*
Y330300D03*
X658700Y29100D03*
Y25600D03*
X611000Y116700D03*
Y120200D03*
Y113700D03*
Y110200D03*
X639320Y274550D03*
Y271050D03*
X636708Y277735D03*
X641228Y247796D03*
Y251296D03*
X646000Y259100D03*
Y255600D03*
X655000Y278100D03*
X658500D03*
X651500D03*
X649500Y255600D03*
Y259100D03*
X636400Y259000D03*
Y255500D03*
X636708Y281235D03*
X649000Y342000D03*
X654000D03*
X659000D03*
X655500Y293500D03*
Y290000D03*
X655000Y281600D03*
X658638Y291123D03*
Y287623D03*
X658500Y281600D03*
X661730Y290008D03*
Y293508D03*
X651000Y291000D03*
Y294500D03*
X651500Y281600D03*
X647500Y291000D03*
Y294500D03*
X649000Y345500D03*
X654000D03*
X659000D03*
X640500Y406500D03*
Y410000D03*
X637000Y406500D03*
Y410000D03*
X710150Y-5950D03*
Y-9450D03*
X712000Y29000D03*
Y32500D03*
X712500Y17500D03*
Y21000D03*
X708900D03*
Y17500D03*
X708500Y32500D03*
Y29000D03*
X672900Y30600D03*
X686000Y30750D03*
X689500D03*
X686700Y27950D03*
Y24450D03*
X700500Y29000D03*
Y32500D03*
X664300Y28050D03*
Y31550D03*
X713937Y-9548D03*
Y-6048D03*
X722000Y20250D03*
Y16750D03*
X715937Y20952D03*
Y17452D03*
X704500Y28700D03*
Y32200D03*
X667800Y31550D03*
Y28050D03*
X682500Y30750D03*
X672900Y34100D03*
X686000Y34250D03*
X689500D03*
X716500Y53250D03*
Y49750D03*
X682500Y34250D03*
X723500Y247500D03*
Y244000D03*
X718000Y224600D03*
Y221100D03*
X720500Y247500D03*
Y244000D03*
X723500Y252500D03*
Y256000D03*
X714000D03*
Y252500D03*
X711000Y256000D03*
Y252500D03*
X717000D03*
Y256000D03*
X720500D03*
Y252500D03*
X707500Y256000D03*
Y252500D03*
X676000Y278100D03*
X672500D03*
X673500Y295000D03*
Y291500D03*
X692470Y293640D03*
Y290140D03*
X684000Y342000D03*
X674000D03*
X701000Y335500D03*
Y332000D03*
X705000Y335500D03*
Y332000D03*
X679000Y342000D03*
X669000D03*
X717900Y309200D03*
Y312700D03*
X701000Y303500D03*
Y307000D03*
Y322500D03*
Y319000D03*
X664000Y342000D03*
X725400Y300450D03*
Y296950D03*
X676000Y281600D03*
X672500D03*
X684000Y345500D03*
X674000D03*
X679400Y371200D03*
Y367700D03*
X689900Y371200D03*
Y367700D03*
X679000Y345500D03*
X669000D03*
X664000D03*
X693200Y416775D03*
Y420275D03*
X696400Y416775D03*
Y420275D03*
X683400Y414700D03*
Y411200D03*
X712100Y515250D03*
Y518750D03*
X708500D03*
Y515250D03*
X700500D03*
Y518750D03*
X669400Y515700D03*
Y519200D03*
X686000Y514250D03*
Y517750D03*
X689500Y520750D03*
Y517250D03*
X683550Y511200D03*
Y507700D03*
X672400Y519250D03*
Y515750D03*
X704500Y515250D03*
Y518750D03*
X675500Y519250D03*
Y515750D03*
X679000Y514250D03*
Y517750D03*
X682500Y514250D03*
Y517750D03*
X716400Y538800D03*
Y535300D03*
X714600Y574500D03*
Y578000D03*
X711000Y574500D03*
Y578000D03*
X759000Y11250D03*
Y14750D03*
X766000D03*
Y11250D03*
X762500D03*
Y14750D03*
X726500Y20250D03*
Y16750D03*
X755500Y11250D03*
Y14750D03*
X759000Y49250D03*
Y52750D03*
X766000D03*
Y49250D03*
X762500D03*
Y52750D03*
X759000Y88611D03*
Y92111D03*
X762500Y88611D03*
Y92111D03*
X766000D03*
Y88611D03*
X755500Y49250D03*
Y52750D03*
Y88611D03*
Y92111D03*
X762300Y213100D03*
Y216600D03*
X766947Y207070D03*
Y210570D03*
X728291Y247500D03*
Y244000D03*
X761600Y245520D03*
Y249020D03*
X726500Y252500D03*
Y256000D03*
X740697Y260490D03*
Y256990D03*
X761850Y275560D03*
Y279060D03*
X742400Y277850D03*
X748700Y276350D03*
Y272850D03*
X747886Y263659D03*
Y260159D03*
X742128Y270902D03*
Y267402D03*
X765134Y271186D03*
Y274686D03*
X764341Y239542D03*
Y243042D03*
X746870Y286050D03*
Y289550D03*
X742400Y281350D03*
X734200Y297650D03*
Y301150D03*
X728900Y300450D03*
Y296950D03*
X743070Y289500D03*
Y286000D03*
X765582Y303588D03*
Y307088D03*
X768367Y337062D03*
Y340562D03*
X762350Y343730D03*
Y347230D03*
X768059Y369287D03*
Y372787D03*
X730100Y573950D03*
Y577450D03*
X726500Y574000D03*
Y577500D03*
X730100Y600500D03*
Y604000D03*
X726800D03*
Y600500D03*
X804200Y195600D03*
Y199100D03*
X809000Y407500D03*
Y404000D03*
X1080500Y272000D03*
Y275500D03*
X1088000Y272000D03*
Y275500D03*
X1077000Y272000D03*
Y275500D03*
X1091500Y272000D03*
Y275500D03*
X1094764Y271972D03*
Y275472D03*
X1084500Y272000D03*
Y275500D03*
X1084580Y326760D03*
Y330260D03*
X1087680Y326760D03*
Y330260D03*
X1095000Y326600D03*
Y330100D03*
X1091180Y326660D03*
Y330160D03*
X1076270Y335780D03*
Y332280D03*
X1255400Y116917D03*
Y120417D03*
Y113917D03*
Y110417D03*
X1228906Y140251D03*
Y136751D03*
X1225775Y140219D03*
Y136719D03*
X1279550Y111670D03*
Y115170D03*
Y119170D03*
Y122670D03*
X1276704Y507538D03*
Y504038D03*
X1275540Y513490D03*
Y516990D03*
X1273687Y507491D03*
Y503991D03*
X1268805Y508940D03*
Y505440D03*
X1272060Y513590D03*
Y517090D03*
X1339500Y90000D03*
Y93500D03*
X1322000Y88000D03*
Y91500D03*
X1326600Y80900D03*
Y77400D03*
X1325500Y91500D03*
Y88000D03*
X1341600Y501750D03*
Y505250D03*
X1323900Y504750D03*
Y508250D03*
X1326900D03*
Y504750D03*
X1338300Y501750D03*
Y505250D03*
X1335100Y501700D03*
Y505200D03*
X1330000Y508250D03*
Y504750D03*
X1387497Y-3011D03*
Y489D03*
X1384371Y-3020D03*
Y480D03*
X1378170Y8888D03*
Y12388D03*
X1379556Y19907D03*
Y16407D03*
X1384200Y31700D03*
X1371591Y88967D03*
Y92467D03*
X1368591Y92450D03*
Y88950D03*
X1360700D03*
Y92450D03*
X1350500Y92640D03*
Y89140D03*
X1351500Y77000D03*
Y80500D03*
X1347500D03*
Y77000D03*
X1356010Y45574D03*
Y42074D03*
X1343500Y90000D03*
Y93500D03*
X1347000Y90000D03*
Y93500D03*
X1374500Y73500D03*
Y70000D03*
X1378000Y73500D03*
Y70000D03*
X1370100Y79500D03*
Y76000D03*
X1364700Y88950D03*
Y92450D03*
X1366100Y79500D03*
Y76000D03*
X1344000Y80500D03*
Y77000D03*
X1374177Y61982D03*
Y65482D03*
X1384200Y35200D03*
X1376550Y113600D03*
Y110100D03*
X1344900Y505250D03*
Y501750D03*
X1396871Y505800D03*
Y509300D03*
X1392953Y509379D03*
Y505879D03*
X1371500Y526000D03*
X1401960Y524955D03*
X1391291Y531936D03*
Y528436D03*
X1400222Y554185D03*
Y550685D03*
X1352000Y560600D03*
Y564100D03*
X1371500Y529500D03*
X1401960Y528455D03*
X1398620Y530921D03*
Y534421D03*
X1398226Y543462D03*
Y539962D03*
X1395120Y530921D03*
Y534421D03*
X1385800Y612500D03*
Y609000D03*
X1352332Y620000D03*
Y616500D03*
X1383879Y619250D03*
Y615750D03*
X1420337Y42977D03*
Y39477D03*
X1416837Y42977D03*
Y39477D03*
X1458136D03*
Y42977D03*
X1454636Y39477D03*
Y42977D03*
X1464086Y39477D03*
Y42977D03*
X1438936Y39477D03*
Y42977D03*
X1426286Y39477D03*
Y42977D03*
X1435436Y39477D03*
Y42977D03*
X1429786Y39477D03*
Y42977D03*
X1445186Y39477D03*
Y42977D03*
X1448686Y39477D03*
Y42977D03*
X1430117Y287489D03*
Y283989D03*
X1461700Y395500D03*
Y399000D03*
X1458450Y365450D03*
Y361950D03*
X1460500Y386000D03*
Y382500D03*
Y392500D03*
Y389000D03*
X1453000Y377750D03*
Y381250D03*
X1453900Y398100D03*
Y394600D03*
X1441800Y366400D03*
Y362900D03*
X1451560Y418179D03*
Y421679D03*
Y428279D03*
Y424779D03*
X1425560Y523955D03*
X1428800Y524000D03*
X1432200Y524050D03*
X1422000Y524000D03*
X1405460Y524955D03*
X1455000Y540750D03*
Y537250D03*
X1458000Y540750D03*
Y537250D03*
X1425560Y527455D03*
X1428800Y527500D03*
X1432200Y527550D03*
X1448900Y540600D03*
Y537100D03*
X1452000D03*
Y540600D03*
X1439200Y534600D03*
Y531100D03*
X1436160Y554655D03*
Y558155D03*
X1422000Y527500D03*
X1432560Y558155D03*
Y554655D03*
X1405460Y528455D03*
X1527600Y-2500D03*
Y1000D03*
X1516900Y-2500D03*
Y1000D03*
X1520100Y-2500D03*
Y1000D03*
X1513700Y-2500D03*
Y1000D03*
X1486486Y39477D03*
Y42977D03*
X1491836Y39577D03*
Y43077D03*
X1495336Y39577D03*
Y43077D03*
X1477036Y39477D03*
Y42977D03*
X1473536Y39477D03*
Y42977D03*
X1467586Y39477D03*
Y42977D03*
X1482986Y39477D03*
Y42977D03*
X1498985Y143065D03*
Y146565D03*
X1493750Y140400D03*
Y143900D03*
X1519200Y206700D03*
Y203200D03*
X1518000Y218250D03*
X1511000D03*
X1518000Y221750D03*
X1511000D03*
X1504453Y302789D03*
Y299289D03*
X1507476Y302789D03*
Y299289D03*
X1510476Y302816D03*
Y299316D03*
X1513476D03*
Y302816D03*
X1516910Y323940D03*
Y327440D03*
X1523000Y347250D03*
Y343750D03*
X1526000D03*
Y347250D03*
X1517000D03*
Y343750D03*
X1520000Y347250D03*
Y343750D03*
X1487000Y347250D03*
Y343750D03*
X1496000D03*
Y347250D03*
X1499000Y343750D03*
Y347250D03*
X1493000Y343750D03*
Y347250D03*
X1490000D03*
Y343750D03*
X1483000Y347250D03*
Y343750D03*
X1472500D03*
Y347250D03*
X1477000Y343750D03*
Y347250D03*
X1480000Y343750D03*
Y347250D03*
X1508000D03*
Y343750D03*
X1514000Y347250D03*
Y343750D03*
X1511000Y347250D03*
Y343750D03*
X1505000Y347250D03*
Y343750D03*
X1502000D03*
Y347250D03*
X1472500Y354250D03*
Y350750D03*
X1494950Y353000D03*
Y356500D03*
X1516960Y352580D03*
Y356080D03*
X1502030Y585894D03*
Y582394D03*
X1466647Y580512D03*
Y577012D03*
X1502268Y604439D03*
Y607939D03*
X1466800Y615439D03*
Y611939D03*
X1466500Y604750D03*
Y608250D03*
X1494300Y618900D03*
Y622400D03*
X1502268Y615439D03*
Y611939D03*
X1498182Y603774D03*
Y607274D03*
X1494982Y603849D03*
Y607349D03*
X1554800Y-2600D03*
Y900D03*
X1564400Y-2600D03*
Y900D03*
X1558000Y-2600D03*
Y900D03*
X1561200Y-2600D03*
Y900D03*
X1540000Y-2500D03*
Y1000D03*
X1534000Y-2500D03*
Y1000D03*
X1543500Y-2500D03*
Y1000D03*
X1530800Y-2500D03*
Y1000D03*
X1548400Y-2600D03*
Y900D03*
X1551600Y-2600D03*
Y900D03*
X1586500Y87000D03*
Y90500D03*
X1585500Y94500D03*
X1589500Y90500D03*
Y87000D03*
X1582500Y94500D03*
X1579998Y39484D03*
Y42984D03*
X1576498Y39484D03*
Y42984D03*
X1585948Y39484D03*
Y42984D03*
X1589448Y39484D03*
Y42984D03*
X1557398Y39684D03*
Y43184D03*
X1548248Y39484D03*
Y42984D03*
X1560898Y39684D03*
Y43184D03*
X1567048Y39484D03*
Y42984D03*
X1570548Y39484D03*
Y42984D03*
X1551748Y39484D03*
Y42984D03*
X1584183Y112179D03*
Y115679D03*
X1580920Y115685D03*
Y112185D03*
X1587222Y115669D03*
Y112169D03*
X1585500Y98000D03*
X1582500D03*
X1576731Y128410D03*
Y131910D03*
X1579000Y185250D03*
Y188750D03*
Y182250D03*
Y178750D03*
X1553000Y162900D03*
Y159400D03*
X1579000Y196750D03*
Y193250D03*
X1541000Y279750D03*
X1548000D03*
X1534000D03*
X1537500D03*
X1540000Y250750D03*
Y254250D03*
X1537000D03*
Y250750D03*
X1550852Y246702D03*
Y243202D03*
X1533000Y257600D03*
Y261100D03*
X1533900Y250750D03*
Y254250D03*
X1543399Y251250D03*
Y254750D03*
X1544500Y279750D03*
X1554400Y258800D03*
Y262300D03*
Y258800D03*
Y255300D03*
X1577500Y334250D03*
Y330750D03*
Y327750D03*
Y324250D03*
X1540957Y337323D03*
Y340823D03*
X1547651Y336246D03*
Y339746D03*
X1560500Y338500D03*
Y335000D03*
X1553500Y338250D03*
Y334750D03*
X1556500Y338250D03*
Y334750D03*
X1543957Y337323D03*
Y340823D03*
X1541000Y283250D03*
X1548000D03*
X1567500Y309750D03*
Y306250D03*
X1534000Y283250D03*
X1537500D03*
X1535250Y317800D03*
Y314300D03*
X1577500Y296000D03*
Y299500D03*
X1544500Y283250D03*
X1545500Y343750D03*
Y347250D03*
X1556500Y343750D03*
Y347250D03*
X1553500Y343750D03*
Y347250D03*
X1560500Y343750D03*
Y347250D03*
X1550500D03*
Y343750D03*
X1529000Y347250D03*
Y343750D03*
X1535000Y347250D03*
Y343750D03*
X1542500D03*
Y347250D03*
X1538000D03*
Y343750D03*
X1532000D03*
Y347250D03*
X1574500Y587500D03*
X1571493D03*
X1562500Y583300D03*
Y586800D03*
X1568212Y587331D03*
X1577000Y610560D03*
Y607060D03*
X1573520Y607090D03*
Y610590D03*
X1577000Y613500D03*
Y617000D03*
X1574500Y591000D03*
X1571493D03*
X1539000Y591919D03*
Y595419D03*
X1573500Y617000D03*
Y613500D03*
X1568212Y590831D03*
X1542500Y591919D03*
Y595419D03*
X1530850Y603650D03*
Y607150D03*
X1649900Y81750D03*
Y85250D03*
X1643629Y83308D03*
Y86808D03*
X1614366Y87329D03*
Y90829D03*
X1636500Y87500D03*
Y91000D03*
X1628500Y90000D03*
Y86500D03*
X1625500Y86750D03*
Y90250D03*
X1598849Y90788D03*
Y87288D03*
X1602000Y87250D03*
Y90750D03*
X1643900Y70300D03*
Y73800D03*
X1650800Y70300D03*
Y73800D03*
X1647500Y70300D03*
Y73800D03*
X1595500Y87250D03*
Y90750D03*
X1592500Y90500D03*
Y87000D03*
X1621949Y83888D03*
Y87388D03*
X1618449Y83888D03*
Y87388D03*
X1605000Y76250D03*
Y79750D03*
X1617393Y41527D03*
Y45027D03*
X1613893Y41527D03*
Y45027D03*
X1595398Y39484D03*
Y42984D03*
X1598898Y39484D03*
Y42984D03*
X1604848Y39479D03*
Y42979D03*
X1608348Y39479D03*
Y42979D03*
X1647852Y189229D03*
Y192729D03*
X1650852D03*
Y189229D03*
X1630154Y214948D03*
Y211448D03*
X1606934Y191791D03*
Y188291D03*
X1603934Y192041D03*
Y188541D03*
X1612934Y191791D03*
Y188291D03*
X1609934Y191791D03*
Y188291D03*
X1639811Y191803D03*
Y188303D03*
X1596000Y187850D03*
Y184350D03*
X1599000Y187850D03*
Y184350D03*
X1618623Y191226D03*
Y187726D03*
X1621623Y191226D03*
Y187726D03*
X1624972Y192756D03*
Y189256D03*
X1636811Y191803D03*
Y188303D03*
X1645000Y217850D03*
X1630418Y192807D03*
Y189307D03*
X1633711Y192804D03*
Y189304D03*
X1645400Y228350D03*
Y224850D03*
X1599201Y249642D03*
Y253142D03*
X1605819Y259329D03*
Y262829D03*
X1591174Y227582D03*
Y231082D03*
X1645000Y221350D03*
X1591500Y329250D03*
Y325750D03*
X1648200Y336750D03*
Y340250D03*
X1645000Y336750D03*
Y340250D03*
X1645650Y345250D03*
Y348750D03*
X1648650D03*
Y345250D03*
X1624200Y403500D03*
X1622550Y358200D03*
Y354700D03*
X1616900Y403400D03*
X1620700D03*
X1616890Y399580D03*
Y396080D03*
X1633400Y372900D03*
Y369400D03*
X1594201Y384066D03*
Y387566D03*
X1594451Y398528D03*
Y395028D03*
X1620000Y349250D03*
Y345750D03*
X1649800Y452300D03*
Y448800D03*
X1627800Y464100D03*
X1643430Y434280D03*
Y437780D03*
X1624200Y407000D03*
X1606500Y405250D03*
Y408750D03*
X1609500D03*
Y405250D03*
X1616900Y406900D03*
X1620700D03*
X1643301Y418255D03*
Y414755D03*
X1622383Y492026D03*
Y495526D03*
X1627800Y467600D03*
X1631538Y530500D03*
Y534000D03*
X1628038Y530500D03*
Y534000D03*
X1621295Y533812D03*
Y530312D03*
X1624538Y534000D03*
Y530500D03*
X1656500Y86000D03*
Y89500D03*
X1653000Y81750D03*
Y85250D03*
X1708000Y59500D03*
Y56000D03*
X1711700Y62000D03*
Y58500D03*
X1705000Y56000D03*
Y59500D03*
X1663700Y87800D03*
Y84300D03*
X1711300Y65400D03*
Y68900D03*
X1667916Y58116D03*
Y54616D03*
X1704900Y69768D03*
Y66268D03*
X1654100Y70300D03*
Y73800D03*
X1705250Y48400D03*
Y44900D03*
X1700000Y102000D03*
Y105500D03*
X1696650Y102000D03*
Y105500D03*
X1706100Y128450D03*
Y124950D03*
X1676849Y189288D03*
Y192788D03*
X1679849Y189288D03*
Y192788D03*
X1667349Y189288D03*
Y192788D03*
X1659949Y189288D03*
Y192788D03*
X1664349Y189288D03*
Y192788D03*
X1703350Y174350D03*
Y177850D03*
X1710650Y166200D03*
Y169700D03*
X1683340Y177101D03*
Y180601D03*
X1653949Y189288D03*
Y192788D03*
X1656949Y189288D03*
Y192788D03*
X1662000Y328750D03*
Y332250D03*
X1656400Y336750D03*
Y340250D03*
X1657500Y462550D03*
X1661000D03*
X1656000Y451750D03*
Y448250D03*
X1659000Y451750D03*
Y448250D03*
X1657500Y466050D03*
X1661000D03*
X1693019Y514752D03*
Y518252D03*
X1690000Y518250D03*
Y514750D03*
X1702830Y512550D03*
Y509050D03*
X1718500Y79750D03*
Y83250D03*
X1722000Y73250D03*
Y76750D03*
X1714850Y74278D03*
Y77778D03*
X1729500Y54500D03*
Y51000D03*
X1726500Y54500D03*
Y51000D03*
X1723500D03*
Y54500D03*
X1762000Y76250D03*
Y79750D03*
X1714700Y58500D03*
Y62000D03*
X1718500Y72750D03*
Y76250D03*
X1758780Y92870D03*
X1755580D03*
X1765500Y76250D03*
Y79750D03*
X1773708Y109776D03*
Y113276D03*
X1758780Y96370D03*
X1755580D03*
X1714129Y173131D03*
Y169631D03*
X1724200Y510100D03*
Y506600D03*
X1715461Y587223D03*
Y590723D03*
X1833100Y4200D03*
Y7700D03*
X1829900Y80450D03*
Y83950D03*
X1824350Y88150D03*
Y91650D03*
X1833000Y83950D03*
Y80450D03*
X1824350Y94450D03*
X1793000Y149000D03*
Y152500D03*
X1819348Y145937D03*
Y149437D03*
X1815348D03*
Y145937D03*
X1802485Y136539D03*
Y140039D03*
X1804720Y106570D03*
Y103070D03*
X1808400Y117300D03*
Y120800D03*
X1811900Y117500D03*
Y121000D03*
X1787500Y152500D03*
Y149000D03*
X1780500Y109750D03*
Y113250D03*
X1822848Y145937D03*
Y149437D03*
X1811348Y145937D03*
Y149437D03*
X1824350Y97950D03*
X1777000Y109750D03*
Y113250D03*
X1786000Y158000D03*
Y161500D03*
X1836000Y158300D03*
Y161800D03*
X1834000Y532500D03*
Y529000D03*
X1782000Y588500D03*
Y585000D03*
X1780756Y576990D03*
Y573490D03*
X1835000Y586250D03*
Y582750D03*
Y575750D03*
Y579250D03*
X1787500Y595000D03*
Y591500D03*
X1884018Y45564D03*
Y49064D03*
X1880630Y45611D03*
Y49111D03*
X1886590Y69285D03*
Y72785D03*
X1890090Y69285D03*
Y72785D03*
X1883090Y69285D03*
Y72785D03*
X1842964Y104926D03*
Y101426D03*
X1859163Y141698D03*
Y145198D03*
X1866500Y144250D03*
Y140750D03*
X1875500Y147750D03*
Y144250D03*
X1878500Y147750D03*
Y144250D03*
X1881500Y147750D03*
Y144250D03*
X1870000D03*
Y140750D03*
X1839598Y101484D03*
Y104984D03*
X1897640Y140100D03*
Y136600D03*
X1862500Y153500D03*
Y150000D03*
X1856329Y107042D03*
Y103542D03*
X1881400Y189350D03*
Y192850D03*
X1897760Y202210D03*
Y198710D03*
X1881400Y181350D03*
Y177850D03*
X1842500Y169500D03*
Y166000D03*
X1875900Y158850D03*
Y162350D03*
Y168850D03*
Y165350D03*
X1840000Y526000D03*
Y522500D03*
X1839000Y513000D03*
Y509500D03*
X1838900Y502300D03*
Y498800D03*
X1881806Y588061D03*
X1840000Y532500D03*
Y529000D03*
X1862500Y574250D03*
Y577750D03*
Y586250D03*
Y582750D03*
X1868000Y584250D03*
Y580750D03*
X1862000Y566250D03*
Y569750D03*
X1871100Y586400D03*
X1873150Y561050D03*
Y557550D03*
X1876650Y561050D03*
Y557550D03*
X1881806Y591561D03*
X1871100Y589900D03*
X1922800Y90900D03*
Y87400D03*
X1925097Y115420D03*
Y111920D03*
X1916094Y103696D03*
Y107196D03*
X1931000Y150500D03*
Y147000D03*
X1916094Y110696D03*
Y107196D03*
X1912894Y107146D03*
Y110646D03*
Y107146D03*
Y103646D03*
X1921144Y115344D03*
Y118844D03*
Y115344D03*
Y111844D03*
X1921139Y105424D03*
Y108924D03*
X1900200Y130000D03*
Y133500D03*
Y123600D03*
Y127100D03*
X1928000Y195850D03*
Y199350D03*
X1922800Y196050D03*
Y199550D03*
X1919800Y196050D03*
Y199550D03*
X1937909Y183346D03*
Y186846D03*
X1941609D03*
Y183346D03*
X1914900Y201350D03*
Y197850D03*
X1911400Y201350D03*
Y197850D03*
X1918200Y548600D03*
Y545100D03*
G54D114*
X266579Y214960D03*
Y211060D03*
X269959Y209109D03*
X273339Y207159D03*
X276719Y205210D03*
X273339Y203260D03*
X276719Y201309D03*
X266579Y230559D03*
Y226660D03*
Y218860D03*
X269959Y279310D03*
Y275409D03*
X266579Y273460D03*
Y269560D03*
Y265660D03*
Y261760D03*
Y257860D03*
Y253960D03*
Y250060D03*
Y246160D03*
Y242260D03*
Y238360D03*
Y234460D03*
Y222760D03*
Y339760D03*
Y335860D03*
Y331960D03*
Y328060D03*
X269959Y326110D03*
Y322209D03*
Y318309D03*
X273339Y316360D03*
Y312460D03*
Y308560D03*
Y304660D03*
Y300760D03*
Y296860D03*
Y292959D03*
Y289060D03*
Y285160D03*
X269959Y283209D03*
X273339Y398260D03*
X280099D03*
X276719Y396309D03*
X273339Y394359D03*
X269959Y392410D03*
Y384609D03*
Y380709D03*
Y376809D03*
Y369010D03*
Y365109D03*
Y361209D03*
Y357309D03*
X266579Y355360D03*
Y351460D03*
Y347560D03*
Y343660D03*
X269959Y372909D03*
X916187Y214960D03*
Y211060D03*
X919567Y209109D03*
X922947Y207159D03*
X926327Y205210D03*
X922947Y203260D03*
X926327Y201309D03*
X916187Y230559D03*
Y226660D03*
Y218860D03*
X919567Y279310D03*
Y275409D03*
X916187Y273460D03*
Y269560D03*
Y265660D03*
Y261760D03*
Y257860D03*
Y253960D03*
Y250060D03*
Y246160D03*
Y242260D03*
Y238360D03*
Y234460D03*
Y222760D03*
Y339760D03*
Y335860D03*
Y331960D03*
Y328060D03*
X919567Y326110D03*
Y322209D03*
Y318309D03*
X922947Y316360D03*
Y312460D03*
Y308560D03*
Y304660D03*
Y300760D03*
Y296860D03*
Y292959D03*
Y289060D03*
Y285160D03*
X919567Y283209D03*
X922947Y398260D03*
X929707D03*
X926327Y396309D03*
X922947Y394359D03*
X919567Y392410D03*
Y384609D03*
Y380709D03*
Y376809D03*
Y369010D03*
Y365109D03*
Y361209D03*
Y357309D03*
X916187Y355360D03*
Y351460D03*
Y347560D03*
Y343660D03*
X919567Y372909D03*
G54D132*
X570000Y473000D03*
X598000D03*
X576900Y499100D03*
X604900D03*
X656800Y82000D03*
X654900Y103050D03*
X643500Y188500D03*
X649500Y239900D03*
X659000Y472700D03*
X684800Y82000D03*
X716500Y129500D03*
X672500Y129000D03*
X700500D03*
X682900Y103050D03*
X689000Y188300D03*
X717000D03*
X671500Y188500D03*
X677500Y239900D03*
X687000Y472700D03*
X744500Y129500D03*
X1224850Y500200D03*
X1252850D03*
X1337100Y554900D03*
X1309100D03*
X1568400Y552200D03*
X1540400D03*
X1800000Y505900D03*
X1828000D03*
G54D30*
X46986Y-19703D03*
G54D222*
X1404910Y536868D03*
Y538443D03*
Y540018D03*
Y541593D03*
Y543168D03*
Y544742D03*
Y546317D03*
Y547892D03*
Y549467D03*
Y551042D03*
X1548550Y598413D03*
Y599988D03*
Y601563D03*
Y603138D03*
Y604713D03*
Y606287D03*
Y607862D03*
Y609437D03*
Y611012D03*
Y612587D03*
G54D213*
G01X132959Y30100D02*
X132892Y30033D01*
Y26500D01*
X133659Y25733D01*
Y22923D01*
G01Y-14877D02*
Y-12067D01*
X132892Y-11300D01*
Y-7767D01*
X132959Y-7700D01*
G01X169770Y30100D02*
X169592Y29922D01*
Y26699D01*
X170470Y25821D01*
Y22923D01*
G01Y-14877D02*
Y-11979D01*
X169592Y-11101D01*
Y-7878D01*
X169770Y-7700D01*
G01X132959Y67900D02*
X132892Y67833D01*
Y64300D01*
X133659Y63533D01*
Y60723D01*
G01X169770Y67900D02*
X169592Y67722D01*
Y64499D01*
X170470Y63621D01*
Y60723D01*
G01X133659Y523900D02*
Y526733D01*
X132892Y527500D01*
Y531033D01*
X132959Y531100D01*
G01X170470Y523900D02*
Y526821D01*
X169592Y527699D01*
Y530922D01*
X169770Y531100D01*
G01X170470Y561700D02*
Y564621D01*
X169592Y565499D01*
Y568722D01*
X169770Y568900D01*
G01X133659Y561700D02*
Y564533D01*
X132892Y565300D01*
Y568833D01*
X132959Y568900D01*
G01X170470Y599500D02*
Y602421D01*
X169592Y603299D01*
Y606522D01*
X169770Y606700D01*
G01X133659Y599500D02*
Y602333D01*
X132892Y603100D01*
Y606633D01*
X132959Y606700D01*
G01X206492Y27300D02*
Y30011D01*
X206581Y30100D01*
G01X206492Y-10500D02*
Y-7789D01*
X206581Y-7700D01*
G01X210628Y3233D02*
Y-1525D01*
X210402Y-1751D01*
Y-1801D01*
G01Y73799D02*
Y73849D01*
X210628Y74075D01*
Y78833D01*
G01X206581Y67900D02*
X206492Y67811D01*
Y65100D01*
G01X210628Y41033D02*
Y36275D01*
X210402Y36049D01*
Y35999D01*
G01X206492Y528300D02*
Y531011D01*
X206581Y531100D01*
G01X210628Y542010D02*
Y537275D01*
X210402Y537049D01*
Y536999D01*
G01X210628Y579810D02*
Y575075D01*
X210402Y574849D01*
Y574799D01*
G01X206492Y566100D02*
Y568811D01*
X206581Y568900D01*
G01X206492Y603900D02*
Y606611D01*
X206581Y606700D01*
G01X210628Y617610D02*
Y612875D01*
X210402Y612649D01*
Y612599D01*
G01X280903Y22923D02*
Y25789D01*
X279992Y26700D01*
Y29889D01*
X280203Y30100D01*
G01X280903Y-14877D02*
Y-12011D01*
X279992Y-11100D01*
Y-7911D01*
X280203Y-7700D01*
G01X284250Y3233D02*
Y-1525D01*
X284024Y-1751D01*
Y-1801D01*
G01X244092Y22923D02*
Y25801D01*
X243292Y26601D01*
Y30000D01*
X243392Y30100D01*
G01X247213Y-1801D02*
Y-1751D01*
X247439Y-1525D01*
Y3233D01*
G01X244092Y-14877D02*
Y-11999D01*
X243292Y-11199D01*
Y-7800D01*
X243392Y-7700D01*
G01X284024Y73799D02*
Y73849D01*
X284250Y74075D01*
Y78833D01*
G01X284024Y35999D02*
Y36049D01*
X284250Y36275D01*
Y41033D01*
G01X280903Y60723D02*
Y63589D01*
X279992Y64500D01*
Y67689D01*
X280203Y67900D01*
G01X247213Y73799D02*
Y73849D01*
X247439Y74075D01*
Y78833D01*
G01X243392Y67900D02*
X243292Y67800D01*
Y64401D01*
X244092Y63601D01*
Y60723D01*
G01X247439Y41033D02*
Y36275D01*
X247213Y36049D01*
Y35999D01*
G01X280903Y523900D02*
Y526789D01*
X279992Y527700D01*
Y530889D01*
X280203Y531100D01*
G01X244092Y523900D02*
Y526801D01*
X243292Y527601D01*
Y531000D01*
X243392Y531100D01*
G01X284250Y542010D02*
Y537275D01*
X284024Y537049D01*
Y536999D01*
G01X247439Y542010D02*
Y537275D01*
X247213Y537049D01*
Y536999D01*
G01X284250Y579810D02*
Y575075D01*
X284024Y574849D01*
Y574799D01*
G01X280903Y561700D02*
Y564589D01*
X279992Y565500D01*
Y568689D01*
X280203Y568900D01*
G01X244092Y561700D02*
Y564601D01*
X243292Y565401D01*
Y568800D01*
X243392Y568900D01*
G01X247439Y579810D02*
Y575075D01*
X247213Y574849D01*
Y574799D01*
G01X280903Y599500D02*
Y602389D01*
X279992Y603300D01*
Y606489D01*
X280203Y606700D01*
G01X244092Y599500D02*
Y602401D01*
X243292Y603201D01*
Y606600D01*
X243392Y606700D01*
G01X247439Y617610D02*
Y612875D01*
X247213Y612649D01*
Y612599D01*
G01X284250Y617610D02*
Y612875D01*
X284024Y612649D01*
Y612599D01*
G01X461612Y22923D02*
Y25781D01*
X460692Y26701D01*
Y29880D01*
X460912Y30100D01*
G01X461612Y-14877D02*
Y-12019D01*
X460692Y-11099D01*
Y-7920D01*
X460912Y-7700D01*
G01X464958Y3233D02*
Y-1525D01*
X464732Y-1751D01*
Y-1801D01*
G01Y73799D02*
Y73849D01*
X464958Y74075D01*
Y78833D01*
G01Y41033D02*
Y36275D01*
X464732Y36049D01*
Y35999D01*
G01X460912Y67900D02*
X460692Y67680D01*
Y64501D01*
X461612Y63581D01*
Y60723D01*
G01X478344Y523900D02*
Y530949D01*
G01X471651Y523900D02*
Y527130D01*
X471650Y527131D01*
G01X461612Y523900D02*
Y526781D01*
X460692Y527701D01*
Y530880D01*
X460912Y531100D01*
G01X464958Y542010D02*
Y537275D01*
X464732Y537049D01*
Y536999D01*
G01X461612Y561700D02*
Y564581D01*
X460692Y565501D01*
Y568680D01*
X460912Y568900D01*
G01X464958Y579810D02*
Y575075D01*
X464732Y574849D01*
Y574799D01*
G01X461612Y599500D02*
Y602381D01*
X460692Y603301D01*
Y606480D01*
X460912Y606700D01*
G01X464958Y617610D02*
Y612875D01*
X464732Y612649D01*
Y612599D01*
G01X535234Y22923D02*
Y25857D01*
X534392Y26699D01*
Y29958D01*
X534534Y30100D01*
G01X538581Y3233D02*
Y-1525D01*
X538355Y-1751D01*
Y-1801D01*
G01X535234Y-14877D02*
Y-11943D01*
X534392Y-11101D01*
Y-7842D01*
X534534Y-7700D01*
G01X498423Y22923D02*
Y25769D01*
X497592Y26600D01*
Y29969D01*
X497723Y30100D01*
G01X501770Y3233D02*
Y-1525D01*
X501544Y-1751D01*
Y-1801D01*
G01X498423Y-14877D02*
Y-12031D01*
X497592Y-11200D01*
Y-7831D01*
X497723Y-7700D01*
G01X538355Y73799D02*
Y73849D01*
X538581Y74075D01*
Y78833D01*
G01X534534Y67900D02*
X534392Y67758D01*
Y64499D01*
X535234Y63657D01*
Y60723D01*
G01X538355Y35999D02*
Y36049D01*
X538581Y36275D01*
Y41033D01*
G01X501544Y73799D02*
Y73849D01*
X501770Y74075D01*
Y78833D01*
G01X497723Y67900D02*
X497592Y67769D01*
Y64400D01*
X498423Y63569D01*
Y60723D01*
G01X501770Y41033D02*
Y36275D01*
X501544Y36049D01*
Y35999D01*
G01X535234Y523900D02*
Y526857D01*
X534392Y527699D01*
Y530958D01*
X534534Y531100D01*
G01X498423Y523900D02*
Y526769D01*
X497592Y527600D01*
Y530969D01*
X497723Y531100D01*
G01X538581Y542010D02*
Y537275D01*
X538355Y537049D01*
Y536999D01*
G01X501770Y542010D02*
Y537275D01*
X501544Y537049D01*
Y536999D01*
G01X535234Y561700D02*
Y564657D01*
X534392Y565499D01*
Y568758D01*
X534534Y568900D01*
G01X538581Y579810D02*
Y575075D01*
X538355Y574849D01*
Y574799D01*
G01X498423Y561700D02*
Y564569D01*
X497592Y565400D01*
Y568769D01*
X497723Y568900D01*
G01X501770Y579810D02*
Y575075D01*
X501544Y574849D01*
Y574799D01*
G01X535234Y599500D02*
Y602457D01*
X534392Y603299D01*
Y606558D01*
X534534Y606700D01*
G01X498423Y599500D02*
Y602369D01*
X497592Y603200D01*
Y606569D01*
X497723Y606700D01*
G01X501770Y617610D02*
Y612875D01*
X501544Y612649D01*
Y612599D01*
G01X538581Y617610D02*
Y612875D01*
X538355Y612649D01*
Y612599D01*
G01X575392Y3233D02*
Y-1525D01*
X575166Y-1751D01*
Y-1801D01*
G01X572045Y22923D02*
Y25747D01*
X571192Y26600D01*
Y29947D01*
X571345Y30100D01*
G01X572045Y-14877D02*
Y-12053D01*
X571192Y-11200D01*
Y-7853D01*
X571345Y-7700D01*
G01X575166Y73799D02*
Y73849D01*
X575392Y74075D01*
Y78833D01*
G01X575166Y35999D02*
Y36049D01*
X575392Y36275D01*
Y41033D01*
G01X572045Y60723D02*
Y63547D01*
X571192Y64400D01*
Y67747D01*
X571345Y67900D01*
G01X572045Y523900D02*
Y526747D01*
X571192Y527600D01*
Y530947D01*
X571345Y531100D01*
G01X575392Y542010D02*
Y537275D01*
X575166Y537049D01*
Y536999D01*
G01X575392Y579810D02*
Y575075D01*
X575166Y574849D01*
Y574799D01*
G01X572045Y561700D02*
Y564547D01*
X571192Y565400D01*
Y568747D01*
X571345Y568900D01*
G01X572045Y599500D02*
Y602347D01*
X571192Y603200D01*
Y606547D01*
X571345Y606700D01*
G01X575392Y617610D02*
Y612875D01*
X575166Y612649D01*
Y612599D01*
G01X782567Y30100D02*
X782500Y30033D01*
Y26500D01*
X783267Y25733D01*
Y22923D01*
X783269D01*
G01Y-14877D02*
X783267D01*
Y-12067D01*
X782500Y-11300D01*
Y-7767D01*
X782567Y-7700D01*
G01Y67900D02*
X782500Y67833D01*
Y64300D01*
X783267Y63533D01*
Y60723D01*
X783269D01*
G01Y523900D02*
X783267Y523923D01*
Y526733D01*
X782500Y527500D01*
Y531033D01*
X782567Y531100D01*
G01X783269Y561700D02*
X783267Y561723D01*
Y564533D01*
X782500Y565300D01*
Y568833D01*
X782567Y568900D01*
G01X783269Y599500D02*
X783267Y599523D01*
Y602333D01*
X782500Y603100D01*
Y606633D01*
X782567Y606700D01*
G01X820080Y22923D02*
X820078D01*
G01X819378Y30100D02*
X819200Y29922D01*
Y26699D01*
X820078Y25821D01*
Y22923D01*
G01X820080Y-14877D02*
X820078D01*
Y-11979D01*
X819200Y-11101D01*
Y-7878D01*
X819378Y-7700D01*
G01X820080Y60723D02*
X820078D01*
G01X819378Y67900D02*
X819200Y67722D01*
Y64499D01*
X820078Y63621D01*
Y60723D01*
G01X820080Y523900D02*
X820078Y523923D01*
Y526821D01*
X819200Y527699D01*
Y530922D01*
X819378Y531100D01*
G01X820080Y561700D02*
X820078Y561723D01*
Y564621D01*
X819200Y565499D01*
Y568722D01*
X819378Y568900D01*
G01X820080Y599500D02*
X820078Y599523D01*
Y602421D01*
X819200Y603299D01*
Y606522D01*
X819378Y606700D01*
G01X897049Y3233D02*
X897047D01*
G01X893702Y-14877D02*
X893700D01*
Y-11999D01*
X892900Y-11199D01*
Y-7800D01*
X893000Y-7700D01*
G01X856189Y30100D02*
X856100Y30011D01*
Y27300D01*
G01Y-10500D02*
Y-7789D01*
X856189Y-7700D01*
G01X860236Y3233D02*
Y-1525D01*
X860010Y-1751D01*
Y-1801D01*
G01X893700Y22923D02*
Y25801D01*
X892900Y26601D01*
Y30000D01*
X893000Y30100D01*
G01X897047Y3233D02*
Y-1525D01*
X896821Y-1751D01*
Y-1801D01*
G01X897049Y78833D02*
X897047D01*
G01X896821Y73799D02*
Y73849D01*
X897047Y74075D01*
Y78833D01*
G01X897049Y41033D02*
X897047D01*
G01X893702Y60723D02*
X893700D01*
G01X893000Y67900D02*
X892900Y67800D01*
Y64401D01*
X893700Y63601D01*
Y60723D01*
G01X860238Y78833D02*
X860236D01*
G01X860010Y73799D02*
Y73849D01*
X860236Y74075D01*
Y78833D01*
G01X856189Y67900D02*
X856100Y67811D01*
Y65100D01*
G01X860238Y41033D02*
X860236D01*
G01X860010Y35999D02*
Y36049D01*
X860236Y36275D01*
Y41033D01*
G01X897047D02*
Y36275D01*
X896821Y36049D01*
Y35999D01*
G01X893702Y523900D02*
X893700Y523923D01*
Y526801D01*
X892900Y527601D01*
Y531000D01*
X893000Y531100D01*
G01X856100Y528300D02*
Y531011D01*
X856189Y531100D01*
G01X893702Y561700D02*
X893700Y561723D01*
Y564601D01*
X892900Y565401D01*
Y568800D01*
X893000Y568900D01*
G01X897049Y579810D02*
X897047D01*
Y575075D01*
X896821Y574849D01*
Y574799D01*
G01X897049Y542010D02*
X897047D01*
Y537275D01*
X896821Y537049D01*
Y536999D01*
G01X860238Y579810D02*
X860236D01*
Y575075D01*
X860010Y574849D01*
Y574799D01*
G01X856100Y566100D02*
Y568811D01*
X856189Y568900D01*
G01X860238Y542010D02*
X860236D01*
Y537275D01*
X860010Y537049D01*
Y536999D01*
G01X893702Y599500D02*
X893700Y599523D01*
Y602401D01*
X892900Y603201D01*
Y606600D01*
X893000Y606700D01*
G01X856100Y603900D02*
Y606611D01*
X856189Y606700D01*
G01X860238Y617610D02*
X860236D01*
Y612875D01*
X860010Y612649D01*
Y612599D01*
G01X896821D02*
Y612649D01*
X897047Y612875D01*
Y617610D01*
X897049D01*
G01X930513Y-14877D02*
X930511D01*
Y-12011D01*
X929600Y-11100D01*
Y-7911D01*
X929811Y-7700D01*
G01X930511Y22923D02*
Y25789D01*
X929600Y26700D01*
Y29889D01*
X929811Y30100D01*
G01X933858Y3233D02*
Y-1525D01*
X933632Y-1751D01*
Y-1801D01*
G01X933860Y78833D02*
X933858D01*
G01X933632Y73799D02*
Y73849D01*
X933858Y74075D01*
Y78833D01*
G01X929811Y67900D02*
X929600Y67689D01*
Y64500D01*
X930511Y63589D01*
Y60723D01*
G01X933860Y41033D02*
X933858D01*
G01X933632Y35999D02*
Y36049D01*
X933858Y36275D01*
Y41033D01*
G01X930513Y523900D02*
X930511Y523923D01*
Y526789D01*
X929600Y527700D01*
Y530889D01*
X929811Y531100D01*
G01X933860Y579810D02*
X933858D01*
Y575075D01*
X933632Y574849D01*
Y574799D01*
G01X930513Y561700D02*
X930511Y561723D01*
Y564589D01*
X929600Y565500D01*
Y568689D01*
X929811Y568900D01*
G01X933860Y542010D02*
X933858D01*
Y537275D01*
X933632Y537049D01*
Y536999D01*
G01X930513Y599500D02*
X930511Y599523D01*
Y602389D01*
X929600Y603300D01*
Y606489D01*
X929811Y606700D01*
G01X933632Y612599D02*
Y612649D01*
X933858Y612875D01*
Y617610D01*
X933860D01*
G01X1148031Y22923D02*
Y25769D01*
X1147200Y26600D01*
Y29969D01*
X1147331Y30100D01*
G01X1148033Y-14877D02*
X1148031D01*
Y-12031D01*
X1147200Y-11200D01*
Y-7831D01*
X1147331Y-7700D01*
G01X1111222Y-14877D02*
X1111220D01*
Y-12019D01*
X1110300Y-11099D01*
Y-7920D01*
X1110520Y-7700D01*
G01X1151378Y3233D02*
Y-1525D01*
X1151152Y-1751D01*
Y-1801D01*
G01X1111220Y22923D02*
Y25781D01*
X1110300Y26701D01*
Y29880D01*
X1110520Y30100D01*
G01X1114566Y3233D02*
Y-1525D01*
X1114340Y-1751D01*
Y-1801D01*
G01X1151380Y78833D02*
X1151378D01*
G01X1151152Y73799D02*
Y73849D01*
X1151378Y74075D01*
Y78833D01*
G01X1151380Y41033D02*
X1151378D01*
G01X1148033Y60723D02*
X1148031D01*
G01X1147331Y67900D02*
X1147200Y67769D01*
Y64400D01*
X1148031Y63569D01*
Y60723D01*
G01X1114568Y78833D02*
X1114566D01*
G01X1114340Y73799D02*
Y73849D01*
X1114566Y74075D01*
Y78833D01*
G01X1111222Y60723D02*
X1111220D01*
G01X1110520Y67900D02*
X1110300Y67680D01*
Y64501D01*
X1111220Y63581D01*
Y60723D01*
G01X1114568Y41033D02*
X1114566D01*
G01X1114340Y35999D02*
Y36049D01*
X1114566Y36275D01*
Y41033D01*
G01X1151378D02*
Y36275D01*
X1151152Y36049D01*
Y35999D01*
G01X1148033Y523900D02*
X1148031Y523923D01*
Y526769D01*
X1147200Y527600D01*
Y530969D01*
X1147331Y531100D01*
G01X1127954Y523900D02*
X1127952Y523923D01*
Y530949D01*
G01X1121261Y523900D02*
X1121259Y523923D01*
Y527130D01*
X1121258Y527131D01*
G01X1111222Y523900D02*
X1111220Y523923D01*
Y526781D01*
X1110300Y527701D01*
Y530880D01*
X1110520Y531100D01*
G01X1151380Y579810D02*
X1151378D01*
Y575075D01*
X1151152Y574849D01*
Y574799D01*
G01X1148033Y561700D02*
X1148031Y561723D01*
Y564569D01*
X1147200Y565400D01*
Y568769D01*
X1147331Y568900D01*
G01X1151380Y542010D02*
X1151378D01*
Y537275D01*
X1151152Y537049D01*
Y536999D01*
G01X1111222Y561700D02*
X1111220Y561723D01*
Y564581D01*
X1110300Y565501D01*
Y568680D01*
X1110520Y568900D01*
G01X1114568Y579810D02*
X1114566D01*
Y575075D01*
X1114340Y574849D01*
Y574799D01*
G01X1114568Y542010D02*
X1114566D01*
Y537275D01*
X1114340Y537049D01*
Y536999D01*
G01X1148033Y599500D02*
X1148031Y599523D01*
Y602369D01*
X1147200Y603200D01*
Y606569D01*
X1147331Y606700D01*
G01X1111222Y599500D02*
X1111220Y599523D01*
Y602381D01*
X1110300Y603301D01*
Y606480D01*
X1110520Y606700D01*
G01X1107876Y617610D02*
Y612651D01*
X1107874Y612649D01*
G01X1114568Y617610D02*
Y612827D01*
X1114340Y612599D01*
G01X1124608Y617610D02*
Y612651D01*
X1124606Y612649D01*
G01X1131301Y617610D02*
Y612651D01*
X1131299Y612649D01*
G01X1137994Y617610D02*
Y612601D01*
X1137992Y612599D01*
G01X1144687Y617610D02*
Y612651D01*
X1144685Y612649D01*
G01X1151380Y617610D02*
Y612827D01*
X1151152Y612599D01*
G01X1184844Y-14877D02*
X1184842D01*
Y-11943D01*
X1184000Y-11101D01*
Y-7842D01*
X1184142Y-7700D01*
G01X1188191Y3233D02*
X1188189D01*
G01X1187963Y-1801D02*
Y-1751D01*
X1188189Y-1525D01*
Y3233D01*
G01X1184842Y22923D02*
Y25857D01*
X1184000Y26699D01*
Y29958D01*
X1184142Y30100D01*
G01X1188191Y78833D02*
X1188189D01*
G01X1187963Y73799D02*
Y73849D01*
X1188189Y74075D01*
Y78833D01*
G01X1188191Y41033D02*
X1188189D01*
G01X1184844Y60723D02*
X1184842D01*
G01X1184142Y67900D02*
X1184000Y67758D01*
Y64499D01*
X1184842Y63657D01*
Y60723D01*
G01X1188189Y41033D02*
Y36275D01*
X1187963Y36049D01*
Y35999D01*
G01X1184844Y523900D02*
X1184842Y523923D01*
Y526857D01*
X1184000Y527699D01*
Y530958D01*
X1184142Y531100D01*
G01X1188191Y579810D02*
X1188189D01*
Y575075D01*
X1187963Y574849D01*
Y574799D01*
G01X1184844Y561700D02*
X1184842Y561723D01*
Y564657D01*
X1184000Y565499D01*
Y568758D01*
X1184142Y568900D01*
G01X1188191Y542010D02*
X1188189D01*
Y537275D01*
X1187963Y537049D01*
Y536999D01*
G01X1184844Y599500D02*
X1184842Y599523D01*
Y602457D01*
X1184000Y603299D01*
Y606558D01*
X1184142Y606700D01*
G01X1161419Y617610D02*
Y612651D01*
X1161417Y612649D01*
G01X1188191Y617610D02*
X1188189D01*
Y612875D01*
X1187963Y612649D01*
Y612599D01*
G01X1224774Y-1801D02*
Y-1751D01*
X1225000Y-1525D01*
Y3233D01*
G01X1221655Y-14877D02*
X1221653D01*
Y-12053D01*
X1220800Y-11200D01*
Y-7853D01*
X1220953Y-7700D01*
G01X1221653Y22923D02*
Y25747D01*
X1220800Y26600D01*
Y29947D01*
X1220953Y30100D01*
G01X1225002Y78833D02*
X1225000D01*
G01X1224774Y73799D02*
Y73849D01*
X1225000Y74075D01*
Y78833D01*
G01X1225002Y41033D02*
X1225000D01*
G01X1220953Y67900D02*
X1220800Y67747D01*
Y64400D01*
X1221653Y63547D01*
Y60723D01*
G01X1225000Y41033D02*
Y36275D01*
X1224774Y36049D01*
Y35999D01*
G01X1221655Y523900D02*
X1221653Y523923D01*
Y526747D01*
X1220800Y527600D01*
Y530947D01*
X1220953Y531100D01*
G01X1225002Y579810D02*
X1225000D01*
Y575075D01*
X1224774Y574849D01*
Y574799D01*
G01X1221655Y561700D02*
X1221653Y561723D01*
Y564547D01*
X1220800Y565400D01*
Y568747D01*
X1220953Y568900D01*
G01X1225002Y542010D02*
X1225000D01*
Y537275D01*
X1224774Y537049D01*
Y536999D01*
G01X1221655Y599500D02*
X1221653Y599523D01*
Y602347D01*
X1220800Y603200D01*
Y606547D01*
X1220953Y606700D01*
G01X1224774Y612599D02*
Y612649D01*
X1225000Y612875D01*
Y617610D01*
X1225002D01*
G01X1626313Y153312D02*
X1624764Y154861D01*
G01X1599104Y584396D02*
X1600788Y586080D01*
X1602551D01*
X1603951Y587480D01*
Y589465D01*
X1601890Y591526D01*
X1601504D01*
G01X1665709Y154861D02*
X1667348Y156500D01*
G01X1768720Y123250D02*
X1758289D01*
X1757689Y123850D01*
G01X1768720Y132250D02*
X1752389D01*
G01X1752189Y136750D02*
X1768720D01*
G01X1755089Y150750D02*
X1768720D01*
G01X1718689Y162281D02*
Y159550D01*
G01X1723189Y162281D02*
Y159550D01*
G01X1727689Y162281D02*
Y159550D01*
G01X1732189Y162281D02*
Y159550D01*
G01X1714189Y162281D02*
Y159550D01*
G01X1736689Y162281D02*
Y159550D01*
X1456476Y278327D03*
X1443878Y268878D03*
X1453327Y278327D03*
X1450177Y275177D03*
X1447028Y272028D03*
X1453327Y275177D03*
Y268878D03*
X1447028D03*
X1450177Y272028D03*
X1456476D03*
Y275177D03*
X1450177Y268878D03*
X1453327Y272028D03*
X1456476Y268878D03*
X1459626Y272028D03*
Y278327D03*
Y275177D03*
Y268878D03*
X1462776Y272028D03*
Y275177D03*
Y278327D03*
Y268878D03*
X1447028Y278327D03*
X1443878Y275177D03*
Y278327D03*
Y272028D03*
X1447028Y275177D03*
X1450177Y278327D03*
X1456476Y306673D03*
X1453327Y303524D03*
X1462776Y294075D03*
Y290925D03*
X1453327Y281476D03*
X1462776Y297224D03*
Y287776D03*
X1443878Y316122D03*
X1459626Y284626D03*
X1456476Y281476D03*
X1447028Y312972D03*
X1450177Y309823D03*
X1453327Y306673D03*
X1456476Y303524D03*
X1459626Y300374D03*
X1462776Y284626D03*
Y281476D03*
X1459626D03*
X1453327Y294075D03*
X1459626Y290925D03*
X1443878Y297224D03*
X1447028Y294075D03*
X1450177D03*
X1443878D03*
Y290925D03*
X1450177D03*
X1456476Y294075D03*
X1453327Y290925D03*
X1447028D03*
X1443878Y287776D03*
X1456476Y290925D03*
X1459626Y287776D03*
X1450177D03*
X1447028D03*
X1453327D03*
X1456476Y284626D03*
X1443878D03*
X1450177D03*
X1456476Y287776D03*
X1453327Y284626D03*
X1447028D03*
X1443878Y281476D03*
X1450177D03*
X1447028D03*
X1443878Y312972D03*
X1447028Y309823D03*
X1450177Y306673D03*
X1443878D03*
Y309823D03*
X1447028Y306673D03*
Y303524D03*
X1450177D03*
X1453327Y300374D03*
X1459626Y297224D03*
X1443878Y303524D03*
X1447028Y300374D03*
X1456476Y297224D03*
X1453327D03*
X1450177Y300374D03*
X1443878D03*
X1456476D03*
X1459626Y294075D03*
X1447028Y297224D03*
X1450177D03*
Y312972D03*
X1447028Y316122D03*
X1453327Y309823D03*
X1456476Y312972D03*
X1453327Y316122D03*
X1456476Y309823D03*
X1450177Y316122D03*
X1453327Y312972D03*
X1456476Y316122D03*
X1459626Y312972D03*
Y306673D03*
X1462776Y303524D03*
X1459626Y309823D03*
Y316122D03*
Y303524D03*
X1462776Y306673D03*
Y312972D03*
Y309823D03*
Y300374D03*
Y316122D03*
X1478524Y278327D03*
X1491122Y268878D03*
X1487972D03*
X1481673Y278327D03*
X1484823Y275177D03*
X1487972Y272028D03*
X1484823D03*
X1478524D03*
X1481673Y275177D03*
X1465925Y272028D03*
Y275177D03*
Y268878D03*
Y278327D03*
X1469075D03*
Y268878D03*
Y275177D03*
Y272028D03*
X1472224Y268878D03*
Y278327D03*
Y275177D03*
Y272028D03*
X1475374Y268878D03*
Y275177D03*
Y278327D03*
X1481673Y272028D03*
X1484823Y268878D03*
X1475374Y272028D03*
X1478524Y268878D03*
Y275177D03*
X1481673Y268878D03*
X1487972Y278327D03*
X1491122Y275177D03*
X1487972D03*
X1491122Y272028D03*
Y278327D03*
X1484823D03*
X1481673Y281476D03*
X1472224Y290925D03*
Y294075D03*
X1481673Y303524D03*
X1478524Y306673D03*
X1469075Y297224D03*
X1465925D03*
Y287776D03*
X1469075D03*
X1472224Y297224D03*
Y287776D03*
X1491122Y316122D03*
X1475374Y284626D03*
X1478524Y281476D03*
X1487972Y312972D03*
X1484823Y309823D03*
X1481673Y306673D03*
X1478524Y303524D03*
X1475374Y300374D03*
X1465925Y294075D03*
X1469075D03*
X1465925Y290925D03*
X1469075D03*
X1465925Y284626D03*
X1469075D03*
X1465925Y281476D03*
X1469075D03*
X1472224Y284626D03*
X1475374Y281476D03*
X1472224D03*
X1481673Y294075D03*
X1478524Y290925D03*
X1491122Y297224D03*
X1487972Y294075D03*
X1484823D03*
X1491122D03*
Y290925D03*
X1484823D03*
X1475374Y294075D03*
X1481673Y290925D03*
X1487972D03*
X1491122Y287776D03*
X1475374Y290925D03*
X1478524Y284626D03*
X1484823Y287776D03*
X1487972D03*
X1481673D03*
X1478524D03*
X1491122Y284626D03*
X1484823D03*
X1475374Y287776D03*
X1481673Y284626D03*
X1487972D03*
X1491122Y281476D03*
X1484823D03*
X1487972D03*
Y309823D03*
X1491122Y312972D03*
X1484823Y306673D03*
X1487972Y303524D03*
X1491122Y309823D03*
X1487972Y306673D03*
X1491122D03*
X1484823Y303524D03*
X1481673Y300374D03*
X1478524Y297224D03*
X1491122Y303524D03*
X1487972Y300374D03*
X1478524D03*
X1481673Y297224D03*
X1484823Y300374D03*
X1491122D03*
X1475374Y297224D03*
X1478524Y294075D03*
X1487972Y297224D03*
X1484823D03*
X1472224Y306673D03*
Y303524D03*
Y309823D03*
Y312972D03*
Y300374D03*
X1475374Y306673D03*
Y316122D03*
Y309823D03*
X1481673Y312972D03*
X1484823Y316122D03*
X1475374Y312972D03*
X1478524Y316122D03*
Y309823D03*
Y312972D03*
X1484823D03*
X1487972Y316122D03*
X1481673D03*
Y309823D03*
X1465925Y303524D03*
Y312972D03*
Y306673D03*
X1469075Y303524D03*
X1465925Y309823D03*
Y316122D03*
Y300374D03*
X1469075Y306673D03*
Y316122D03*
Y309823D03*
Y300374D03*
X1475374Y303524D03*
X1469075Y312972D03*
X1472224Y316122D03*
X1484193Y371161D03*
X1481105D03*
X1475098Y381068D03*
X1487879Y368287D03*
X1477972Y374294D03*
Y377382D03*
X1484193Y493839D03*
X1481105D03*
X1475098Y483932D03*
X1487879Y496713D03*
X1477972Y487618D03*
Y490706D03*
X1573895Y371161D03*
X1570807D03*
X1567121Y368287D03*
X1579902Y381068D03*
X1577028Y377382D03*
Y374294D03*
X1573895Y493839D03*
X1570807D03*
X1567121Y496713D03*
X1579902Y483932D03*
X1577028Y490706D03*
Y487618D03*
X1624764Y123365D03*
X1627914D03*
X1634213Y120215D03*
Y117066D03*
X1618465Y126514D03*
Y123365D03*
Y135963D03*
Y132814D03*
X1643662Y154861D03*
X1640512Y120215D03*
Y154861D03*
X1631064Y123365D03*
X1624764Y154861D03*
X1621615Y151711D03*
X1618465Y148562D03*
Y145412D03*
Y142262D03*
X1649961Y148562D03*
X1646812Y120215D03*
Y154861D03*
X1643662Y120215D03*
X1618465Y139113D03*
X1634213Y151711D03*
Y154861D03*
X1649961Y126514D03*
Y145412D03*
Y142262D03*
Y139113D03*
Y132814D03*
Y135963D03*
X1631064Y154861D03*
X1627914D03*
X1621615Y129664D03*
Y126514D03*
Y123365D03*
Y148562D03*
Y145412D03*
Y142262D03*
Y139113D03*
Y135963D03*
X1646812Y123365D03*
Y151711D03*
X1643662Y129664D03*
Y123365D03*
Y151711D03*
X1621615Y132814D03*
X1643662Y145412D03*
Y142262D03*
Y139113D03*
Y135963D03*
Y132814D03*
X1640512Y123365D03*
Y151711D03*
X1634213Y123365D03*
X1627914Y151711D03*
X1624764D03*
X1618465Y120215D03*
X1609016D03*
X1615316Y117066D03*
X1649961Y123365D03*
Y120215D03*
Y151711D03*
X1640512Y129664D03*
Y145412D03*
Y142262D03*
Y139113D03*
Y135963D03*
Y132814D03*
X1637363Y129664D03*
Y123365D03*
Y120215D03*
Y117066D03*
Y113916D03*
Y110766D03*
Y107617D03*
Y154861D03*
Y151711D03*
Y145412D03*
Y142262D03*
Y139113D03*
Y135963D03*
Y132814D03*
Y104467D03*
X1634213Y129664D03*
Y145412D03*
Y142262D03*
Y139113D03*
Y135963D03*
Y132814D03*
X1631064Y129664D03*
Y151711D03*
Y145412D03*
Y142262D03*
Y139113D03*
Y135963D03*
Y132814D03*
X1627914Y129664D03*
Y117066D03*
Y145412D03*
Y142262D03*
Y139113D03*
Y135963D03*
Y132814D03*
X1624764Y120215D03*
X1621615D03*
X1618465Y151711D03*
X1615316Y126514D03*
X1631064Y113916D03*
Y117066D03*
Y120215D03*
X1615316Y113916D03*
X1624764Y107617D03*
Y104467D03*
X1627914D03*
Y120215D03*
X1605867D03*
X1602717D03*
X1605867Y123365D03*
X1602717D03*
Y126514D03*
X1605867D03*
X1609016Y123365D03*
Y126514D03*
X1612166Y135963D03*
Y139113D03*
X1609016Y132814D03*
Y129664D03*
X1615316Y135963D03*
X1649961Y113916D03*
Y110766D03*
X1646812D03*
Y113916D03*
X1640512Y117066D03*
Y113916D03*
Y110766D03*
X1634213Y107617D03*
X1646812D03*
X1602717Y148562D03*
Y145412D03*
X1609016Y148562D03*
X1605867D03*
X1609016Y151711D03*
X1605867D03*
X1615316Y148562D03*
Y145412D03*
X1612166Y148562D03*
Y151711D03*
X1615316Y154861D03*
Y151711D03*
X1631064Y110766D03*
X1627914Y113916D03*
Y110766D03*
Y107617D03*
X1621615Y110766D03*
X1618465Y107617D03*
X1621615Y113916D03*
Y117066D03*
X1615316Y110766D03*
X1618465D03*
X1615316Y104467D03*
Y107617D03*
X1618465Y117066D03*
X1624764Y113916D03*
Y110766D03*
X1621615Y104467D03*
X1624764Y117066D03*
X1618465Y104467D03*
X1621615Y107617D03*
X1618465Y113916D03*
X1631064Y104467D03*
Y107617D03*
X1612166Y110766D03*
Y113916D03*
Y117066D03*
X1615316Y120215D03*
X1612166Y107617D03*
Y104467D03*
Y123365D03*
X1615316D03*
X1602717Y117066D03*
X1618465Y129664D03*
X1615316D03*
X1605867Y117066D03*
X1609016Y113916D03*
Y117066D03*
X1612166Y120215D03*
X1602717Y113916D03*
X1605867D03*
X1615316Y132814D03*
X1612166Y126514D03*
X1649961Y154861D03*
Y117066D03*
X1646812D03*
X1643662D03*
Y110766D03*
Y113916D03*
X1649961Y104467D03*
Y107617D03*
X1602717Y151711D03*
X1605867Y154861D03*
X1602717D03*
X1609016D03*
X1612166D03*
X1621615D03*
X1618465D03*
X1605867Y142262D03*
X1609016D03*
X1649961Y129664D03*
X1605867Y132814D03*
Y129664D03*
X1602717D03*
Y132814D03*
Y135963D03*
X1646812Y104467D03*
X1643662Y107617D03*
Y104467D03*
X1640512D03*
Y107617D03*
X1634213Y104467D03*
Y113916D03*
Y110766D03*
X1605867Y135963D03*
X1609016D03*
X1615316Y139113D03*
X1612166Y132814D03*
Y129664D03*
X1605867Y139113D03*
X1602717D03*
X1609016D03*
X1602717Y142262D03*
X1609016Y145412D03*
X1615316Y142262D03*
X1612166D03*
Y145412D03*
X1605867D03*
X1627914Y170609D03*
Y167459D03*
X1621615Y161160D03*
X1609016Y158010D03*
Y161160D03*
X1615316D03*
X1602717D03*
X1643662Y167459D03*
Y170609D03*
X1646812Y167459D03*
Y170609D03*
Y161160D03*
X1643662Y158010D03*
X1646812D03*
X1649961Y161160D03*
X1612166Y158010D03*
X1605867D03*
X1602717D03*
X1624764D03*
Y161160D03*
X1627914Y158010D03*
Y161160D03*
X1605867D03*
X1612166D03*
X1615316Y158010D03*
X1618465D03*
X1646812Y164310D03*
X1649961Y170609D03*
Y167459D03*
X1640512Y161160D03*
X1643662D03*
X1640512Y158010D03*
X1649961Y164310D03*
Y158010D03*
X1634213Y167459D03*
Y170609D03*
X1637363Y167459D03*
Y170609D03*
X1634213Y164310D03*
X1631064D03*
Y167459D03*
Y170609D03*
X1643662Y164310D03*
X1637363D03*
Y161160D03*
Y158010D03*
X1640512Y164310D03*
Y170609D03*
Y167459D03*
X1621615Y158010D03*
X1615316Y164310D03*
X1612166Y167459D03*
Y164310D03*
X1618465D03*
X1615316Y167459D03*
X1618465Y161160D03*
X1624764Y164310D03*
Y170609D03*
Y167459D03*
X1627914Y164310D03*
X1631064Y158010D03*
X1634213D03*
Y161160D03*
X1631064D03*
X1621615Y170609D03*
X1618465D03*
Y167459D03*
X1615316Y170609D03*
X1612166D03*
X1621615Y164310D03*
Y167459D03*
X1656260Y154861D03*
X1662560D03*
X1659410D03*
X1665709Y129664D03*
X1656260Y126514D03*
Y151711D03*
Y145412D03*
Y139113D03*
Y132814D03*
X1653111Y120215D03*
Y135963D03*
X1665709Y123365D03*
Y148562D03*
Y142262D03*
Y135963D03*
Y154861D03*
X1656260Y120215D03*
X1659410D03*
X1662560Y117066D03*
Y120215D03*
X1668859Y117066D03*
X1665709D03*
X1659410D03*
X1656260Y113916D03*
X1659410D03*
X1665709D03*
X1662560D03*
X1668859D03*
X1656260Y117066D03*
X1653111Y113916D03*
Y117066D03*
X1659410Y110766D03*
X1653111D03*
X1656260D03*
X1659410Y107617D03*
X1656260D03*
X1659410Y104467D03*
X1656260D03*
X1653111Y107617D03*
Y104467D03*
Y154861D03*
X1662560Y139113D03*
X1668859Y154861D03*
X1659410Y139113D03*
X1656260Y135963D03*
X1659410D03*
X1668859Y120215D03*
Y123365D03*
Y132814D03*
Y129664D03*
X1662560Y126514D03*
X1665709D03*
X1656260Y129664D03*
X1659410D03*
X1662560D03*
X1653111D03*
X1665709Y132814D03*
X1662560D03*
X1653111Y123365D03*
X1656260D03*
X1659410D03*
X1665709Y120215D03*
X1659410Y126514D03*
X1662560Y123365D03*
X1659410Y132814D03*
X1653111D03*
X1668859Y126514D03*
X1653111D03*
X1665709Y139113D03*
X1662560Y135963D03*
X1668859Y139113D03*
Y135963D03*
Y142262D03*
X1659410D03*
X1662560D03*
X1653111Y139113D03*
Y151711D03*
X1662560D03*
X1659410D03*
X1665709D03*
X1668859D03*
X1656260Y148562D03*
X1659410D03*
X1653111Y145412D03*
X1659410D03*
X1653111Y148562D03*
X1662560D03*
X1668859D03*
X1662560Y145412D03*
X1665709D03*
X1653111Y142262D03*
X1668859Y145412D03*
X1656260Y142262D03*
X1653111Y158010D03*
X1668859D03*
X1662560D03*
X1656260D03*
X1659410D03*
Y167459D03*
X1656260Y170609D03*
X1659410D03*
X1653111Y167459D03*
Y164310D03*
X1659410D03*
X1653111Y161160D03*
X1656260Y164310D03*
Y161160D03*
X1659410D03*
X1662560D03*
X1665709D03*
X1653111Y170609D03*
X1656260Y167459D03*
X1668859Y161160D03*
X1665709Y158010D03*
X1718591Y115876D03*
X1740638Y131624D03*
X1718591Y122175D03*
X1743787D03*
Y115876D03*
X1721740Y112726D03*
X1737488D03*
X1721740Y109577D03*
X1740638D03*
X1718591Y106427D03*
X1721740Y100128D03*
X1740638D03*
X1743787Y147372D03*
Y137923D03*
X1718591Y134774D03*
Y128474D03*
X1743787D03*
X1721740Y119026D03*
X1718591Y112726D03*
X1743787D03*
X1740638Y103278D03*
X1743787Y134774D03*
X1718591Y144222D03*
X1743787Y103278D03*
X1721740Y125325D03*
X1740638D03*
X1718591Y119026D03*
X1743787D03*
X1721740Y115876D03*
X1740638D03*
X1718591Y109577D03*
X1743787Y106427D03*
X1718591Y100128D03*
X1743787D03*
X1718591Y147372D03*
X1743787Y144222D03*
X1718591Y131624D03*
X1743787D03*
X1718591Y125325D03*
X1743787D03*
X1724890Y119026D03*
X1743787Y109577D03*
X1718591Y103278D03*
X1737488D03*
X1718591Y137923D03*
X1743787Y141073D03*
X1721740Y131624D03*
X1737488Y147372D03*
Y128474D03*
X1724890Y147372D03*
Y109577D03*
X1737488D03*
X1721740Y106427D03*
X1740638D03*
X1724890D03*
X1737488D03*
X1721740Y103278D03*
X1737488Y100128D03*
X1724890Y103278D03*
Y100128D03*
X1737488Y119026D03*
Y115876D03*
X1724890Y125325D03*
X1737488D03*
X1721740Y122175D03*
X1740638D03*
X1724890D03*
X1737488D03*
X1724890Y115876D03*
X1740638Y119026D03*
Y112726D03*
X1724890D03*
Y131624D03*
Y128474D03*
X1721740D03*
X1740638D03*
X1721740Y134774D03*
X1740638D03*
X1721740Y137923D03*
X1740638D03*
X1718591Y141073D03*
X1737488Y131624D03*
X1724890Y144222D03*
X1740638D03*
X1721740D03*
X1740638Y141073D03*
X1721740D03*
X1737488Y137923D03*
X1724890D03*
X1737488Y144222D03*
X1721740Y147372D03*
X1724890Y134774D03*
X1740638Y147372D03*
X1737488Y134774D03*
X1724890Y141073D03*
X1737488D03*
G54D231*
G01X2200Y75650D02*
X4262D01*
G01X207281Y22923D02*
Y25811D01*
X206492Y26600D01*
Y27300D01*
G01X207281Y-14877D02*
Y-11989D01*
X206492Y-11200D01*
Y-10500D01*
G01Y65100D02*
Y64400D01*
X207281Y63611D01*
Y60723D01*
G01Y523900D02*
Y526811D01*
X206492Y527600D01*
Y528300D01*
G01X207281Y561700D02*
Y564611D01*
X206492Y565400D01*
Y566100D01*
G01X207281Y599500D02*
Y602411D01*
X206492Y603200D01*
Y603900D01*
G01X274619Y216909D02*
X276869D01*
G01X274619Y224709D02*
X276869D01*
G01X274619Y232509D02*
X276869D01*
G01X492442Y372197D02*
X494692D01*
G01X485682D02*
X487932D01*
G01X481172D02*
X478922D01*
G01X489062Y374146D02*
X491312D01*
G01X489062Y378047D02*
X491312D01*
G01X495822Y397546D02*
X498072D01*
G01X489062D02*
X491312D01*
G01X485682Y364396D02*
X487932D01*
G01X495822Y366347D02*
X498072D01*
G01X482302Y370247D02*
X484552D01*
G01X482302Y362447D02*
X484552D01*
G01X485682Y360496D02*
X487932D01*
G01X485682Y403396D02*
X487932D01*
G01X482302Y405347D02*
X484552D01*
G01X721000Y10652D02*
Y5000D01*
G01X676700Y16437D02*
X671048D01*
G01X720043Y584050D02*
Y589702D01*
G01X856100Y27300D02*
Y26600D01*
X856889Y25811D01*
Y22923D01*
G01X856891Y-14877D02*
X856889D01*
Y-11989D01*
X856100Y-11200D01*
Y-10500D01*
G01X856891Y60723D02*
X856889D01*
G01X856100Y65100D02*
Y64400D01*
X856889Y63611D01*
Y60723D01*
G01X856891Y523900D02*
X856889Y523923D01*
Y526811D01*
X856100Y527600D01*
Y528300D01*
G01X856891Y561700D02*
X856889Y561723D01*
Y564611D01*
X856100Y565400D01*
Y566100D01*
G01X856891Y599500D02*
X856889Y599523D01*
Y602411D01*
X856100Y603200D01*
Y603900D01*
G01X926477Y216909D02*
X924227D01*
G01X926477Y224709D02*
X924227D01*
G01X926477Y232509D02*
X924227D01*
G01X1148810Y340996D02*
X1151060D01*
G01X1152190Y339047D02*
X1154440D01*
G01X1130780Y372197D02*
X1128530D01*
G01X1135290D02*
X1137540D01*
G01X1142050D02*
X1144300D01*
G01X1138670Y374146D02*
X1140920D01*
G01X1138670Y378047D02*
X1140920D01*
G01X1155570Y387796D02*
X1157820D01*
G01X1145430Y397546D02*
X1147680D01*
G01X1138670D02*
X1140920D01*
G01X1131910Y362447D02*
X1134160D01*
G01X1131910Y370247D02*
X1134160D01*
G01X1155570Y352696D02*
X1157820D01*
G01X1148810Y348796D02*
X1151060D01*
G01X1145430Y366347D02*
X1147680D01*
G01X1148810Y368296D02*
X1151060D01*
G01X1154440Y366347D02*
X1152190D01*
G01X1135290Y364396D02*
X1137540D01*
G01X1135290Y360496D02*
X1137540D01*
G01X1155570D02*
X1157820D01*
G01X1152190Y358547D02*
X1154440D01*
G01X1135290Y403396D02*
X1137540D01*
G01X1131910Y405347D02*
X1134160D01*
G01X1185989Y339047D02*
X1188239D01*
G01X1194999Y335147D02*
X1192749D01*
G01X1194999Y331247D02*
X1192749D01*
G01X1196129Y340996D02*
X1198379D01*
G01X1185989Y335147D02*
X1188239D01*
G01X1172469D02*
X1174719D01*
G01X1175849Y337096D02*
X1178099D01*
G01X1167960Y339047D02*
X1165710D01*
G01X1162330Y337096D02*
X1164580D01*
G01X1185989Y366347D02*
X1188239D01*
G01X1189369Y348796D02*
X1191619D01*
G01X1194999Y346847D02*
X1192749D01*
G01X1194999Y354647D02*
X1192749D01*
G01X1202889Y360496D02*
X1205139D01*
G01X1199509Y350747D02*
X1201759D01*
G01X1162330Y372197D02*
X1164580D01*
G01X1169089D02*
X1171339D01*
G01X1179229Y374146D02*
X1181479D01*
G01X1165710Y397546D02*
X1165711Y397547D01*
X1167960D01*
G01X1158950Y397546D02*
X1161200D01*
G01X1169089Y399496D02*
X1171339D01*
G01X1172469Y354647D02*
X1174719D01*
G01X1169089Y348796D02*
X1171339D01*
G01X1165710Y370247D02*
X1167960D01*
G01X1158950D02*
X1161200D01*
G01X1175849Y364396D02*
X1178099D01*
G01X1167960Y362447D02*
X1165710D01*
G01X1179229Y346847D02*
X1181479D01*
G01X1169089Y360496D02*
X1171339D01*
G01X1169089Y356596D02*
X1171339D01*
G01X1162330D02*
X1164580D01*
G01X1188239Y378047D02*
X1185989D01*
G01X1191619Y360496D02*
X1189369D01*
G01X1175849Y403396D02*
X1178099D01*
G01X1162330D02*
X1164580D01*
G01X1557957Y270200D02*
X1556226Y268469D01*
X1553918D01*
G01X1560063Y268683D02*
X1557880Y266500D01*
X1553868D01*
G01X1620100Y150200D02*
X1621611Y151711D01*
X1621615D01*
G01X1649961Y135963D02*
X1651532Y137534D01*
G01X1632503Y343146D02*
X1629503Y346146D01*
G01X1625951Y346099D02*
X1629310D01*
G01D02*
X1629430Y346219D01*
X1629503Y346146D01*
G01X1656260Y126514D02*
X1656261D01*
X1657835Y124940D01*
G01X1717014Y108000D02*
X1718587Y106427D01*
X1718591D01*
G01X1737488Y112726D02*
X1739062Y114300D01*
X1739064D01*
G01X1742214Y111150D02*
Y111275D01*
X1743665Y112726D01*
X1743787D01*
G01X1745364Y120600D02*
X1743789Y122175D01*
X1743787D01*
G01X1742214Y126900D02*
X1743787Y128473D01*
Y128474D01*
G01X1742214Y98550D02*
X1740638Y100126D01*
Y100128D01*
G01X1720164Y126800D02*
X1718591Y128373D01*
Y128474D01*
G01X1720164Y133200D02*
X1718591Y134773D01*
Y134774D01*
G01Y122175D02*
X1720164Y120602D01*
Y120600D01*
G01X1723314Y117450D02*
Y117452D01*
X1721740Y119026D01*
G01X1723314Y111150D02*
X1721741Y109577D01*
X1721740D01*
G01X1718591Y112726D02*
Y112723D01*
X1720164Y111150D01*
G01D02*
X1721740Y112726D01*
G01X1720164Y97550D02*
Y98550D01*
X1721740Y100126D01*
Y100128D01*
G01X1745364Y145800D02*
X1743792Y147372D01*
X1743787D01*
G01Y137923D02*
X1749016D01*
X1750189Y136750D01*
X1752189D01*
G01X1745364Y114300D02*
X1743788Y115876D01*
X1743787D01*
G01X1742214Y101700D02*
X1740638Y103276D01*
Y103278D01*
G01X1739064Y108000D02*
X1740638Y109574D01*
Y109577D01*
G01X1718591Y137923D02*
X1717014Y139500D01*
G01X1743787Y134774D02*
X1746186D01*
X1746189Y134777D01*
G01X1743787Y109577D02*
Y109762D01*
X1745768Y111743D01*
G01X1745363Y108004D02*
X1743787Y106428D01*
Y106427D01*
G01X1737488Y103278D02*
Y103274D01*
X1735914Y101700D01*
G01X1740638Y115876D02*
X1742214Y114300D01*
G01X1740638Y125325D02*
X1740639D01*
X1742214Y123750D01*
G01X1743787Y125325D02*
X1743789D01*
X1745364Y123750D01*
G01X1721740Y125325D02*
Y125324D01*
X1723314Y123750D01*
G01X1718591Y125325D02*
X1720164Y123752D01*
Y123750D01*
G01X1718591Y119026D02*
Y119024D01*
X1720164Y117451D01*
G01D02*
X1721739Y115876D01*
X1721740D01*
G01X1724890Y119026D02*
X1726464Y117452D01*
Y117450D01*
G01X1743787Y144222D02*
X1743792D01*
X1745364Y142650D01*
G01X1746189Y131624D02*
X1743787D01*
G01Y119026D02*
X1743788D01*
X1745364Y117450D01*
G01X1718591Y131624D02*
X1718590D01*
X1717014Y133200D01*
G01X1718591Y109577D02*
X1718587D01*
X1717014Y111150D01*
G01X1718591Y103278D02*
X1718586D01*
X1717014Y104850D01*
G01Y97550D02*
Y98575D01*
X1718567Y100128D01*
X1718591D01*
G01X1743787D02*
Y100127D01*
X1745364Y98550D01*
G01X1743787Y103278D02*
X1745500Y104500D01*
G01X1891736Y190300D02*
X1890300D01*
X1889400Y191200D01*
G01X1966100Y94786D02*
X1966010Y94876D01*
Y99545D01*
X1964943Y100612D01*
X1963526D01*
G01Y98644D02*
Y97039D01*
X1962512Y96025D01*
X1958223D01*
G01D02*
X1957361Y95163D01*
G01X1921264Y153000D02*
Y155900D01*
G01X1911421D02*
Y153540D01*
X1911961Y153000D01*
G01X1905516Y155900D02*
Y153024D01*
X1905540Y153000D01*
G01X1967580Y104721D02*
X1965439Y102580D01*
X1963526D01*
X1496004Y374823D03*
X1499941D03*
X1503878D03*
X1507815D03*
X1511752D03*
X1515689D03*
X1519626D03*
Y371555D03*
X1523563Y374823D03*
X1527500D03*
X1476732Y387224D03*
Y399035D03*
X1480000Y387224D03*
Y395098D03*
Y399035D03*
X1481634Y385256D03*
Y389193D03*
Y393130D03*
Y401004D03*
X1481437Y376988D03*
X1481634Y381319D03*
X1484622Y375979D03*
X1488130Y374823D03*
X1492067D03*
X1494035Y369921D03*
Y373189D03*
X1490098D03*
X1486161D03*
X1492067Y371555D03*
X1482673Y374030D03*
X1488130Y371555D03*
X1490098Y369921D03*
X1483071Y378957D03*
X1480000Y383287D03*
X1478366Y381319D03*
Y385256D03*
X1476732Y383287D03*
X1481634Y397067D03*
X1478366D03*
X1480000Y379350D03*
X1525531Y373189D03*
X1523563Y371555D03*
X1521594Y369921D03*
X1525531D03*
X1527500Y371555D03*
X1521594Y373189D03*
X1499941Y371555D03*
X1509783Y369921D03*
X1497972D03*
Y373189D03*
X1505846Y369921D03*
X1517657Y373189D03*
Y369921D03*
X1505846Y373189D03*
X1507815Y371555D03*
X1503878D03*
X1515689D03*
X1501909Y369921D03*
X1513720Y373189D03*
X1511752Y371555D03*
X1501909Y373189D03*
X1513720Y369921D03*
X1509783Y373189D03*
X1496004Y371555D03*
X1478366Y389193D03*
X1476732Y395098D03*
X1480000Y391161D03*
X1478366Y393130D03*
X1476732Y391161D03*
X1480000Y402972D03*
X1478366Y401004D03*
X1476732Y402972D03*
Y410846D03*
Y414783D03*
Y450217D03*
X1478366Y404941D03*
Y420689D03*
Y428563D03*
Y432500D03*
Y440374D03*
X1480000Y410846D03*
Y414783D03*
Y450217D03*
X1481634Y404941D03*
Y408878D03*
Y412815D03*
Y416752D03*
Y420689D03*
Y424626D03*
Y428563D03*
Y432500D03*
Y436437D03*
Y440374D03*
Y444311D03*
Y448248D03*
Y452185D03*
Y456122D03*
Y460059D03*
Y463996D03*
X1478366D03*
X1476732Y462028D03*
X1480000D03*
X1478366Y460059D03*
X1476732Y458091D03*
X1480000D03*
X1478366Y456122D03*
X1476732Y454154D03*
X1480000D03*
X1478366Y452185D03*
X1476732Y446280D03*
Y442343D03*
X1478366Y448248D03*
X1480000Y446280D03*
X1478366Y444311D03*
X1480000Y442343D03*
Y430531D03*
X1476732D03*
X1478366Y412815D03*
X1476732Y422657D03*
Y426594D03*
X1478366Y416752D03*
X1480000Y406909D03*
Y422657D03*
Y426594D03*
X1478366Y408878D03*
X1476732Y406909D03*
X1480000Y438406D03*
X1476732D03*
X1480000Y418720D03*
X1476732D03*
X1480000Y434469D03*
X1476732D03*
X1478366Y424626D03*
Y436437D03*
X1527500Y490177D03*
Y493445D03*
X1496004Y490177D03*
X1499941D03*
X1503878D03*
X1507815D03*
X1511752D03*
Y493445D03*
X1515689Y490177D03*
X1519626D03*
X1523563D03*
X1525531Y491811D03*
Y495079D03*
X1507815Y493445D03*
X1478366Y483681D03*
X1481634Y471870D03*
Y483681D03*
Y467933D03*
Y475807D03*
Y479744D03*
X1488130Y490177D03*
Y493445D03*
X1490098Y491811D03*
Y495079D03*
X1492067Y490177D03*
X1484094Y484469D03*
X1482673Y490970D03*
X1476732Y469902D03*
X1480000D03*
X1478366Y467933D03*
X1476732Y465965D03*
X1480000D03*
X1476732Y481713D03*
X1480000D03*
X1478366Y479744D03*
X1476732Y477776D03*
X1480000D03*
X1478366Y475807D03*
X1476732Y473839D03*
X1480000D03*
X1478366Y471870D03*
X1509783Y495079D03*
Y491811D03*
X1486161D03*
X1484622Y489021D03*
X1517657Y495079D03*
Y491811D03*
X1519626Y493445D03*
X1521594Y495079D03*
Y491811D03*
X1523563Y493445D03*
X1492067D03*
X1494035Y495079D03*
Y491811D03*
X1496004Y493445D03*
X1497972Y495079D03*
Y491811D03*
X1499941Y493445D03*
X1501909Y495079D03*
Y491811D03*
X1503878Y493445D03*
X1505846Y495079D03*
Y491811D03*
X1513720Y495079D03*
Y491811D03*
X1515689Y493445D03*
X1481634Y487618D03*
X1480000Y485650D03*
X1576634Y397067D03*
X1562933Y374823D03*
X1566870D03*
X1571732Y379350D03*
X1570378Y375979D03*
X1573366Y389193D03*
Y385256D03*
Y393130D03*
Y397067D03*
Y401004D03*
Y381319D03*
X1576634Y393130D03*
X1558996Y374823D03*
Y371555D03*
X1531437Y374823D03*
X1533406Y369921D03*
Y373189D03*
X1535374Y374823D03*
X1539311D03*
X1543248D03*
X1547185D03*
X1551122D03*
X1555059D03*
X1529469Y369921D03*
X1531437Y371555D03*
X1529469Y373189D03*
X1566870Y371555D03*
X1564902Y373189D03*
Y369921D03*
X1573366Y377382D03*
X1562933Y371555D03*
X1560965Y369921D03*
X1568839Y373189D03*
X1575000Y391161D03*
X1578268Y387224D03*
X1575000D03*
X1576634Y389193D03*
X1560965Y373189D03*
X1578268Y391161D03*
Y383287D03*
X1575000D03*
X1576634Y381319D03*
Y385256D03*
X1572327Y374030D03*
X1575000Y379350D03*
X1578268Y402972D03*
X1576634Y401004D03*
X1575000Y402972D03*
X1553091Y369921D03*
X1535374Y371555D03*
X1541280Y369921D03*
X1543248Y371555D03*
X1537343Y369921D03*
X1539311Y371555D03*
X1557028Y373189D03*
Y369921D03*
X1545217D03*
X1555059Y371555D03*
X1541280Y373189D03*
X1551122Y371555D03*
X1549154Y373189D03*
X1553091D03*
X1547185Y371555D03*
X1549154Y369921D03*
X1545217Y373189D03*
X1537343D03*
X1575000Y399035D03*
X1578268D03*
Y395098D03*
X1575000D03*
X1576634Y412815D03*
Y460059D03*
X1578268Y438406D03*
Y454154D03*
X1575000D03*
X1573366Y404941D03*
Y408878D03*
Y412815D03*
Y416752D03*
Y420689D03*
Y424626D03*
Y428563D03*
Y432500D03*
Y436437D03*
Y440374D03*
Y444311D03*
Y448248D03*
Y452185D03*
Y456122D03*
Y460059D03*
Y463996D03*
X1575000Y438406D03*
X1576634Y404941D03*
X1575000Y406909D03*
X1576634Y408878D03*
X1578268Y406909D03*
X1575000Y410846D03*
X1578268D03*
Y442343D03*
X1576634Y440374D03*
Y448248D03*
X1575000Y446280D03*
X1576634Y452185D03*
X1575000Y442343D03*
X1576634Y444311D03*
X1578268Y446280D03*
Y450217D03*
X1575000D03*
X1578268Y418720D03*
X1576634Y424626D03*
X1575000Y430531D03*
X1576634Y428563D03*
Y420689D03*
X1575000Y418720D03*
X1578268Y414783D03*
Y426594D03*
X1575000Y414783D03*
X1576634Y436437D03*
X1578268Y430531D03*
Y422657D03*
X1576634Y432500D03*
X1578268Y434469D03*
X1575000D03*
Y426594D03*
Y422657D03*
X1576634Y416752D03*
X1575000Y462028D03*
X1576634Y463996D03*
X1578268Y462028D03*
X1575000Y458091D03*
X1578268D03*
X1576634Y456122D03*
X1562933Y490177D03*
Y493445D03*
X1564902Y491811D03*
Y495079D03*
X1571732Y485650D03*
X1573366Y467933D03*
Y471870D03*
Y475807D03*
Y479744D03*
X1555059Y490177D03*
X1558996D03*
X1531437D03*
X1535374D03*
Y493445D03*
X1539311Y490177D03*
X1543248D03*
X1547185D03*
Y493445D03*
X1549154Y491811D03*
Y495079D03*
X1551122Y490177D03*
X1568839Y491811D03*
X1572327Y490970D03*
X1537343Y491811D03*
Y495079D03*
X1541280Y491811D03*
Y495079D03*
X1543248Y493445D03*
X1545217Y491811D03*
Y495079D03*
X1539311Y493445D03*
X1533406Y495079D03*
Y491811D03*
X1529469Y495079D03*
Y491811D03*
X1531437Y493445D03*
X1551122D03*
X1553091Y491811D03*
Y495079D03*
X1555059Y493445D03*
X1557028Y491811D03*
Y495079D03*
X1558996Y493445D03*
X1560965Y491811D03*
Y495079D03*
X1570378Y489021D03*
X1566870Y493445D03*
X1575000Y465965D03*
Y481713D03*
X1576634Y467933D03*
Y479744D03*
X1575000Y469902D03*
Y477776D03*
X1576634Y471870D03*
Y475807D03*
X1573366Y487618D03*
X1575000Y485650D03*
X1573366Y483681D03*
X1575000Y473839D03*
X1578268Y465965D03*
Y481713D03*
Y469902D03*
Y477776D03*
X1576634Y483681D03*
X1578268Y473839D03*
X1566870Y490177D03*
G54D12*
G01X-14690Y551470D02*
X-15831Y550329D01*
Y547265D01*
G01X-11246Y587765D02*
X-14190D01*
X-15361Y586594D01*
Y583807D01*
G01D02*
Y579559D01*
X-15570Y579350D01*
G01X16600Y22344D02*
Y24544D01*
X16400Y24744D01*
G01X34597Y24567D02*
X31855D01*
X29854Y22566D01*
Y21862D01*
G01X16925Y53711D02*
Y55911D01*
X16625Y56211D01*
G01X2170Y51080D02*
Y48010D01*
X2940Y47240D01*
G01X4400Y71700D02*
X5600D01*
G01X34500Y51000D02*
X33001D01*
X31627Y52374D01*
X29943D01*
G01X38645Y172740D02*
X44291Y178386D01*
G01D02*
X49937Y184032D01*
G01X38645D02*
X44291Y178386D01*
G01D02*
X49937Y172740D01*
G01X-7615D02*
X-1969Y178386D01*
G01D02*
X3677Y184032D01*
G01X-7615D02*
X-1969Y178386D01*
G01D02*
X3677Y172740D01*
G01X34300Y482890D02*
X35118Y483708D01*
Y483851D01*
X36635Y485368D01*
X41200D01*
X41952Y484616D01*
X49208D01*
X52792Y488200D01*
X77080D01*
X83820Y481460D01*
G01X27300Y513000D02*
Y510440D01*
X27280Y510420D01*
G01X23800Y513000D02*
Y511350D01*
X22788Y510338D01*
G01X27300Y513000D02*
X23800D01*
G01X6500Y564000D02*
Y567000D01*
X6200Y567300D01*
G01X-10983Y551374D02*
X-12323D01*
X-12419Y551470D01*
X-14690D01*
G01X-7483Y551374D02*
X-6947D01*
X-5091Y549518D01*
G01X32867Y534919D02*
Y531671D01*
X30265Y529069D01*
X27765D01*
G01X33500Y580000D02*
X33922Y579578D01*
G01D02*
Y562532D01*
G01X-4100Y554400D02*
X-4578Y554878D01*
X-7342D01*
G01X-7746Y587765D02*
X-7077D01*
X-5681Y586369D01*
G01X25200Y562500D02*
X30390D01*
X30422Y562532D01*
G01X24265Y529069D02*
X20531D01*
X20500Y529100D01*
G01X-10331Y547265D02*
X-6886D01*
X-6410Y546789D01*
G01X-9861Y583807D02*
X-6578D01*
X-5719Y582948D01*
G01X-12450Y590965D02*
X-9785D01*
G01X56540Y-16808D02*
X60110D01*
X62486Y-19184D01*
G01X53340Y-16796D02*
X56528D01*
X56540Y-16808D01*
G01X108077Y86864D02*
Y84599D01*
X108385Y84291D01*
G01X106698Y219572D02*
Y215610D01*
G01X95100Y165300D02*
Y162300D01*
G01D02*
X97320D01*
X99250Y160370D01*
G01X108000Y249330D02*
Y250234D01*
X110088Y252322D01*
G01X104000Y243000D02*
Y242480D01*
X107750Y238730D01*
G01X108500Y227500D02*
X104010D01*
G01X113400Y231450D02*
X110500D01*
X108500Y229450D01*
Y227500D01*
G01Y259500D02*
Y260300D01*
X111700Y263500D01*
G01X108879Y266557D02*
Y266321D01*
X111700Y263500D01*
G01X103090Y258300D02*
Y258310D01*
G01X103250Y261680D02*
Y258470D01*
X103090Y258310D01*
G01D02*
X104000Y257400D01*
Y254000D01*
G01X109799Y295373D02*
Y292165D01*
X107966Y290332D01*
G01X105400Y283300D02*
X107966Y285866D01*
Y290332D01*
G01X109230Y326840D02*
X108200Y325810D01*
Y322500D01*
G01X111000Y360500D02*
X107300D01*
G01X92246Y396060D02*
X86310D01*
X83905Y393655D01*
X76633D01*
X75288Y395000D01*
X72000D01*
G01X72603Y474072D02*
X72653D01*
Y474056D01*
X70500Y471903D01*
Y468663D01*
X70525Y468638D01*
G01X130324Y212033D02*
X130624Y211733D01*
Y209533D01*
G01X157015Y216985D02*
Y211415D01*
X153900Y208300D01*
G01X150400D02*
X143900D01*
G01X123624Y240533D02*
X122621D01*
X120177Y242977D01*
G01X122820Y244133D02*
X121333D01*
X120177Y242977D01*
G01X130824Y241333D02*
Y243533D01*
X130324Y244033D01*
G01X118225Y230125D02*
X116900Y231450D01*
G01X111700Y263500D02*
X113500D01*
G01X117000D02*
X119030Y261470D01*
G01X127124Y240533D02*
Y243124D01*
X127500Y243500D01*
G01X127624Y272533D02*
Y275376D01*
X127500Y275500D01*
G01X155200Y248200D02*
Y242502D01*
X153210Y240512D01*
G01X156500Y281000D02*
Y275550D01*
X156700Y275350D01*
Y272900D01*
G01X114000Y227500D02*
X115527D01*
G01X114000Y259500D02*
X116342D01*
G01X149710Y240512D02*
X147404D01*
X146916Y241000D01*
X143900D01*
G01X153200Y272900D02*
X147700D01*
G01X123624Y304533D02*
Y307721D01*
X123301Y308044D01*
G01X121519Y336550D02*
X118962D01*
X116995Y338517D01*
G01D02*
X119050Y340572D01*
Y341625D01*
G01X123624Y304533D02*
X121126D01*
X120744Y304915D01*
X118164D01*
G01X129700Y340152D02*
Y338869D01*
X131019Y337550D01*
G01X130624Y305533D02*
Y307733D01*
X130324Y308033D01*
G01X113299Y295373D02*
X114399Y296473D01*
X116442D01*
G01X119282Y294453D02*
X117262Y296473D01*
X116442D01*
G01X113500Y327300D02*
X109690D01*
X109230Y326840D01*
G01X119223Y325995D02*
X117918Y327300D01*
X117000D01*
G01X127124Y304533D02*
Y307124D01*
X127500Y307500D01*
G01X155000Y312000D02*
Y307000D01*
X154100Y306100D01*
G01X125019Y336550D02*
X127000Y338531D01*
Y339000D01*
G01X157624Y352033D02*
Y340394D01*
X154630Y337400D01*
X153409D01*
G01X114562Y290332D02*
X113466D01*
G01X113700Y322500D02*
X114859D01*
X115681Y323322D01*
G01X150600Y306100D02*
X144600D01*
G01X146409Y337400D02*
X149909D01*
G01X123871Y368603D02*
Y370529D01*
X122300Y372100D01*
G01X117976Y368958D02*
X120341D01*
X120696Y368603D01*
X123871D01*
G01X130869Y369241D02*
Y370421D01*
X130585Y370705D01*
Y372085D01*
G01X110620Y388180D02*
Y390130D01*
X112620Y392130D01*
X113520D01*
G01X117020D02*
X117610D01*
X118975Y390765D01*
G01X127371Y368603D02*
Y371541D01*
X127420Y371590D01*
G01X111000Y360500D02*
Y356750D01*
X110750Y356500D01*
G01X118220Y360500D02*
X114500D01*
G01X151210Y369400D02*
X155679Y369437D01*
X157661Y371455D01*
X157624Y375924D01*
G01D02*
Y384533D01*
G01X116250Y356500D02*
X117746D01*
X118635Y355611D01*
G01X118290Y388000D02*
X116300D01*
X116120Y388180D01*
G01X147710Y369400D02*
X146180D01*
X145906Y369674D01*
X144210D01*
G01X327754Y-14877D02*
Y-7108D01*
G01X347833Y28022D02*
Y22923D01*
G01X337793Y17057D02*
Y22923D01*
G01D02*
Y28014D01*
G01X341140Y-1743D02*
Y3233D01*
G01D02*
Y9122D01*
G01X337793Y-14877D02*
Y-9901D01*
G01X347833Y-14877D02*
Y-7108D01*
G01X311021Y28014D02*
Y22923D01*
G01X317714Y28014D02*
Y22923D01*
G01X311021D02*
Y17057D01*
G01X327754Y22923D02*
Y28014D01*
G01X331100Y9114D02*
Y3233D01*
G01X321061D02*
Y-1743D01*
G01X314368Y3233D02*
Y-1843D01*
G01Y9114D02*
Y3233D01*
G01X311021Y-14877D02*
Y-9786D01*
G01X317714Y-14877D02*
Y-9786D01*
G01X351179Y-4536D02*
Y3233D01*
G01X317714Y17057D02*
Y22923D01*
G01X321061Y9114D02*
Y3233D01*
G01X331100Y-4536D02*
Y3233D01*
G01X321061Y9114D02*
X317942Y12233D01*
Y13200D01*
G01X317714Y17057D02*
X317942Y16829D01*
Y13200D01*
G01X327754Y-7108D02*
X329992Y-5388D01*
X331100Y-4536D01*
G01X351179Y41033D02*
Y46922D01*
G01X341140Y78833D02*
Y73757D01*
G01X351179Y78833D02*
Y73757D01*
G01Y35957D02*
Y41033D01*
G01X347833Y65822D02*
Y60723D01*
G01X337793Y65814D02*
Y60723D01*
G01D02*
Y54857D01*
G01X341140Y35957D02*
Y41033D01*
G01X331100Y78833D02*
Y73757D01*
G01X321061Y78833D02*
Y73757D01*
G01X314368Y78833D02*
Y73757D01*
G01X331100Y35957D02*
Y41033D01*
G01X317714Y60723D02*
Y65814D01*
G01X311021Y60723D02*
Y65814D01*
G01X321061Y41033D02*
Y46914D01*
G01X314368Y41033D02*
Y46914D01*
G01X311021Y54857D02*
Y60723D01*
G01X321061Y35957D02*
Y41033D01*
G01X314368Y35957D02*
Y41033D01*
G01X317714Y54857D02*
Y60723D01*
G01X327754D02*
Y65814D01*
G01Y60723D02*
Y54857D01*
G01X341140Y46922D02*
Y41033D01*
G01X347833Y54857D02*
Y60723D01*
G01X331100Y46914D02*
Y41033D01*
G01X351179Y78833D02*
Y84599D01*
G01X341140Y78833D02*
Y87392D01*
G01X331100Y78833D02*
Y84714D01*
G01X321061Y78833D02*
Y87392D01*
G01X314368Y78833D02*
Y84735D01*
G01X347833Y54857D02*
X348000Y54690D01*
Y51000D01*
G01X331100Y46914D02*
X330142Y47872D01*
Y51000D01*
G01X317714Y520723D02*
Y523900D01*
G01X337793Y523923D02*
Y529014D01*
G01X347833Y518157D02*
Y523900D01*
G01D02*
Y529022D01*
G01X327754Y518157D02*
Y523900D01*
G01D02*
Y529014D01*
G01X317714Y523900D02*
Y529014D01*
G01X311021Y523923D02*
Y529014D01*
G01X306936Y585230D02*
X307675Y584491D01*
Y579833D01*
G01X300982D02*
Y585714D01*
G01X314368Y579810D02*
Y574757D01*
G01Y585714D02*
Y579810D01*
G01X317714Y555857D02*
Y561700D01*
G01X311021Y555857D02*
Y561700D01*
G01X321061Y585714D02*
Y579810D01*
G01D02*
Y574757D01*
G01X341140Y585722D02*
Y579810D01*
G01D02*
Y574757D01*
G01Y542010D02*
Y536957D01*
G01Y547922D02*
Y542010D01*
G01X351179D02*
Y536957D01*
G01Y547922D02*
Y542010D01*
G01X321061Y536957D02*
Y542010D01*
G01X331100D02*
Y547914D01*
G01Y536957D02*
Y542010D01*
G01X314368D02*
Y536957D01*
G01Y547914D02*
Y542010D01*
G01X321061D02*
Y547914D01*
G01X347833Y561700D02*
Y566822D01*
G01Y555857D02*
Y561700D01*
G01X351179Y585722D02*
Y579810D01*
G01D02*
Y574757D01*
G01X337793Y555857D02*
Y561700D01*
G01X331100Y579810D02*
Y585714D01*
G01Y574757D02*
Y579810D01*
G01X327754Y555857D02*
Y561700D01*
G01X311021Y566814D02*
Y561700D01*
G01X337793Y566814D02*
Y561700D01*
G01X317714Y566814D02*
Y561700D01*
G01X327754Y566814D02*
Y561700D01*
G01X304329Y599500D02*
Y599523D01*
G01X312442Y589800D02*
X310624D01*
X309424Y591000D01*
X307892D01*
G01X304329Y599500D02*
Y591465D01*
G01D02*
X304278Y591414D01*
G01X331100Y617610D02*
Y609864D01*
G01X347833Y593657D02*
Y599500D01*
G01D02*
Y607292D01*
G01X337793Y599500D02*
Y604499D01*
G01Y593657D02*
Y599500D01*
G01X327754D02*
Y593657D01*
G01X311021D02*
Y599500D01*
G01X317714Y593657D02*
Y599500D01*
G01D02*
Y604614D01*
G01X311021Y599500D02*
Y604614D01*
G01X314368Y617610D02*
Y612457D01*
G01X321061Y617610D02*
Y612457D01*
G01X341140Y617610D02*
Y612457D01*
G01X327754Y607292D02*
Y599500D01*
G01X352109Y609918D02*
X351179Y610848D01*
G01D02*
Y617610D01*
G01X430749Y-124922D02*
G02I-12000J0D01*
G01X425599D02*
G02I-6850J0D01*
G01X434749D02*
X402749D01*
G01X404700Y13200D02*
X408184D01*
G01X417150D02*
X421368D01*
G01X357872Y-14877D02*
Y-9786D01*
G01X408069Y9107D02*
Y3233D01*
G01X411415Y-14877D02*
Y-9786D01*
G01X398029Y-4536D02*
Y3233D01*
G01X401376Y-14877D02*
X401375Y-14876D01*
Y-7108D01*
G01X398029Y3233D02*
Y9107D01*
G01X357872Y22923D02*
Y28014D01*
G01Y17014D02*
Y22923D01*
G01X367911Y17042D02*
Y22923D01*
G01D02*
Y28014D01*
G01X357872Y3233D02*
Y8914D01*
X357672Y9114D01*
G01X367911Y3233D02*
Y9114D01*
G01Y-14877D02*
Y-9786D01*
G01X357872Y-1858D02*
Y3233D01*
G01X367911Y-1858D02*
Y3233D01*
G01X357872Y-9786D02*
Y-1858D01*
G01X401377Y28022D02*
X401376Y28021D01*
G01X411416Y28022D02*
X411415Y28021D01*
G01X408069Y3233D02*
Y-1742D01*
G01X401376Y28021D02*
Y22923D01*
G01X411415Y28021D02*
Y22923D01*
G01X371258Y-1858D02*
Y-9800D01*
G01D02*
Y-14877D01*
G01X408069Y78833D02*
Y73742D01*
G01X398029Y78833D02*
Y73742D01*
G01X401376Y60723D02*
Y65821D01*
X401377Y65822D01*
G01X398029Y41033D02*
Y46907D01*
G01X401376Y54842D02*
Y60723D01*
G01X411415D02*
Y65821D01*
X411416Y65822D01*
G01X408069Y46907D02*
Y41033D01*
G01X357872Y60723D02*
Y65736D01*
G01X367911Y46914D02*
Y41033D01*
G01X357872Y46914D02*
Y41033D01*
G01X367911Y35942D02*
Y41033D01*
G01X398029Y78833D02*
Y84800D01*
G01X357872Y78833D02*
Y83880D01*
X358107Y84115D01*
G01X408069Y78833D02*
Y84475D01*
G01X358491Y73479D02*
X357872Y74098D01*
Y78833D01*
G01X367911D02*
Y73619D01*
X367742Y73450D01*
G01X358619Y36031D02*
X357872Y36778D01*
Y41033D01*
G01X367911Y60723D02*
Y65031D01*
X366992Y65950D01*
G01X411415Y54858D02*
Y60723D01*
G01X357872Y55588D02*
Y60723D01*
G01X371258Y78833D02*
Y79299D01*
X375337Y83378D01*
Y83877D01*
G01X371258Y60723D02*
X377923D01*
X380400Y63200D01*
X380892D01*
G01X384992Y81600D02*
X382892Y83700D01*
Y89500D01*
X380892Y91500D01*
G01X386630Y521860D02*
X385696D01*
X382892Y519056D01*
Y513256D01*
X380892Y511256D01*
G01X357872Y523900D02*
Y528942D01*
G01X401376Y523900D02*
Y529021D01*
X401377Y529022D01*
G01X411415Y523900D02*
Y529021D01*
X411416Y529022D01*
G01X375192Y516356D02*
Y518856D01*
G01D02*
Y519355D01*
X371258Y523289D01*
Y523900D01*
G01X401376Y555842D02*
Y561700D01*
G01X408069Y579810D02*
Y574742D01*
G01X398029Y536942D02*
Y542010D01*
G01D02*
Y547907D01*
G01X408069D02*
Y542010D01*
G01D02*
Y536942D01*
G01X357910Y536727D02*
Y536703D01*
X357872Y536665D01*
Y542010D01*
G01Y574742D02*
Y579810D01*
G01X367211Y555842D02*
Y557619D01*
X367911Y558319D01*
Y561700D01*
G01X408069Y585707D02*
Y579810D01*
G01X398029D02*
Y585707D01*
G01Y579810D02*
Y574757D01*
G01X357872Y579810D02*
Y584867D01*
G01X411416Y555857D02*
X411415Y555858D01*
G01X366890Y586000D02*
Y584641D01*
G01X411415Y561700D02*
Y566821D01*
G01X401376Y561700D02*
Y566821D01*
G01X367911Y561700D02*
Y566138D01*
G01X357872Y584867D02*
X357025Y585714D01*
G01X357872Y547714D02*
Y542010D01*
G01X411415Y555858D02*
Y561700D01*
G01X366890Y584641D02*
X367911Y583620D01*
Y579810D01*
G01X411415Y566821D02*
X411416Y566822D01*
G01X401376Y566821D02*
X401377Y566822D01*
G01X357872Y566776D02*
Y561700D01*
G01X367911Y566138D02*
X367235Y566814D01*
X367192D01*
G01X398029Y617610D02*
Y609864D01*
G01X357872Y617610D02*
Y612242D01*
G01X401376Y599500D02*
Y593642D01*
G01X411415Y604614D02*
Y599500D01*
G01X367911Y593642D02*
Y599500D01*
G01X357872D02*
Y594488D01*
X357026Y593642D01*
G01X367911Y599500D02*
Y604614D01*
G01X401375Y607292D02*
Y599524D01*
X401376Y599523D01*
Y599500D01*
G01X357872Y612242D02*
Y604614D01*
G01D02*
Y599500D01*
G01X408068Y612657D02*
X408069Y612658D01*
G01X367911Y617610D02*
Y612761D01*
G01X411415Y593658D02*
Y599500D01*
G01X408069Y612658D02*
Y617610D01*
G01X367911Y612761D02*
X367170Y612020D01*
Y611759D01*
G01X434749Y-140922D02*
Y-220922D01*
G01D02*
X1729349D01*
G01X434749Y-176422D02*
X1729349D01*
G01X418749Y-140922D02*
Y-108922D01*
G01X434749Y-140922D02*
X1729349D01*
G01X430150Y13200D02*
X433508D01*
G01X418108Y3233D02*
Y-4536D01*
G01X441533Y28007D02*
Y22923D01*
G01X431494Y9107D02*
Y3233D01*
G01X424801Y9107D02*
Y3233D01*
G01X418108Y9107D02*
Y3233D01*
G01X428147Y-14877D02*
Y-7108D01*
G01X424801Y3233D02*
Y-4536D01*
G01X431494Y3233D02*
Y-4536D01*
G01X434840Y-14877D02*
Y-7108D01*
G01X441533Y-1843D02*
Y-14877D01*
G01X418108Y-9701D02*
Y-14877D01*
G01Y-4536D02*
Y-9701D01*
G01X441533Y3233D02*
Y-1843D01*
G01Y3233D02*
Y9107D01*
G01X418108Y22923D02*
Y28007D01*
G01X434842Y28268D02*
X434840Y28266D01*
G01X428147Y28020D02*
Y22923D01*
G01X434840Y28266D02*
Y22923D01*
G01X424801Y78833D02*
Y73742D01*
G01X418108Y78833D02*
Y73742D01*
G01X431494Y78833D02*
Y73742D01*
G01X441533Y60723D02*
Y65807D01*
G01X418108Y60723D02*
Y65807D01*
G01X428147Y60723D02*
Y65820D01*
X428149Y65822D01*
G01X434840Y60723D02*
Y65820D01*
X434842Y65822D01*
G01X418108Y41033D02*
Y46907D01*
G01X424801D02*
Y41033D01*
G01X441533Y46907D02*
Y41033D01*
G01X431494Y46907D02*
Y41033D01*
G01X441533Y54842D02*
Y60723D01*
G01X431494Y78833D02*
Y84706D01*
X431400Y84800D01*
G01X424801Y78833D02*
Y84800D01*
G01X418108Y78833D02*
Y84599D01*
G01X441533Y78833D02*
Y81584D01*
G01X418108Y60723D02*
Y54842D01*
G01X441533Y73742D02*
Y78833D01*
G01X428147Y54859D02*
Y60723D01*
G01X434840Y54859D02*
Y60723D01*
G01X441533Y523923D02*
Y529007D01*
G01X428147Y523900D02*
Y529020D01*
X428149Y529022D01*
G01X434840Y523900D02*
Y529020D01*
X434842Y529022D01*
G01X451573Y579833D02*
Y585714D01*
G01X448226Y546844D02*
Y542033D01*
G01X451573D02*
Y547914D01*
G01X448226Y585028D02*
Y579833D01*
G01Y555661D02*
Y561700D01*
G01D02*
Y561723D01*
G01X441533Y585707D02*
Y579810D01*
G01X418108Y561700D02*
Y555842D01*
G01Y585599D02*
Y579810D01*
G01X424801D02*
Y574742D01*
G01X431494Y536942D02*
Y542010D01*
G01X424801Y536942D02*
Y542010D01*
G01X418108Y536942D02*
Y542010D01*
G01D02*
Y547907D01*
G01X424801Y542010D02*
Y547907D01*
G01X441533Y536957D02*
Y542010D01*
G01Y555842D02*
Y561700D01*
G01D02*
Y566807D01*
G01X418108Y561700D02*
Y566807D01*
G01X431494Y547907D02*
Y542010D01*
G01X441533Y547907D02*
Y542010D01*
G01X431494Y579810D02*
Y574742D01*
G01Y579810D02*
Y585707D01*
G01X424801Y579810D02*
Y585707D01*
G01X418108Y579810D02*
Y574858D01*
G01X428149Y555857D02*
X428147Y555859D01*
G01X434840Y561700D02*
Y555859D01*
G01Y561700D02*
Y566820D01*
G01X428147Y555859D02*
Y561700D01*
G01X434840Y555859D02*
X434842Y555857D01*
G01X441533Y574759D02*
Y579810D01*
G01X434840Y566820D02*
X434842Y566822D01*
G01X448226Y599500D02*
Y593765D01*
G01Y599523D02*
Y599500D01*
G01X441533Y617610D02*
Y612557D01*
G01X418108Y617610D02*
Y609864D01*
G01X431494Y617610D02*
Y609864D01*
G01X424801Y617610D02*
Y609864D01*
G01X418108Y599500D02*
Y593642D01*
G01Y604499D02*
Y599500D01*
G01X428147Y607292D02*
Y599500D01*
G01X434840Y607292D02*
Y599500D01*
G01X441533D02*
Y593642D01*
G01Y599500D02*
Y607292D01*
G01X434840Y599500D02*
Y593568D01*
G01X428147Y599500D02*
Y593659D01*
G01X595500Y102000D02*
Y90444D01*
X595470Y90414D01*
G01X595500Y102000D02*
Y104590D01*
X589650Y110440D01*
Y112700D01*
G01X671261Y40403D02*
X675945D01*
X675972Y40376D01*
G01X723500Y211000D02*
Y209850D01*
X721500Y207850D01*
X718700D01*
X717900Y207050D01*
G01X713175Y208275D02*
X714400Y207050D01*
G01X674184Y212995D02*
X667008Y220171D01*
Y225786D01*
X668831Y227609D01*
X670213D01*
G01X714761Y210752D02*
X717752D01*
X718000Y211000D01*
G01X701700Y226600D02*
X701500Y226800D01*
Y229000D01*
G01X687550Y260597D02*
X689863D01*
X689960Y260500D01*
G01X667634Y278953D02*
X668909D01*
X669762Y278100D01*
X672500D01*
G01D02*
X676000D01*
G01D02*
Y274100D01*
X675750Y273850D01*
Y271357D01*
G01X673713Y227609D02*
X678109D01*
X678600Y228100D01*
G01X704214Y290775D02*
X706662D01*
G01Y287275D02*
X704175D01*
G01X725400Y300450D02*
Y301010D01*
X727300Y302910D01*
G01X720800Y297500D02*
Y291200D01*
X721563Y290437D01*
Y289369D01*
G01X720800Y300700D02*
Y297500D01*
G01Y300700D02*
Y306300D01*
X717900Y309200D01*
G01X713050Y301275D02*
Y297975D01*
G01Y304375D02*
Y301275D01*
G01X717750Y290600D02*
Y291950D01*
X713050Y296650D01*
Y297975D01*
G01X717900Y312700D02*
Y315899D01*
X731850Y329849D01*
X737849D01*
X743516Y335516D01*
G01X670800Y292600D02*
X671900Y291500D01*
X673500D01*
G01X683100Y526000D02*
Y529000D01*
X681500Y530600D01*
Y533500D01*
X682899Y534899D01*
G01X780232Y209533D02*
Y211733D01*
X779932Y212033D01*
G01X772351Y240966D02*
X770561D01*
X768560Y242967D01*
Y244055D01*
G01X772519Y272931D02*
X770000D01*
X769019Y273912D01*
Y276400D01*
G01X779545Y272906D02*
Y275612D01*
X779400Y275757D01*
Y276200D01*
G01X758000Y228000D02*
Y230300D01*
X759700Y232000D01*
G01D02*
X763300D01*
G01X766800D02*
X768743Y230057D01*
G01X759000Y260105D02*
X763295Y264400D01*
X763500D01*
G01X759000Y260105D02*
Y267000D01*
G01X768100Y263100D02*
X767000Y264200D01*
Y264400D01*
G01X775851Y240966D02*
Y242351D01*
X777000Y243500D01*
G01X763500Y228000D02*
X766800D01*
G01X764500Y260105D02*
X767300D01*
G01X762842Y302434D02*
X763996Y303588D01*
X765582D01*
G01X772870Y304000D02*
X771278Y305592D01*
Y307918D01*
G01X728900Y300450D02*
Y301310D01*
X727300Y302910D01*
G01X780232Y337533D02*
Y339733D01*
X779932Y340033D01*
G01X779100Y307900D02*
X779786Y307214D01*
Y305173D01*
G01X743516Y335516D02*
X744698D01*
G01X756200Y292000D02*
X755800Y292400D01*
Y297900D01*
X757300Y299400D01*
X757905D01*
G01D02*
X758600D01*
X762200Y295800D01*
X763400D01*
G01X766900D02*
X768803Y293897D01*
G01X757956Y328095D02*
X758156Y327895D01*
Y325044D01*
X758450Y324750D01*
Y323658D01*
G01X762750Y327608D02*
X760199D01*
X759712Y328095D01*
X757956D01*
G01X766250Y327608D02*
X767392D01*
X768682Y326318D01*
G01X776370Y304000D02*
Y307000D01*
X776270Y307100D01*
G01X765850Y291010D02*
X765710Y291150D01*
X762680D01*
X761830Y292000D01*
X761700D01*
G01X768230Y323658D02*
X767277D01*
G01D02*
X763950D01*
G01X768059Y369287D02*
X772728D01*
G01X772982Y369033D02*
X772728Y369287D01*
G01D02*
X772443Y369572D01*
Y371976D01*
G01X779682Y369533D02*
Y371833D01*
X779882Y372033D01*
G01X763300Y359800D02*
X760500D01*
G01X758375Y355850D02*
Y357675D01*
X760500Y359800D01*
G01X766800D02*
X768674Y357926D01*
G01X762800Y393400D02*
X759900Y390500D01*
Y388700D01*
G01X760103Y397997D02*
X762800Y395300D01*
Y393400D01*
G01X768215Y391485D02*
X766300Y393400D01*
G01X776482Y369033D02*
Y371382D01*
X777100Y372000D01*
G01X781020Y398509D02*
Y393613D01*
X778069Y390662D01*
G01X781020Y398509D02*
X780986Y398543D01*
Y401784D01*
G01X763875Y355850D02*
X766700D01*
G01X765400Y388700D02*
X767000D01*
X767746Y387954D01*
G01X807232Y224533D02*
Y214648D01*
X805998Y213414D01*
Y210248D01*
X803350Y207600D01*
G01X795899D02*
X799850D01*
G01X806600Y241000D02*
Y247100D01*
G01D02*
X807232Y247732D01*
Y256533D01*
G01Y288533D02*
Y274632D01*
X805600Y273000D01*
G01X803100Y241000D02*
X799385D01*
X799351Y240966D01*
G01X802100Y273000D02*
X801001D01*
X800899Y272898D01*
X798587D01*
G01X807232Y351533D02*
Y338332D01*
X805300Y336400D01*
G01X807232Y320533D02*
Y307432D01*
X804800Y305000D01*
G01X797770D02*
X801300D01*
G01X796000Y336400D02*
X801800D01*
G01X807000Y381500D02*
Y375705D01*
G01D02*
X805708Y374413D01*
Y367560D01*
G01X792782Y368417D02*
X796829D01*
X797686Y367560D01*
X802208D01*
G01X941849Y-140922D02*
Y-220922D01*
G01X960629Y28014D02*
Y22923D01*
G01X970669Y-1743D02*
Y3233D01*
G01X963976Y-1843D02*
Y3233D01*
G01X967324Y-14877D02*
X967322D01*
Y-9786D01*
G01X960631Y-14877D02*
X960629D01*
Y-9786D01*
G01X967322Y17057D02*
Y22923D01*
G01X960629Y17057D02*
Y22923D01*
G01X963976Y9114D02*
Y3233D01*
G01X970669Y9114D02*
Y3233D01*
G01X967324Y22923D02*
X967322D01*
G01Y17057D02*
X967550Y16829D01*
Y13200D01*
G01X970669Y9114D02*
X967550Y12233D01*
Y13200D01*
G01X960629Y22923D02*
X960631D01*
G01X963976Y3233D02*
X963978D01*
G01X970669D02*
X970671D01*
G01X967322Y22923D02*
Y28014D01*
G01X960629Y65814D02*
Y60723D01*
G01X967322Y65814D02*
Y60723D01*
G01X970671Y78833D02*
Y87390D01*
X970669Y87392D01*
G01X963976Y46914D02*
Y41033D01*
G01X970669Y46914D02*
Y41033D01*
G01X960629Y54857D02*
Y60723D01*
G01X970669Y35957D02*
Y41033D01*
G01X963976Y35957D02*
Y41033D01*
G01X967322Y54857D02*
Y60723D01*
G01X963978Y78833D02*
X963976D01*
Y73757D01*
G01X963978Y78833D02*
Y83833D01*
X963976Y83835D01*
G01X970671Y78833D02*
Y73759D01*
X970669Y73757D01*
G01X963976Y41033D02*
X963978D01*
G01X970669D02*
X970671D01*
G01X960629Y60723D02*
X960631D01*
G01X967322D02*
X967324D01*
G01X960629Y529014D02*
Y523923D01*
G01X953939Y561700D02*
Y568746D01*
X953936Y568749D01*
G01X957701Y552000D02*
X961950D01*
G01X957283Y585558D02*
Y579833D01*
G01Y548200D02*
X957285Y548198D01*
G01D02*
Y542010D01*
G01X963978D02*
X963976D01*
G01X963978Y579810D02*
X963976D01*
G01X970671D02*
X970669D01*
G01Y574757D02*
Y579810D01*
G01X970671Y542010D02*
X970669D01*
G01Y547914D02*
Y542010D01*
G01X963976Y547914D02*
Y542010D01*
G01Y574757D02*
Y579810D01*
G01X970669D02*
Y585714D01*
G01Y542010D02*
Y536957D01*
G01X963976Y542010D02*
Y536957D01*
G01Y579810D02*
Y585714D01*
G01X960631Y561700D02*
Y555859D01*
X960629Y555857D01*
G01X967324Y561700D02*
Y555859D01*
G01X967322Y566814D02*
X967324Y566812D01*
G01X960631Y561700D02*
Y566812D01*
G01X967324Y555859D02*
X967322Y555857D01*
G01X967324Y566812D02*
Y561700D01*
G01X960631Y566812D02*
X960629Y566814D01*
G01X953939Y599500D02*
X953937D01*
G01Y594324D02*
Y599500D01*
G01D02*
Y599523D01*
G01X967324Y599500D02*
X967322D01*
G01Y593657D02*
Y599500D01*
G01X960631D02*
X960629D01*
G01Y593657D02*
Y599500D01*
G01X970671Y617610D02*
X970669D01*
Y612457D01*
G01X963978Y617610D02*
X963976D01*
Y612457D01*
G01X967322Y599500D02*
Y604614D01*
G01X960629Y599500D02*
Y604614D01*
G01X997443Y-14877D02*
X997441D01*
Y-7108D01*
G01X1007480Y28014D02*
Y22923D01*
G01X1007482Y3233D02*
X1007480D01*
Y8914D01*
X1007280Y9114D01*
G01X987401Y28014D02*
Y22923D01*
G01X987403Y-14877D02*
X987401D01*
Y-9901D01*
G01X980708Y-4536D02*
Y3233D01*
G01X1017519Y28014D02*
Y22923D01*
G01X1007480Y-9786D02*
Y-14877D01*
X1007482D01*
G01X1007480Y-1858D02*
Y-9786D01*
G01X1017519Y9114D02*
Y3233D01*
G01X977362Y-7108D02*
Y-14877D01*
X977364D01*
G01X1007482Y3233D02*
X1007480Y3231D01*
Y-1858D01*
G01X1017521Y-14877D02*
X1017519Y-14875D01*
Y-9786D01*
G01X990748Y-1743D02*
Y3233D01*
G01X980708Y9114D02*
Y3233D01*
G01X987401Y17057D02*
Y22923D01*
G01X1017519Y-1858D02*
Y3233D01*
G01X1007480Y17014D02*
Y22923D01*
G01X1017519Y17042D02*
Y22923D01*
G01X990748Y9122D02*
Y3233D01*
G01X980708D02*
X980710D01*
G01X987401Y22923D02*
X987403D01*
G01X1017519Y3233D02*
X1017521D01*
G01X1007480Y22923D02*
X1007482D01*
G01X1017519D02*
X1017521D01*
G01X990748Y3233D02*
X990750D01*
G01X977364Y22923D02*
X977362D01*
G01X997443D02*
X997441D01*
G01X1000787Y-4536D02*
Y3233D01*
G01X977362Y22923D02*
Y28014D01*
G01X997441Y22923D02*
Y28022D01*
G01X1000787Y3233D02*
X1000789D01*
G01X1020868Y-14877D02*
Y-1860D01*
X1020866Y-1858D01*
G01X1010900Y50800D02*
X1009367Y52333D01*
X1007370D01*
G01X1007482Y60723D02*
X1007480D01*
Y65736D01*
G01X1030500Y91500D02*
X1032500Y89500D01*
Y83700D01*
X1035000Y81200D01*
G01X987401Y65814D02*
Y60723D01*
G01X977362Y54857D02*
Y60723D01*
G01X990750Y78833D02*
Y87390D01*
X990748Y87392D01*
G01X1017521Y78833D02*
Y73621D01*
X1017350Y73450D01*
G01X980710Y78833D02*
Y84712D01*
X980708Y84714D01*
G01Y35957D02*
Y41033D01*
G01Y46914D02*
Y41033D01*
G01X987401Y54857D02*
Y60723D01*
G01X977362Y65814D02*
Y60723D01*
G01X1007482Y78833D02*
Y84806D01*
G01X1000789Y78833D02*
Y73759D01*
X1000787Y73757D01*
G01X1000789Y78833D02*
Y84597D01*
X1000787Y84599D01*
G01X990750Y78833D02*
Y73759D01*
X990748Y73757D01*
G01X980710Y78833D02*
Y73759D01*
X980708Y73757D01*
G01X1007482Y78833D02*
Y74096D01*
X1008099Y73479D01*
G01X1017521Y41033D02*
Y46912D01*
X1017519Y46914D01*
G01X997443Y60723D02*
Y65820D01*
X997441Y65822D01*
G01X980708Y41033D02*
X980710D01*
G01X977362Y60723D02*
X977364D01*
G01X1016600Y65950D02*
X1017521Y65029D01*
Y60723D01*
G01X1016400Y50800D02*
Y53723D01*
X1017519Y54842D01*
G01X987401Y60723D02*
X987403D01*
G01X1007482D02*
Y55586D01*
G01X990750Y41033D02*
Y46920D01*
G01X1000789Y41033D02*
Y46920D01*
G01X997443Y60723D02*
Y54859D01*
G01X1007482Y41033D02*
Y46912D01*
G01X990748Y35957D02*
X990750Y35959D01*
G01X1017519Y35942D02*
X1017521Y35944D01*
G01X1000787Y35957D02*
X1000789Y35959D01*
G01X1007482Y55586D02*
X1008226Y54842D01*
G01X990750Y46920D02*
X990748Y46922D01*
G01X1000789Y46920D02*
X1000787Y46922D01*
G01X997443Y54859D02*
X997441Y54857D01*
G01X1007482Y46912D02*
X1007480Y46914D01*
G01X990750Y35959D02*
Y41033D01*
G01X1017521Y35944D02*
Y41033D01*
G01X1000789Y35959D02*
Y41033D01*
G01X1024945Y83877D02*
Y83378D01*
X1020866Y79299D01*
Y78833D01*
X1020868D01*
G01X1034000Y95900D02*
X1032900Y97000D01*
X1030500D01*
G01X1034200Y506956D02*
X1033000Y505756D01*
X1030500D01*
G01X977364Y523900D02*
X977362D01*
G01X997443D02*
X997441D01*
G01X1007482D02*
X1007480Y523923D01*
Y528942D01*
G01X1030500Y511256D02*
X1032500Y513256D01*
Y519056D01*
X1035000Y521556D01*
G01X977362Y529014D02*
Y523900D01*
G01X997441Y529022D02*
Y523900D01*
G01X987401Y529014D02*
Y523923D01*
G01X977362Y523900D02*
Y518157D01*
G01X997441Y523900D02*
Y518157D01*
G01X1024800Y518856D02*
X1022867D01*
X1020866Y520857D01*
Y523900D01*
X1020868D01*
G01X1024800Y516356D02*
Y518856D01*
G01X990750Y542010D02*
X990748D01*
G01X1000789D02*
X1000787D01*
G01X1007518Y536727D02*
Y536703D01*
X1007480Y536665D01*
Y542010D01*
G01X1000789Y579810D02*
X1000787D01*
G01Y585722D02*
Y579810D01*
G01X1007482D02*
X1007480D01*
G01X997443Y561700D02*
X997441D01*
G01Y566822D02*
Y561700D01*
G01X990750Y579810D02*
X990748D01*
G01Y585722D02*
Y579810D01*
G01X980710D02*
X980708D01*
G01Y574757D02*
Y579810D01*
G01X980710Y542010D02*
X980708D01*
G01Y536957D02*
Y542010D01*
G01X1017521Y561700D02*
Y557920D01*
X1016819Y557218D01*
Y555842D01*
G01X990748Y536957D02*
Y542010D01*
G01X1000787Y536957D02*
Y542010D01*
G01X980708Y579810D02*
Y585714D01*
G01Y542010D02*
Y547914D01*
G01X1007480Y542010D02*
X1007482D01*
G01X1000787Y579810D02*
Y574757D01*
G01X1007480Y579810D02*
Y574742D01*
G01X997441Y561700D02*
Y555857D01*
G01X990748Y579810D02*
Y574757D01*
G01Y542010D02*
Y547922D01*
G01X1000787Y542010D02*
Y547922D01*
G01X1006633Y585714D02*
X1007480Y584867D01*
G01X987403Y561700D02*
Y555859D01*
G01X1007482Y561700D02*
X1007480D01*
Y555855D01*
G01X977364Y561700D02*
Y555859D01*
G01X1016000Y551700D02*
X1016819Y552519D01*
G01X977364Y561700D02*
Y566812D01*
G01X987403Y561700D02*
Y566812D01*
G01X1007482Y561700D02*
Y566778D01*
G01X1017521Y561700D02*
Y566093D01*
G01X1007480Y584867D02*
Y579810D01*
G01X987403Y555859D02*
X987401Y555857D01*
G01X1007480Y547714D02*
Y542010D01*
G01X977364Y555859D02*
X977362Y555857D01*
G01X1016819Y552519D02*
Y555842D01*
G01X977364Y566812D02*
X977362Y566814D01*
G01X987403Y566812D02*
X987401Y566814D01*
G01X1007482Y566778D02*
X1007518Y566814D01*
G01X1017521Y566093D02*
X1016800Y566814D01*
G01X1000789Y617610D02*
X1000787D01*
Y609864D01*
G01X1007482Y617610D02*
X1007480D01*
Y612242D01*
G01X980710Y617610D02*
X980708D01*
Y609864D01*
G01X977362Y593657D02*
Y599500D01*
G01X997441Y593657D02*
Y599500D01*
G01X1007482D02*
X1007480D01*
G01X1017521D02*
X1017519D01*
G01Y593642D02*
Y599500D01*
G01X987403D02*
X987401D01*
G01Y593657D02*
Y599500D01*
G01X990750Y617610D02*
X990748D01*
Y612457D01*
G01X1007480Y604614D02*
Y599500D01*
G01Y612242D02*
Y604614D01*
G01X977362Y607292D02*
Y599500D01*
G01X997441Y607292D02*
Y599500D01*
G01X977362D02*
X977364D01*
G01X1017519D02*
Y604614D01*
G01X987401Y599500D02*
Y604499D01*
G01X1007480Y599500D02*
Y594488D01*
X1006634Y593642D01*
G01X997441Y599500D02*
X997443D01*
G01X1079349Y-140922D02*
Y-220922D01*
G01X1084450Y22923D02*
Y17057D01*
G01Y22923D02*
Y28098D01*
G01X1077757Y22923D02*
Y17057D01*
G01Y22923D02*
Y28022D01*
G01X1061025Y-14877D02*
X1061023D01*
Y-9786D01*
G01X1081102Y9107D02*
Y3233D01*
G01X1074409Y9107D02*
Y3233D01*
G01X1067716Y9107D02*
Y3233D01*
G01X1091143D02*
X1091141D01*
Y9107D01*
G01X1084450Y-14877D02*
X1084448D01*
Y-7108D01*
G01X1077757Y-14877D02*
X1077755D01*
Y-7108D01*
G01X1047637Y9107D02*
Y3233D01*
G01X1067716Y-4536D02*
Y3233D01*
G01X1074409Y-4536D02*
Y3233D01*
G01X1081102Y-4536D02*
Y3233D01*
G01X1047639D02*
X1047637D01*
G01X1067716D02*
X1067718D01*
G01X1074409D02*
X1074411D01*
G01X1081102D02*
X1081104D01*
G01X1047637D02*
Y-4536D01*
G01X1050986Y22923D02*
Y28021D01*
G01X1061025Y22923D02*
Y28021D01*
G01X1067716Y28007D02*
X1067718Y28005D01*
G01X1091141Y28007D02*
X1091143Y28005D01*
G01X1057679Y3233D02*
Y-1740D01*
G01X1091143Y3233D02*
Y-1841D01*
G01Y-14877D02*
Y-1845D01*
G01X1050983Y-7108D02*
X1050986Y-7111D01*
G01X1067716Y-9901D02*
X1067718Y-9903D01*
G01X1061024Y17057D02*
X1061025Y17058D01*
G01X1067716Y17042D02*
X1067718Y17044D01*
G01X1050986Y22923D02*
Y17044D01*
G01X1057679Y3233D02*
Y9105D01*
G01X1091143Y22923D02*
Y17044D01*
G01X1061025Y17058D02*
Y22923D01*
G01X1067718Y17044D02*
Y22923D01*
G01X1050986Y17044D02*
X1050984Y17042D01*
G01X1057679Y9105D02*
X1057677Y9107D01*
G01X1091143Y17044D02*
X1091141Y17042D01*
G01X1050986Y28021D02*
X1050985Y28022D01*
G01X1061025Y28021D02*
X1061024Y28022D01*
G01X1067718Y28005D02*
Y22923D01*
G01X1091143Y28005D02*
Y22923D01*
G01X1057679Y-1740D02*
X1057676Y-1743D01*
G01X1091143Y-1841D02*
X1091141Y-1843D01*
G01X1091143Y-1845D02*
X1091141Y-1843D01*
G01X1050986Y-7111D02*
Y-14877D01*
G01X1067718Y-9903D02*
Y-14877D01*
G01X1057679Y78833D02*
Y84421D01*
X1057676Y84424D01*
G01X1067718Y60723D02*
X1067716D01*
Y65807D01*
G01X1074409Y46907D02*
Y41033D01*
G01X1081102Y46907D02*
Y41033D01*
G01X1091141Y65807D02*
Y60723D01*
G01X1050985Y65822D02*
X1050984Y65821D01*
Y60723D01*
G01X1057677Y35942D02*
Y41033D01*
G01X1067718Y60723D02*
X1067716Y60721D01*
Y54842D01*
G01X1091143Y78833D02*
Y81598D01*
G01X1057677Y46907D02*
Y41033D01*
G01X1074409Y35942D02*
Y41033D01*
G01X1050984Y54842D02*
Y60723D01*
G01X1077757Y65822D02*
X1077755Y65820D01*
Y60723D01*
G01X1081102Y35942D02*
Y41033D01*
G01X1091141Y46907D02*
Y41033D01*
G01Y54842D02*
Y60723D01*
G01X1084450Y65822D02*
X1084448Y65820D01*
Y60723D01*
G01X1091143Y78833D02*
X1091141D01*
Y73742D01*
G01X1081104Y78833D02*
Y73744D01*
X1081102Y73742D01*
G01X1081104Y78833D02*
Y84597D01*
X1081102Y84599D01*
G01X1074411Y78833D02*
Y84712D01*
X1074409Y84714D01*
G01X1074411Y78833D02*
Y73744D01*
X1074409Y73742D01*
G01X1067718Y78833D02*
Y84597D01*
X1067716Y84599D01*
G01X1067718Y78833D02*
Y73744D01*
X1067716Y73742D01*
G01X1057679Y78833D02*
Y73744D01*
X1057677Y73742D01*
G01X1047639Y78833D02*
Y73744D01*
X1047637Y73742D01*
G01X1047639Y78833D02*
Y84597D01*
X1047637Y84599D01*
G01X1061025Y60723D02*
Y65821D01*
X1061024Y65822D01*
G01X1074409Y41033D02*
X1074411D01*
G01X1081102D02*
X1081104D01*
G01X1057677D02*
X1057679D01*
G01X1050984Y60723D02*
X1050986D01*
G01X1077755D02*
X1077757D01*
G01X1091141Y41033D02*
X1091143D01*
G01X1091141Y60723D02*
X1091143D01*
G01X1084448D02*
X1084450D01*
G01X1047637Y46907D02*
X1047639Y46905D01*
G01X1077755Y60723D02*
Y54859D01*
G01X1084448Y60723D02*
Y54859D01*
G01X1067718Y41033D02*
Y46905D01*
G01X1047639D02*
Y41033D01*
G01X1067718Y46905D02*
X1067716Y46907D01*
G01X1091141Y35959D02*
Y41033D01*
G01X1067718Y523900D02*
X1067716Y523923D01*
Y529007D01*
G01X1091143Y542010D02*
X1091141D01*
G01X1081104D02*
X1081102D01*
G01X1074411D02*
X1074409D01*
G01X1067718D02*
X1067716D01*
G01X1067718Y579810D02*
X1067716D01*
G01X1091143Y561700D02*
X1091141D01*
Y555842D01*
G01X1067718Y561700D02*
X1067716D01*
Y555842D01*
G01X1081104Y579810D02*
X1081102D01*
Y574742D01*
G01X1091143Y579810D02*
X1091141D01*
G01X1074411D02*
X1074409D01*
Y574742D01*
G01X1067716Y574858D02*
Y579810D01*
G01X1050986Y561700D02*
X1050984D01*
Y555842D01*
G01X1057679Y579810D02*
X1057677D01*
G01Y574742D02*
Y579810D01*
G01X1057679Y542010D02*
X1057677D01*
G01Y547907D02*
Y542010D01*
G01X1047639D02*
X1047637D01*
G01Y536942D02*
Y542010D01*
G01X1074409Y547907D02*
Y542010D01*
G01X1067716Y547907D02*
Y542010D01*
G01X1091141Y547907D02*
Y542010D01*
G01X1081102Y547907D02*
Y542010D01*
G01X1077757Y561700D02*
Y566822D01*
G01X1084450Y561700D02*
Y566822D01*
G01X1047637Y574757D02*
Y579810D01*
X1047639D01*
G01X1067716D02*
Y585599D01*
G01X1091141Y579810D02*
Y585707D01*
G01X1057677Y579810D02*
Y585707D01*
G01Y542010D02*
Y536942D01*
G01X1047637Y542010D02*
Y547907D01*
G01X1074409Y542010D02*
Y536942D01*
G01X1067716Y542010D02*
Y536942D01*
G01X1091141Y542010D02*
Y536942D01*
G01X1081102Y542010D02*
Y536942D01*
G01X1061025Y561700D02*
X1061023D01*
Y555858D01*
G01X1084450Y561700D02*
X1084448D01*
Y555859D01*
G01X1077757Y561700D02*
X1077755D01*
Y555859D01*
G01X1047639Y579810D02*
Y585705D01*
G01X1081104Y579810D02*
Y585705D01*
G01X1074411Y579810D02*
Y585705D01*
G01X1050985Y566822D02*
X1050986Y566821D01*
G01X1061024Y566822D02*
X1061025Y566821D01*
G01X1067716Y566807D02*
X1067718Y566805D01*
G01X1091141Y566807D02*
X1091143Y566805D01*
G01X1061023Y555858D02*
X1061024Y555857D01*
G01X1084448Y555859D02*
X1084450Y555857D01*
G01X1077755Y555859D02*
X1077757Y555857D01*
G01X1047639Y585705D02*
X1047637Y585707D01*
G01X1081104Y585705D02*
X1081102Y585707D01*
G01X1074411Y585705D02*
X1074409Y585707D01*
G01X1050986Y566821D02*
Y561700D01*
G01X1091141Y574759D02*
Y579810D01*
G01X1061025Y566821D02*
Y561700D01*
G01X1067718Y566805D02*
Y561700D01*
G01X1091143Y566805D02*
Y561700D01*
G01X1047639Y617610D02*
X1047637D01*
Y609864D01*
G01X1074411Y617610D02*
X1074409D01*
Y609864D01*
G01X1081104Y617610D02*
X1081102D01*
Y609864D01*
G01X1091143Y617610D02*
X1091141D01*
Y612557D01*
G01X1067718Y617610D02*
X1067716D01*
Y609864D01*
G01X1091143Y599500D02*
X1091141D01*
G01X1084450D02*
X1084448D01*
G01X1077757D02*
X1077755D01*
G01X1067718D02*
X1067716D01*
G01X1061025D02*
X1061023D01*
G01X1050986D02*
X1050984D01*
G01X1067716Y604499D02*
Y599500D01*
G01X1050983Y607292D02*
Y599524D01*
X1050984Y599523D01*
Y599500D01*
G01X1077755D02*
Y607292D01*
G01X1061023Y599500D02*
Y604614D01*
G01X1067716Y599500D02*
Y593642D01*
G01X1050984Y599500D02*
Y593642D01*
G01X1091141Y599500D02*
Y607292D01*
G01Y593657D02*
Y599500D01*
G01X1084448D02*
Y607292D01*
G01Y593757D02*
Y599500D01*
G01X1061023D02*
Y593658D01*
G01X1077755Y599500D02*
Y593659D01*
G01X1057677Y612658D02*
Y617610D01*
X1057679D01*
G01X1097836Y561700D02*
X1097834D01*
G01Y556162D02*
Y561700D01*
G01Y584771D02*
Y579833D01*
G01Y546425D02*
Y542033D01*
G01X1101181Y547914D02*
Y542033D01*
G01X1097834Y561700D02*
Y561723D01*
G01X1101181Y579833D02*
Y585714D01*
G01X1097836Y599500D02*
X1097834D01*
G01Y593347D02*
Y599500D01*
G01D02*
Y599523D01*
G01X1194349Y-140922D02*
Y-220922D01*
G01X1267800Y593600D02*
Y591692D01*
X1266108Y590000D01*
G01X1332700Y30800D02*
X1330000Y33500D01*
Y40700D01*
G01X1340090Y7970D02*
Y-4350D01*
G01D02*
X1342716Y-6976D01*
Y-7476D01*
G01X1317300Y89600D02*
X1314600D01*
X1313884Y88884D01*
Y81896D01*
G01X1333500Y40700D02*
X1337257D01*
X1337272Y40715D01*
G01X1341634Y106194D02*
Y107234D01*
X1344500Y110100D01*
G01X1341634Y100694D02*
X1338359D01*
X1337134Y99469D01*
G01X1338069Y520804D02*
X1336861Y519596D01*
X1335664D01*
G01Y514096D02*
X1330835D01*
X1330342Y513603D01*
G01X1361849Y-140922D02*
Y-220922D01*
G01X1375676Y7630D02*
X1374569Y8737D01*
X1373128D01*
X1372989Y8876D01*
G01X1379556Y16407D02*
X1382996D01*
X1383506Y16917D01*
G01X1384958Y-13901D02*
X1386714D01*
X1387747Y-12868D01*
Y-9885D01*
G01X1378974Y-12796D02*
X1380079Y-13901D01*
X1381458D01*
G01X1369489Y8876D02*
Y5876D01*
X1369389Y5776D01*
G01X1383506Y22417D02*
X1383500Y22411D01*
X1378004D01*
G01X1379025Y-9799D02*
X1379111Y-9885D01*
X1382247D01*
G01X1351600Y37300D02*
X1346687D01*
X1343272Y40715D01*
G01X1366900Y40200D02*
Y38000D01*
X1367100Y37800D01*
G01X1366650Y69151D02*
X1370318Y72819D01*
X1370366D01*
G01X1366100Y76000D02*
X1370100D01*
G01X1370366Y72819D02*
Y74794D01*
X1370100Y75060D01*
Y76000D01*
G01X1369407Y396668D02*
X1369207Y396868D01*
Y399068D01*
G01X1382692Y385494D02*
X1388219D01*
X1390013Y383700D01*
X1393840D01*
X1394370Y384230D01*
G01X1386433Y375976D02*
X1390460D01*
X1393518Y372918D01*
G01X1391446Y379926D02*
X1393518Y377854D01*
Y372918D01*
G01X1382933Y375976D02*
X1380872Y378037D01*
Y378098D01*
G01X1347300Y370500D02*
Y376000D01*
G01X1384250Y380350D02*
X1384674Y379926D01*
X1385946D01*
G01X1350800Y370500D02*
X1352700D01*
X1355000Y368200D01*
G01X1395120Y530921D02*
Y525818D01*
X1395581Y525357D01*
G01X1380420Y548730D02*
Y550900D01*
X1382590Y553070D01*
X1391709D01*
X1393735Y551044D01*
G01X1380420Y548730D02*
Y547315D01*
X1381523Y546212D01*
X1383323D01*
X1384725Y544810D01*
Y544575D01*
X1385033Y544267D01*
G01X1398620Y530921D02*
X1395120D01*
G01X1370900Y587056D02*
Y584856D01*
X1371100Y584656D01*
G01X1388817Y564894D02*
X1390616Y566786D01*
Y568907D01*
G01X1392390Y561630D02*
X1390818D01*
X1388817Y563631D01*
Y564894D01*
G01X1385317D02*
X1383533D01*
X1382623Y565804D01*
G01X1383075Y568907D02*
X1385116D01*
G01X1351400Y556000D02*
Y552204D01*
X1352202Y551402D01*
G01X1351400Y556000D02*
Y558400D01*
X1352000Y559000D01*
Y560600D01*
G01X1378200Y619200D02*
X1378250Y619250D01*
X1383879D01*
G01X1389750Y595500D02*
Y597250D01*
X1390750Y598250D01*
Y599500D01*
G01X1389750Y595500D02*
X1394030D01*
G01X1383004Y596505D02*
X1384009Y595500D01*
X1386250D01*
G01X1384225Y600025D02*
X1384750Y599500D01*
X1385250D01*
G01X1356682Y618600D02*
X1355282Y620000D01*
X1352332D01*
G01X1502030Y582394D02*
X1508372D01*
G01D02*
X1513700Y577066D01*
G01X1481800Y582200D02*
X1476612Y577012D01*
G01D02*
X1466647D01*
G01X1466733Y585753D02*
Y583266D01*
X1466647Y583180D01*
Y580512D01*
G01X1502030Y585894D02*
Y591354D01*
G01X1504700Y608500D02*
X1502829D01*
X1502268Y607939D01*
G01X1523100Y619276D02*
X1529608D01*
X1530385Y620053D01*
G01X1490500Y622600D02*
X1490700Y622400D01*
X1494300D01*
G01X1487932Y618268D02*
X1488564Y618900D01*
X1494300D01*
G01X1521094Y621175D02*
Y622646D01*
G01X1485173Y620592D02*
Y622427D01*
X1485000Y622600D01*
G01X1531849Y-140922D02*
Y-220922D01*
G01X1544500Y283250D02*
Y286242D01*
X1543786Y286956D01*
Y289786D01*
X1544500Y290500D01*
G01X1533838Y288706D02*
X1536244D01*
X1539700Y285250D01*
Y285148D01*
X1541000Y283848D01*
Y283250D01*
G01X1537500D02*
X1534000D01*
G01X1528562D02*
X1534000D01*
G01D02*
X1533914Y283336D01*
Y286073D01*
G01X1657498Y267100D02*
X1634700D01*
G01D02*
X1633101Y268699D01*
X1623812D01*
G01X1656611Y491104D02*
X1653866D01*
X1651754Y488992D01*
Y488025D01*
G01D02*
X1652612Y487167D01*
X1656611D01*
G01X1729349Y-140922D02*
Y-220922D01*
G01X1757349Y-124922D02*
G02I-12000J0D01*
G01X1752199D02*
G02I-6850J0D01*
G01X1745349Y-140922D02*
Y-108922D01*
G01X1761349Y-124922D02*
X1729349D01*
G01X1731264Y204236D02*
X1731268D01*
X1731232Y199300D01*
X1731229Y198900D01*
Y198885D01*
X1731216Y198872D01*
G01X1753311Y198700D02*
Y204236D01*
G01X1765909D02*
X1765882Y204209D01*
Y199760D01*
X1765879Y199300D01*
X1765876Y198900D01*
X1765875Y198781D01*
X1765866Y198772D01*
G01X1769059Y204236D02*
X1769032Y204209D01*
Y199842D01*
X1769028Y199300D01*
X1769025Y198900D01*
Y198881D01*
X1769016Y198872D01*
G01X1725733Y492097D02*
Y460861D01*
X1731199Y455395D01*
Y447959D01*
X1727620Y444380D01*
G01X1780720Y146250D02*
Y150750D01*
G01Y153850D02*
Y150750D01*
G01X1781658Y204236D02*
X1781662D01*
X1781626Y199300D01*
X1781623Y198900D01*
Y198879D01*
X1781616Y198872D01*
G01X1778508Y204236D02*
X1778512D01*
X1778477Y199300D01*
X1778474Y198900D01*
X1778473Y198779D01*
X1778466Y198772D01*
G01X1816303Y204236D02*
Y202002D01*
X1816273Y201972D01*
X1816270Y199300D01*
X1816269Y198900D01*
Y198775D01*
X1816266Y198772D01*
G01X1806821Y198600D02*
X1806824Y199063D01*
X1806854Y199093D01*
Y204236D01*
G01X1807751Y209586D02*
X1806850Y208685D01*
Y204236D01*
X1806854D01*
G01X1803705D02*
Y200433D01*
X1804166Y199972D01*
Y198472D01*
G01X1828700Y198800D02*
Y199106D01*
X1828906Y199312D01*
Y204236D01*
X1828902D01*
G01X1819453D02*
X1819457D01*
Y198872D01*
G01X1791106Y204236D02*
Y198812D01*
X1791066Y198772D01*
G01X1794256Y204236D02*
Y198912D01*
X1794216Y198872D01*
G01X1863908Y140992D02*
X1863202Y141698D01*
X1859163D01*
G01X1847650Y104640D02*
X1845220D01*
X1844934Y104926D01*
X1842964D01*
G01X1847650Y99140D02*
X1849426Y97364D01*
Y95500D01*
G01X1861670Y102800D02*
X1857071D01*
X1856329Y103542D01*
G01X1881400Y192850D02*
Y194836D01*
X1882452Y195888D01*
G01X1903150Y217250D02*
X1906000Y220100D01*
Y233940D01*
X1897855Y242085D01*
X1887834D01*
X1872323Y257596D01*
Y264167D01*
G01X1943750Y70547D02*
X1963495D01*
X1964833Y69209D01*
X1970342D01*
X1973572Y72439D01*
Y81350D01*
X1971572Y83350D01*
X1969320D01*
X1966100Y86570D01*
Y94786D01*
G01X1955531Y191417D02*
X1956015Y191901D01*
Y196641D01*
X1954042Y198614D01*
X1952717D01*
G01X1918885Y235941D02*
X1914037Y240789D01*
Y243646D01*
G01X1962401Y500829D02*
X1959261D01*
X1957100Y502990D01*
G01X1973450Y506339D02*
Y505670D01*
X1970500Y502720D01*
G01X1965132Y506339D02*
Y503560D01*
X1962401Y500829D01*
G01X1968870Y481710D02*
X1965132Y477972D01*
Y477599D01*
G01X1973450D02*
X1973229D01*
X1970270Y474640D01*
X-20700Y31400D03*
Y25200D03*
Y22300D03*
Y28100D03*
X-20600Y41200D03*
X-20526Y44263D03*
X-16602Y81858D03*
Y79358D03*
X-20500Y60300D03*
Y57300D03*
X-20700Y48800D03*
X-20726Y37463D03*
X-20800Y34400D03*
X-20500Y54300D03*
Y51300D03*
X-19210Y162529D03*
X-15768Y161922D03*
X-18000Y247400D03*
X-15000D03*
X-18000Y262700D03*
X-15000D03*
X-17014Y455604D03*
X-14800Y526100D03*
X-16700Y497400D03*
X-17200Y510800D03*
X-17302Y506798D03*
X-19802Y476738D03*
X-19783Y481286D03*
X-18160Y522609D03*
X-16186Y519304D03*
X-14690Y471140D03*
X-16726Y503651D03*
X-17084Y467626D03*
X-16766Y500106D03*
X-14971Y540000D03*
X-17300Y530800D03*
X-17500Y574000D03*
X-17397Y564242D03*
X30600Y-12000D03*
X22499Y-19381D03*
X19924Y-18875D03*
X19964Y18793D03*
X16550Y18300D03*
X25060Y16214D03*
X25838Y-20458D03*
X25827Y-16958D03*
X38227Y-20485D03*
X42520Y-16896D03*
X41677Y-14390D03*
X602Y30502D03*
X2871Y22791D03*
X-10850Y30800D03*
X34719Y19455D03*
X8660Y27274D03*
X16400Y24744D03*
X10600Y25100D03*
X1068Y24831D03*
X27102Y25383D03*
X40530Y20220D03*
X43960Y20572D03*
X39530Y5205D03*
X45670Y5185D03*
X33370D03*
X45429Y-4669D03*
X33628Y131D03*
X40994Y-7148D03*
X45700Y40D03*
X11539Y31427D03*
X27200Y30600D03*
X27239Y28027D03*
X25600Y32500D03*
X11600Y33944D03*
X37739Y19501D03*
X13716Y24861D03*
X2934Y26933D03*
X23728Y18731D03*
X26760Y49595D03*
X-8610Y59810D03*
X-1750Y43320D03*
X-1920Y47290D03*
X27800Y86900D03*
X22100Y56400D03*
X6500Y84400D03*
X6600Y87900D03*
X27800Y89900D03*
Y83900D03*
X9425Y88067D03*
X11925D03*
X30400Y89800D03*
Y86800D03*
Y83800D03*
X8700Y49700D03*
X-1470Y63910D03*
X1863Y59426D03*
X1572Y38307D03*
X14025Y56211D03*
X-3560Y34620D03*
X-13610Y64360D03*
X-9987Y50899D03*
X-7050Y50900D03*
X-10470Y64450D03*
X-8370Y62600D03*
X-6010Y61030D03*
X-9390Y67410D03*
X8988Y58267D03*
X3600Y36200D03*
X16625Y56211D03*
X3100Y65900D03*
X10925Y56167D03*
X27904Y56294D03*
X30686Y79943D03*
X23530Y94840D03*
X11030D03*
X13530D03*
X16030D03*
X18530D03*
X22380Y92670D03*
X21030Y94840D03*
X2380Y92670D03*
X4880D03*
X7380D03*
X9880D03*
X12380D03*
X14880D03*
X17380D03*
X19880D03*
X3530Y94840D03*
X6030D03*
X8530D03*
X-1000Y81500D03*
X24880Y92670D03*
X25870Y80880D03*
X28294Y80889D03*
X32500Y81791D03*
X35650Y91150D03*
X34000Y93350D03*
X5500Y77444D03*
X5600Y80444D03*
X11625Y81267D03*
X9125D03*
X-8562Y81858D03*
Y79358D03*
X-14102Y81858D03*
Y79358D03*
X-5912Y84258D03*
X-8812Y84308D03*
X-5930Y79358D03*
X-5860Y81858D03*
X-11452Y79308D03*
Y81808D03*
X9225Y84467D03*
X11725D03*
X25100Y56300D03*
X-1190Y53240D03*
X11200Y49600D03*
X14010Y49570D03*
X11925Y74867D03*
X11864Y71294D03*
X11539Y39927D03*
X11500Y43400D03*
X11539Y47127D03*
X25886Y71467D03*
X25925Y75867D03*
X26185Y67017D03*
X27488Y64671D03*
X11925Y65311D03*
X27625Y73967D03*
X27525Y69367D03*
X11925Y67811D03*
X11864Y62794D03*
X24064Y61894D03*
X15111Y62553D03*
X27564Y61894D03*
X11600Y36444D03*
X25900Y40300D03*
X27564Y59394D03*
X24064D03*
X25700Y36200D03*
X27300Y34300D03*
Y38300D03*
X27208Y42313D03*
X27239Y47027D03*
X25700Y44400D03*
X27525Y77867D03*
X11864Y78494D03*
X1382Y68100D03*
X1826Y56447D03*
X44200Y139400D03*
X44300Y144800D03*
X44200Y130700D03*
Y116800D03*
X44100Y97800D03*
X44200Y111500D03*
X44300Y102700D03*
Y125600D03*
X39109Y154901D03*
X44600Y154100D03*
X37037Y138425D03*
X46900Y139750D03*
X47309Y154356D03*
X46900Y144750D03*
Y130750D03*
Y116750D03*
Y97750D03*
Y102750D03*
Y111750D03*
Y125750D03*
X-12861Y163165D03*
X5120Y276058D03*
X2269Y273532D03*
X19904Y254162D03*
X41000Y265350D03*
X37000D03*
X41000Y274647D03*
X37000Y275000D03*
X44310Y268160D03*
X33490Y267900D03*
X3806Y302347D03*
X1500Y295000D03*
X7995Y285385D03*
X6806Y302347D03*
X47100Y327000D03*
X2450Y460000D03*
X32450Y454050D03*
X35100Y453900D03*
X35900Y423500D03*
X37550Y425400D03*
X43550Y431300D03*
X40965Y429434D03*
X20075Y424850D03*
X12025Y427900D03*
Y424850D03*
X17025D03*
X7025Y427900D03*
X2025D03*
Y424850D03*
X7025D03*
X21397Y439354D03*
Y444354D03*
X24447Y439354D03*
Y444354D03*
X10786Y441785D03*
X15786D03*
X18836D03*
X7736D03*
X10365Y461602D03*
X-6100Y464840D03*
X11100Y446200D03*
X-6104Y461190D03*
X46100Y416271D03*
Y413520D03*
X5000Y469000D03*
X2350Y469650D03*
X10443Y490649D03*
X40132Y499800D03*
X-6712Y515731D03*
X2160Y479000D03*
X-6676Y501800D03*
X44050Y504383D03*
X-9900Y486400D03*
X-13500D03*
X17000Y475500D03*
X-6650Y487800D03*
X-14190Y473840D03*
X-5690Y467840D03*
X14500Y475500D03*
X11972Y475417D03*
X5100Y478330D03*
X-11490Y473840D03*
X-2430Y524340D03*
X-4350Y482100D03*
X2589Y481983D03*
X-900Y482300D03*
X22491Y500618D03*
X24400Y519500D03*
X280Y524350D03*
X-9600Y526100D03*
X46507Y523953D03*
X40185Y482918D03*
X37568Y482836D03*
X34300Y482890D03*
X31477Y482788D03*
X26780Y488910D03*
X41993Y523425D03*
X37000Y511200D03*
X39200Y509500D03*
X40111Y520623D03*
X31800Y510600D03*
X38389Y523748D03*
X34300Y511000D03*
X37600Y507400D03*
X35707Y509055D03*
X21000Y495800D03*
X6748Y517021D03*
X3354Y517143D03*
X13300Y509600D03*
X13600Y504300D03*
X4000Y509500D03*
X2485Y498185D03*
X13700Y498500D03*
X-5680Y524570D03*
X10932Y523601D03*
X14700Y517000D03*
X-7360Y512000D03*
X-2083Y513704D03*
X-1000Y479000D03*
X5689Y481983D03*
X27280Y510420D03*
X-6200Y505400D03*
X24591Y479139D03*
X35896Y557668D03*
X33396D03*
X38696D03*
X-10200Y558200D03*
X3600Y531300D03*
X-10947Y544117D03*
X-4100Y554400D03*
X-9287Y531604D03*
X21700Y532300D03*
X19100D03*
X27000D03*
X1040Y531218D03*
X-8318Y542216D03*
X6200Y531300D03*
X-3100Y533991D03*
X21948Y566700D03*
X19448D03*
X27114Y557563D03*
X24748Y566700D03*
X0Y566800D03*
X-8200Y578600D03*
X6200Y567300D03*
X-2500Y569500D03*
X-12600Y578900D03*
X-4300Y558400D03*
X1400Y556500D03*
X-1200D03*
X3600Y567300D03*
X-9283Y571324D03*
X29400Y532300D03*
X46400Y536290D03*
Y539790D03*
X43505Y538714D03*
X43241Y535965D03*
X41500Y533800D03*
X29914Y557563D03*
X45880Y554710D03*
Y557820D03*
X46560Y581000D03*
Y577500D03*
X1439Y546583D03*
Y553783D03*
X1539Y550183D03*
X1500Y540600D03*
X15787Y551700D03*
X17100Y545400D03*
X13639Y534683D03*
Y537183D03*
X15800Y543300D03*
X15600Y539100D03*
X17139Y534683D03*
Y537183D03*
X17100Y541200D03*
X17035Y549558D03*
X15800Y547500D03*
X17139Y553683D03*
X1500Y543100D03*
X1439Y538083D03*
X15800Y579500D03*
Y575300D03*
X17108Y585513D03*
X17156Y581481D03*
X17100Y577400D03*
X17139Y573183D03*
X1500Y576600D03*
X17139Y570683D03*
X1500Y579100D03*
X1539Y586183D03*
X1439Y582583D03*
Y574083D03*
X15770Y587700D03*
X15800Y583500D03*
X-6566Y568363D03*
X-9291Y535201D03*
X27495Y591409D03*
X-900Y592500D03*
X1600D03*
X-4500Y594000D03*
X-12450Y590965D03*
X30212Y591417D03*
X35085Y591621D03*
X32609Y591538D03*
X46500Y595190D03*
X43190Y598410D03*
X43210Y595180D03*
X43190Y601910D03*
X1439Y589783D03*
X17139Y589683D03*
X77000Y25992D03*
X74000D03*
X62000Y28500D03*
X59500D03*
X65000D03*
X68000D03*
X71000D03*
X74000D03*
X77000D03*
X80000Y29000D03*
Y26000D03*
X62000D03*
X59500D03*
X65000D03*
X71000Y25992D03*
X68000D03*
X65800Y14200D03*
X59061Y476D03*
X61152Y-12752D03*
X71172Y-18486D03*
X52389Y-14258D03*
X52744Y-4368D03*
X74386Y-18439D03*
X67564Y-20745D03*
X65164Y-19456D03*
X59281Y-20641D03*
X104500Y-1850D03*
X64159Y11303D03*
X50586Y-20687D03*
X63683Y-12866D03*
X66061Y-13689D03*
X60035Y7508D03*
X106000Y17260D03*
X87091Y-16391D03*
X88777Y-10586D03*
X82300Y-16600D03*
X93500Y-18000D03*
X82013Y14129D03*
X79372Y14895D03*
X79096Y9886D03*
X79116Y12361D03*
X81669Y11693D03*
X81610Y9159D03*
X64200Y17389D03*
X99102Y-12010D03*
X105892Y8700D03*
X62076Y5575D03*
X76247Y1189D03*
X84202Y-11395D03*
X81702D03*
X79202D03*
X73611Y1158D03*
X71111D03*
X68611D03*
X73574Y-1437D03*
X71074D03*
X68574D03*
X79500Y-16600D03*
X55713Y-5095D03*
X76165Y-1415D03*
X62008Y13249D03*
X106200Y26500D03*
X61446Y18238D03*
X62536Y-2379D03*
X61994Y362D03*
X54307Y-8051D03*
X62486Y-19184D03*
X51090Y8080D03*
X53382Y-1173D03*
X60500Y79000D03*
X70500Y70500D03*
X73000D03*
X78000D03*
X75500D03*
X81000Y61500D03*
Y58500D03*
X63000Y74000D03*
X60500D03*
X63000Y76500D03*
X60500D03*
X67500Y49500D03*
X70500D03*
X73500D03*
X79500D03*
X61500Y43500D03*
X59000D03*
X64500D03*
X67500D03*
X70500D03*
X60500Y70500D03*
X63000D03*
X61500Y58500D03*
Y49500D03*
X59000Y56000D03*
X61500D03*
X59000Y49500D03*
X76500Y43500D03*
X79500Y82000D03*
Y46500D03*
X76500D03*
X73500D03*
X70500D03*
X67500D03*
X64500D03*
X59000D03*
X61500D03*
X68000Y70500D03*
X65500D03*
X79500Y43500D03*
X63000Y81500D03*
X59000Y58500D03*
X61500Y61000D03*
X59000D03*
X76500Y49500D03*
X73500Y43500D03*
X64500Y49500D03*
X79500Y79000D03*
X63000D03*
X60500Y81500D03*
X79500Y72500D03*
X102100Y73800D03*
X105892Y45290D03*
X52500Y67200D03*
Y63700D03*
Y60700D03*
Y37700D03*
Y34700D03*
Y43700D03*
Y40700D03*
Y57700D03*
X82046Y90043D03*
X100140Y83170D03*
X79725Y75993D03*
X71050Y89600D03*
X48700Y90700D03*
Y95500D03*
X61300Y89800D03*
X81861Y93392D03*
X86600Y94000D03*
X76106Y89337D03*
X108385Y84291D03*
X68725Y90900D03*
X63725D03*
X51381Y90750D03*
X105898Y55194D03*
X63737Y130602D03*
X48900Y132600D03*
X68592D03*
X85250Y127680D03*
X77730Y126860D03*
X63858Y97620D03*
X66600Y102360D03*
X62422Y109413D03*
X68000Y111000D03*
X48900Y123500D03*
X62524Y123395D03*
X68584Y123900D03*
X68654Y118680D03*
X48800Y118900D03*
X48700Y109600D03*
X48600Y104900D03*
X63582Y116409D03*
X62502Y105100D03*
X52500Y152000D03*
X60300Y151500D03*
X70800Y151400D03*
X79670Y132300D03*
X91913Y121318D03*
X77790Y121030D03*
X70980Y97166D03*
X104424Y110833D03*
X98420Y112198D03*
X48800Y137600D03*
X63878Y144800D03*
X68632Y137800D03*
X63888Y140064D03*
X87200Y152374D03*
X107254Y128041D03*
X75660Y152380D03*
X78950Y152810D03*
X51381Y104750D03*
Y109750D03*
X63098Y151473D03*
X68098D03*
X51309Y154356D03*
X51569Y132750D03*
Y118750D03*
X51381Y95750D03*
X51569Y123750D03*
Y137750D03*
X65384Y109750D03*
Y104750D03*
X65405Y118730D03*
X60831Y144750D03*
X65687Y132750D03*
X60831Y130750D03*
X60700Y116750D03*
X60801Y97750D03*
X60831Y139750D03*
X65687Y137750D03*
X60831Y125750D03*
X65405Y123730D03*
X60700Y111750D03*
X60801Y102750D03*
X91306Y157194D03*
X106698Y215610D03*
X102507Y211047D03*
X107700Y211040D03*
X100500Y188600D03*
X97500Y185700D03*
X104800D03*
X102400D03*
X99900D03*
X77650Y178150D03*
X76143Y183019D03*
X61402Y177773D03*
X97900Y194500D03*
X104820Y198800D03*
X97800Y197600D03*
X104820Y202100D03*
X90831Y184982D03*
X86952Y181721D03*
X87151Y184872D03*
X61800Y191600D03*
X99250Y160370D03*
X61356Y181000D03*
X61256Y186000D03*
X64187Y176332D03*
X104820Y195700D03*
X97800Y200800D03*
X86731Y189148D03*
X73500Y191500D03*
X107750Y238730D03*
X99500Y223800D03*
X83300Y267400D03*
X84000Y272500D03*
X79300Y272300D03*
X57500Y254100D03*
X62000Y278000D03*
X59500D03*
X108000Y249330D03*
X99758Y240300D03*
X53400Y277582D03*
Y274500D03*
X97200Y265000D03*
X91600Y278700D03*
X69125Y310625D03*
X98538Y341139D03*
X94360Y335210D03*
X94938Y323467D03*
X92086Y324258D03*
X48800Y282600D03*
Y285100D03*
X53500Y307300D03*
X48800Y292400D03*
Y289600D03*
X53400Y298100D03*
X61900Y286200D03*
X68300Y281600D03*
X70900D03*
X66300Y285850D03*
X58700Y283000D03*
X58600Y297200D03*
X58700Y299800D03*
X88600Y302997D03*
X75626Y310418D03*
X72100Y321800D03*
X79410Y331636D03*
X84000Y324542D03*
X53100Y327000D03*
X74800Y338850D03*
X69000Y338800D03*
X72000D03*
X81324Y316119D03*
X82500Y341400D03*
X65800Y338900D03*
X54400Y340300D03*
X64000Y313900D03*
Y316500D03*
X56300Y338500D03*
X79400Y325400D03*
X74887Y321780D03*
X79600Y335200D03*
X49200Y340650D03*
X87400Y337200D03*
X77600Y320800D03*
X68418Y336150D03*
X53100Y315000D03*
X59452Y338800D03*
X82150Y335800D03*
X66900Y322000D03*
X85300Y335750D03*
X69500Y322000D03*
X58400Y314600D03*
X77300Y315600D03*
X53000Y323500D03*
X52804Y333247D03*
X61300Y328600D03*
X84000Y316083D03*
X70700Y330349D03*
X103500Y302100D03*
X93500Y289000D03*
X93400Y296000D03*
X103500Y304700D03*
Y308500D03*
X102322Y295478D03*
X104600Y316602D03*
X103200Y335190D03*
X100550Y335140D03*
X103200Y330190D03*
X88840Y324740D03*
X98680Y338080D03*
X99770Y325249D03*
X71500Y298000D03*
X66000Y292700D03*
X76800Y298000D03*
X76900Y292600D03*
X66500Y303400D03*
X76800D03*
X62900Y339000D03*
X53250Y302800D03*
X48550Y301650D03*
X64700Y310525D03*
X84300Y305700D03*
Y310700D03*
X61625Y283201D03*
X72904Y284898D03*
X84300Y289000D03*
X82050Y283951D03*
X77103Y283900D03*
X84866Y294213D03*
X84300Y299000D03*
X58600Y302700D03*
X72600Y310800D03*
X77500Y312500D03*
X53025Y337475D03*
X93500Y285000D03*
X67400Y391690D03*
X67230Y397380D03*
X64725Y391645D03*
Y396645D03*
X67710Y402040D03*
X65384Y403258D03*
X93712Y380507D03*
X66350Y347950D03*
X87900Y347500D03*
X88000Y343900D03*
X51900Y351000D03*
X63800Y348600D03*
X58271Y363669D03*
X61041Y351737D03*
X49091Y351509D03*
X49017Y346509D03*
X49117Y349009D03*
X49017Y344009D03*
X55616Y368998D03*
X52000Y354500D03*
X60400Y355750D03*
X90518Y388828D03*
X54900Y389400D03*
X74800Y383114D03*
X85609Y385234D03*
X61000Y383000D03*
X57500Y388100D03*
X77300Y390600D03*
X101880Y346300D03*
X102060Y351759D03*
X101750Y360120D03*
X101965Y368296D03*
X107224Y393848D03*
X50510Y359240D03*
X47970Y359550D03*
X76500Y368300D03*
X76300Y358400D03*
X82037Y358542D03*
X70600Y368400D03*
X82100Y368300D03*
X70900Y358300D03*
X102040Y348960D03*
X101828Y371096D03*
X51923Y346164D03*
X60934Y362307D03*
X57395Y366795D03*
X55500Y371700D03*
X61914Y368731D03*
X60900Y348300D03*
X79100Y347000D03*
X49100Y354500D03*
X57800Y376100D03*
X60565Y380131D03*
X65000Y383000D03*
X74800Y379700D03*
X80200D03*
X62600Y375100D03*
X102160Y354780D03*
X101770Y363150D03*
X97472Y380934D03*
X54244Y405624D03*
X51500Y406000D03*
X57471Y410749D03*
X56383Y408163D03*
X63024Y405636D03*
X64007Y408276D03*
X61005Y429305D03*
Y424305D03*
X63630Y424280D03*
X63600Y429000D03*
X49265Y423995D03*
Y418995D03*
X51890Y424470D03*
Y418970D03*
X54662Y416478D03*
X51645Y416281D03*
X103100Y411800D03*
X65450Y475610D03*
X67477Y477940D03*
X47800Y487600D03*
X47550Y504367D03*
X66750Y521900D03*
Y519400D03*
X64503Y521054D03*
X64380Y523606D03*
Y526202D03*
X64600Y515600D03*
X66750Y516900D03*
X64600Y518100D03*
X66840Y526800D03*
Y524300D03*
X47369Y527005D03*
X55500Y521800D03*
X53000Y524300D03*
Y521800D03*
X58000D03*
X55500Y519300D03*
X52992Y516846D03*
X58000Y524300D03*
X57936Y519212D03*
X53900Y505450D03*
X57100D03*
X60300D03*
X55500Y524300D03*
X53000Y519300D03*
X53900Y502250D03*
X60300D03*
X57100D03*
X88855Y522359D03*
X86100Y505200D03*
X72603Y474072D03*
X59731Y480066D03*
X66016Y468350D03*
X89497Y479201D03*
X60300Y508650D03*
X51607Y511747D03*
X74480Y504480D03*
X79630Y504580D03*
X60000Y526500D03*
X79400Y502150D03*
X74600Y502064D03*
X77000Y502133D03*
X49800Y524300D03*
X76996Y504587D03*
X60700Y521900D03*
X57936Y516012D03*
X60202Y495342D03*
X57302Y495442D03*
X105958Y518550D03*
X91650Y522000D03*
X94998Y481612D03*
X106392Y527413D03*
X71050Y478670D03*
X92326Y480398D03*
X77960Y541468D03*
Y538468D03*
X75461Y541468D03*
Y538468D03*
X73009Y541444D03*
Y538444D03*
X62500Y535500D03*
X71500Y575000D03*
Y578000D03*
Y582000D03*
X81500Y575000D03*
X78500D03*
X81500Y578000D03*
X78500D03*
X74500Y575000D03*
Y578000D03*
Y582000D03*
X81500D03*
X78500D03*
X75500Y557500D03*
X72500Y561500D03*
Y557500D03*
X69500Y561500D03*
Y557500D03*
X75500Y561500D03*
X78500D03*
X81500D03*
Y557500D03*
X78500D03*
X66500Y554500D03*
X70521Y538403D03*
X63500Y554500D03*
X68500Y535500D03*
X65500D03*
X70498Y541394D03*
X75500Y554500D03*
X72500D03*
X69500D03*
X81500D03*
X78500D03*
X80389Y541468D03*
Y538468D03*
X66500Y557500D03*
X63500Y561500D03*
Y557500D03*
X66500Y561500D03*
X106392Y537000D03*
X105392Y574800D03*
X105412Y556580D03*
X105392Y566000D03*
X86230Y620250D03*
X89360Y620310D03*
X105000Y614533D03*
X102236Y614167D03*
X91150Y618250D03*
X93800Y618111D03*
X82459Y618932D03*
X78500Y615500D03*
X81500D03*
X75500D03*
X72500D03*
X69500D03*
X78500Y602000D03*
X72500D03*
X69500Y596000D03*
X81500Y599000D03*
X78500D03*
X81500Y596000D03*
Y612000D03*
X78500D03*
X69500Y599000D03*
Y602000D03*
X75500D03*
X78500Y596000D03*
X72500D03*
X63500Y602000D03*
Y596000D03*
X66500Y599000D03*
Y602000D03*
X63500Y599000D03*
X66500Y596000D03*
X81500Y602000D03*
X75500Y596000D03*
X72500Y599000D03*
X75500D03*
X105352Y594770D03*
X101898Y611483D03*
X91952Y620900D03*
X106192Y604600D03*
X114000Y3500D03*
X114680Y17320D03*
X150391Y14814D03*
X163427Y14714D03*
X157084Y14814D03*
X160431Y-1801D03*
X153738Y9114D03*
X150391Y-7851D03*
X163391D03*
X157084D03*
X153738Y-1751D03*
X160431Y9114D03*
X126616Y14714D03*
X136756Y16900D03*
X120273Y16839D03*
X132959Y14814D03*
X141880Y17114D03*
X147045Y9114D03*
X130163D03*
X141856Y9100D03*
X136780Y9098D03*
X123620Y9114D03*
X126580Y-7851D03*
X132959Y-7700D03*
X120273Y-9901D03*
X141893Y-9864D03*
X136806Y-9650D03*
X136780Y-1801D03*
X123620D03*
X130313Y-1751D03*
X141906Y-2050D03*
X147045Y-1751D03*
X169770Y14814D03*
X167124Y-1751D03*
X169770Y-7700D03*
X166974Y9114D03*
X114100Y6120D03*
X116300Y-9460D03*
X116692Y-1800D03*
X114050Y21320D03*
X169770Y30100D03*
X120273Y27899D03*
X141893Y27936D03*
X136806Y28150D03*
X126580Y29949D03*
X132959Y30100D03*
X157084Y29949D03*
X163391D03*
X150391D03*
X132959Y-4100D03*
X130313Y-9901D03*
X126580Y-4100D03*
X123620Y-9901D03*
X147045D03*
X141880Y-7260D03*
X136806Y-7050D03*
X136780Y-4401D03*
X132959Y33700D03*
X130313Y27899D03*
X126580Y33700D03*
X123620Y27899D03*
X147045D03*
X141880Y30540D03*
X136806Y30750D03*
X141880Y33149D03*
X136780Y33399D03*
X130313Y17157D03*
X132959Y12114D03*
X123620Y17157D03*
X126666Y12114D03*
X147045Y17157D03*
X141880Y14514D03*
X136780Y14300D03*
X141880Y11914D03*
X136780Y11700D03*
X163391Y-4100D03*
X160431Y-9901D03*
X157084Y-3700D03*
X153738Y-9901D03*
X150391Y-3700D03*
X169770Y-4100D03*
X167124Y-9901D03*
X163391Y33700D03*
X160431Y27899D03*
X153738D03*
X169770Y33700D03*
X167124Y27899D03*
X160431Y17157D03*
X163477Y12114D03*
X153738Y17157D03*
X157084Y12114D03*
X150391D03*
X167124Y17157D03*
X169770Y12114D03*
X120273Y9157D03*
X141880Y-4651D03*
X169770Y90364D03*
X166974Y84714D03*
Y73849D03*
Y46914D03*
X169770Y52614D03*
X167124Y36049D03*
X169770Y67900D03*
X157084Y67749D03*
X163391D03*
X130313Y73849D03*
X123620Y73799D03*
X141906Y73550D03*
X136780Y73799D03*
X126580Y67749D03*
X132959Y67900D03*
X141880Y54914D03*
X123620Y35983D03*
X141856Y46900D03*
X141906Y35750D03*
X136806Y65950D03*
X141893Y65736D03*
X136756Y54700D03*
X136780Y35999D03*
X130313Y35983D03*
X123620Y46914D03*
X132959Y52614D03*
X126616Y52514D03*
X147045Y46914D03*
Y36049D03*
X120273Y54839D03*
X119892Y84700D03*
X120273Y92500D03*
X126616Y90314D03*
X132959Y90414D03*
X141880Y92714D03*
X163427Y90314D03*
X157084Y90414D03*
X150391D03*
X160431Y84714D03*
X153738D03*
X136756Y92500D03*
X141856Y84700D03*
X136780Y84698D03*
X123620Y84714D03*
X147045D03*
X130163D03*
X109057Y92774D03*
X112007Y93139D03*
X116070Y35780D03*
X113100Y57770D03*
X115980Y73680D03*
X116200Y70387D03*
X114082Y55100D03*
X130163Y46914D03*
X136780Y46898D03*
X120273Y66000D03*
X147045Y73849D03*
X153738Y36049D03*
Y73849D03*
X160431Y73799D03*
X157084Y52614D03*
X160431Y35999D03*
X150391Y67749D03*
Y52614D03*
X163427Y52514D03*
X160431Y46914D03*
X153738D03*
X130313Y65699D03*
X123620D03*
X147045D03*
X136806Y68550D03*
X141880Y68340D03*
X130313Y54957D03*
X132959Y49914D03*
X123620Y54957D03*
X126666Y49914D03*
X147045Y54957D03*
X141880Y52314D03*
X136780Y52100D03*
X141880Y49714D03*
X136780Y49500D03*
X132959Y87714D03*
X126580Y71500D03*
X123620Y92757D03*
X126666Y87714D03*
X147045Y92757D03*
X141880Y70949D03*
Y87514D03*
X136780Y89900D03*
X141880Y90114D03*
X136780Y71199D03*
Y87300D03*
X132959Y71500D03*
X130313Y92757D03*
X160431Y65699D03*
X153738D03*
X167124D03*
X160431Y54957D03*
X163477Y49914D03*
X157084Y34100D03*
X153738Y54957D03*
X157084Y49914D03*
X150391Y34100D03*
Y49914D03*
X167124Y54957D03*
X169770Y49914D03*
X157084Y71900D03*
X153738Y92757D03*
X157084Y87714D03*
X150391Y71900D03*
Y87714D03*
X169770Y71500D03*
X167124Y92757D03*
X169770Y87714D03*
X163391Y71500D03*
X160431Y92757D03*
X163477Y87714D03*
X120273Y46957D03*
X117652Y132792D03*
X120117Y132865D03*
X120138Y130408D03*
X117682Y130387D03*
X112664Y128795D03*
X120533Y109535D03*
X120197Y106587D03*
X109622Y128879D03*
X156954Y192872D03*
X154454Y193021D03*
X151810Y192670D03*
X124895Y212033D03*
X127754Y211853D03*
X122542Y214019D03*
X130324Y212033D03*
X115508Y216512D03*
X153788Y187309D03*
X156928Y190053D03*
X148900Y180400D03*
X148800Y185300D03*
Y182900D03*
X148900Y190100D03*
X148800Y187700D03*
X113800Y180500D03*
X116900D03*
X124340Y197750D03*
X117600Y193805D03*
X151359Y187700D03*
X156294Y187625D03*
X151300Y190200D03*
X141263Y215216D03*
X125563Y218616D03*
X137763Y217716D03*
X128500Y218700D03*
X141263Y217716D03*
X137763Y215216D03*
X115536Y213508D03*
X154130Y190186D03*
X162788Y200650D03*
X162800Y195600D03*
X150000Y199850D03*
Y194850D03*
X117080Y225330D03*
X169150Y223600D03*
Y227600D03*
X112904Y237218D03*
X118008Y220991D03*
X116310Y222940D03*
X122820Y244133D03*
X115497Y248376D03*
X130324Y244033D03*
X122203Y246675D03*
X127500Y243500D03*
X123074Y275948D03*
X113100Y269163D03*
X115508Y280512D03*
X130324Y276033D03*
X116000Y254643D03*
X127500Y275500D03*
X117063Y257016D03*
X118008Y252991D03*
X122400Y278671D03*
X125624Y223633D03*
Y221133D03*
X141263Y234216D03*
X141200Y229600D03*
X141211Y225615D03*
X141300Y221700D03*
X139763Y231700D03*
Y227600D03*
Y223700D03*
X139582Y219800D03*
X125563Y234316D03*
X125663Y230716D03*
X125563Y227116D03*
X128200Y250700D03*
X125563Y250616D03*
X141263Y249716D03*
Y247216D03*
X137763D03*
Y249716D03*
X125624Y255633D03*
X125563Y259116D03*
X125663Y262716D03*
X125563Y266316D03*
X141300Y253700D03*
X139631Y251900D03*
X125624Y253133D03*
X137763Y279216D03*
X141263Y266216D03*
X139763Y255700D03*
Y259600D03*
X139800Y263700D03*
X141313Y257533D03*
X141263Y279216D03*
X141200Y261600D03*
X115525Y245372D03*
X115536Y277508D03*
X137300Y337200D03*
X118800Y298400D03*
X123301Y308044D03*
X110180Y280920D03*
X130324Y308033D03*
X127500Y307500D03*
X115508Y312512D03*
X129700Y340152D03*
X127000Y339000D03*
X109960Y313190D03*
X119050Y341625D03*
X116000Y286643D03*
X113000Y304000D03*
X117063Y289016D03*
X118008Y284991D03*
X122493Y310633D03*
X116000Y318643D03*
X118008Y316991D03*
X117063Y321016D03*
X113100Y333106D03*
X125624Y287633D03*
X125663Y294716D03*
X125563Y298316D03*
Y291116D03*
X128200Y282600D03*
X141263Y311216D03*
X137763D03*
X141263Y281716D03*
X139730Y284200D03*
X139763Y288200D03*
Y292000D03*
Y296000D03*
X125624Y285133D03*
X141200Y286100D03*
X141261Y290076D03*
X141300Y294000D03*
X141263Y298216D03*
X137763Y281716D03*
X125563Y282616D03*
X141211Y325515D03*
X128200Y314800D03*
X141263Y330216D03*
X139763Y327800D03*
X141300Y317500D03*
Y321500D03*
X139582Y315800D03*
X139763Y319400D03*
X125563Y323116D03*
X125663Y326716D03*
X125563Y330316D03*
Y314616D03*
X141263Y313716D03*
X137763D03*
X139763Y323600D03*
X125624Y317133D03*
Y319633D03*
X115536Y309508D03*
Y341508D03*
X109640Y376070D03*
X113500Y369000D03*
X115508Y344512D03*
X130585Y372085D03*
X127420Y371590D03*
X110670Y344500D03*
X112600Y366300D03*
X122300Y372100D03*
X119300Y400900D03*
X110397Y402603D03*
X109924Y393848D03*
X116000Y382643D03*
X122473Y374716D03*
X117063Y385016D03*
X153392Y404000D03*
X122361Y342649D03*
X116000Y350643D03*
X118008Y348991D03*
X117063Y353016D03*
X141289Y349488D03*
X128100Y346700D03*
X141300Y353300D03*
X141200Y357200D03*
X137763Y345716D03*
X141263D03*
Y343216D03*
X125624Y349133D03*
X137763Y343216D03*
X125563Y362316D03*
Y355116D03*
X125663Y358716D03*
X141263Y362216D03*
X139582Y347800D03*
X139763Y351400D03*
Y355200D03*
Y359500D03*
X125624Y351633D03*
X125563Y346616D03*
X141300Y381800D03*
X139763Y384000D03*
X125624Y381133D03*
X141263Y394216D03*
Y390416D03*
X141261Y385876D03*
X139736Y392300D03*
X125563Y378616D03*
X125663Y390716D03*
X125563Y387116D03*
Y394316D03*
X137763Y375216D03*
X141263D03*
Y377716D03*
X137763D03*
X139631Y379900D03*
X128500Y378700D03*
X139900Y388000D03*
X125624Y383633D03*
X118220Y360500D03*
X118629Y381193D03*
X109500Y370000D03*
X157862Y416012D03*
X117363Y417416D03*
X121981Y405573D03*
X110452Y407092D03*
X148666Y417397D03*
X148300Y414600D03*
X148409Y422239D03*
X119100Y411600D03*
X119016Y414201D03*
X119398Y406348D03*
X122242Y419199D03*
X123441Y421795D03*
X151909Y413267D03*
X153392Y407500D03*
X167680Y408440D03*
X167640Y404842D03*
X150650Y409860D03*
X111961Y499877D03*
X130163Y510114D03*
X147045D03*
X132959Y515814D03*
X126616Y515714D03*
X120273Y517900D03*
X136780Y510098D03*
X136756Y517900D03*
X141856Y510100D03*
X141880Y518114D03*
X123620Y510114D03*
X119892Y510100D03*
X114322Y525980D03*
X114442Y510300D03*
Y507800D03*
X116927Y517900D03*
X150391Y515814D03*
X169770Y515764D03*
X163427Y515714D03*
X166974Y510114D03*
X160431D03*
X157084Y515814D03*
X153738Y510114D03*
X112427Y497225D03*
X132959Y513114D03*
X163477D03*
X160431Y518157D03*
X130313D03*
X136780Y512700D03*
X141880Y515514D03*
X136780Y515300D03*
X141880Y512914D03*
X169770Y513114D03*
X167124Y518157D03*
X150391Y513114D03*
X147045Y518157D03*
X126666Y513114D03*
X123620Y518157D03*
X157084Y513114D03*
X153738Y518157D03*
X141893Y528936D03*
X136806Y529150D03*
X141906Y536750D03*
X132959Y553614D03*
X126616Y553514D03*
X130163Y547914D03*
X123620D03*
X136780Y547898D03*
X141856Y547900D03*
X147045Y537049D03*
Y547914D03*
X120210Y529200D03*
X130313Y537049D03*
X132959Y531100D03*
X126580Y530949D03*
X123620Y536999D03*
X136780D03*
X114792Y528600D03*
X119892Y536983D03*
Y547900D03*
X115883Y548024D03*
X123620Y574799D03*
X130313Y574849D03*
X132959Y568900D03*
X126580Y568749D03*
X141856Y585700D03*
X141906Y574550D03*
X136780Y574799D03*
Y585698D03*
X120092Y566900D03*
X136806Y566950D03*
X147045Y585714D03*
Y574849D03*
X113692Y566000D03*
X119892Y574700D03*
Y585700D03*
X114509Y575658D03*
X114150Y585850D03*
X116927Y555700D03*
X141880Y555914D03*
X120273Y555700D03*
X136756D03*
X141893Y566736D03*
X130163Y585714D03*
X123620D03*
X150391Y530949D03*
Y553614D03*
X166974Y537049D03*
X163391Y530949D03*
X160431Y536999D03*
X169770Y553564D03*
X163427Y553514D03*
X166974Y547914D03*
X160431D03*
X157084Y530949D03*
X153738Y537049D03*
X157084Y553614D03*
X153738Y547914D03*
X169770Y531100D03*
X150391Y568749D03*
X163391D03*
X160431Y585714D03*
X166974D03*
Y574849D03*
X160431Y574799D03*
X169770Y568900D03*
X157084Y568749D03*
X153738Y585714D03*
Y574849D03*
X130313Y528899D03*
X132959Y588714D03*
X160431Y528899D03*
X163391Y534700D03*
X132959D03*
X136780Y550500D03*
X141880Y553314D03*
X136780Y553100D03*
X141880Y550714D03*
X169770Y550914D03*
X167124Y555957D03*
X150391Y550914D03*
X147045Y555957D03*
X126666Y550914D03*
X123620Y555957D03*
X157084Y550914D03*
X153738Y555957D03*
X132959Y550914D03*
X163477D03*
X160431Y555957D03*
X130313D03*
X136780Y534399D03*
X141880Y531540D03*
X136806Y531750D03*
X141880Y534149D03*
X167124Y528899D03*
X169770Y534700D03*
X147045Y528899D03*
X150391Y535100D03*
X123620Y528899D03*
X126580Y534700D03*
X153738Y528899D03*
X157084Y535100D03*
X136780Y588300D03*
X141880Y588514D03*
X169770Y588714D03*
X150391D03*
X126666D03*
X157084D03*
X163477D03*
X136780Y572199D03*
X136806Y569550D03*
X141880Y571949D03*
X167124Y566699D03*
X169770Y572500D03*
X147045Y566699D03*
X150391Y572900D03*
X123620Y566699D03*
X126580Y572500D03*
X153738Y566699D03*
X157084Y572900D03*
X130313Y566699D03*
X160431D03*
X163391Y572500D03*
X132959D03*
X141880Y569340D03*
X147045Y612649D03*
X123620Y612599D03*
X136780D03*
X130313Y612649D03*
X119892Y612583D03*
X160431Y612599D03*
X166974Y612649D03*
X153738D03*
X126616Y591314D03*
X116992Y590700D03*
X132959Y591414D03*
X136756Y593500D03*
X141880Y593714D03*
X132959Y606700D03*
X126580Y606549D03*
X120092Y604900D03*
X141906Y612350D03*
X136806Y604750D03*
X141893Y604536D03*
X114792Y604600D03*
X116927Y593500D03*
X150391Y591414D03*
Y606549D03*
X163427Y591314D03*
X163391Y606549D03*
X169770Y606700D03*
Y591364D03*
X157084Y591414D03*
Y606549D03*
X130313Y604499D03*
X136780Y609999D03*
X141880Y607140D03*
Y591114D03*
X136806Y607350D03*
X136780Y590900D03*
X167124Y604499D03*
Y593757D03*
X169770Y610300D03*
X147045Y604499D03*
X150391Y610700D03*
X147045Y593757D03*
X123620Y604499D03*
X126580Y610300D03*
X123620Y593757D03*
X153738Y604499D03*
X157084Y610700D03*
X153738Y593757D03*
X160431Y604499D03*
X163391Y610300D03*
X160431Y593757D03*
X132959Y610300D03*
X130313Y593757D03*
X141880Y609749D03*
X173591Y-1801D03*
X178691Y17114D03*
X173567Y16900D03*
X178717Y-2050D03*
X183856Y-1751D03*
X173617Y-9650D03*
X178704Y-9864D03*
X178667Y9100D03*
X173591Y9098D03*
X183856Y9114D03*
X178704Y27936D03*
X173617Y28150D03*
X190549Y9114D03*
X197242D03*
X210402Y9098D03*
X210428Y-9650D03*
X193895Y-3700D03*
X190549Y-9901D03*
X187202Y-3700D03*
X183856Y-9901D03*
X206581Y-4100D03*
X203935Y-9901D03*
X200202Y-4100D03*
X197242Y-9901D03*
X173617Y-7050D03*
X210428D03*
X173591Y-4401D03*
X210402D03*
X178691Y-4651D03*
X193895Y-7851D03*
X187202D03*
X200202D03*
X210402Y-1801D03*
X190549Y-1751D03*
X197242Y-1801D03*
X203935Y-1751D03*
X206581Y-7700D03*
X203785Y9114D03*
X210378Y16900D03*
X210428Y28150D03*
X200202Y29949D03*
X187202D03*
X193895Y14814D03*
Y29949D03*
X200238Y14714D03*
X187202Y14814D03*
X206581D03*
X190549Y27899D03*
X183856D03*
X206581Y33700D03*
X203935Y27899D03*
X200202Y33700D03*
X197242Y27899D03*
X173617Y30750D03*
X210428D03*
X178691Y30540D03*
X173591Y33399D03*
X210402D03*
X178691Y33149D03*
X190549Y17157D03*
X193895Y12114D03*
X183856Y17157D03*
X187202Y12114D03*
X203935Y17157D03*
X206581Y12114D03*
X197242Y17157D03*
X200288Y12114D03*
X173591Y14300D03*
X210402D03*
X178691Y14514D03*
X173591Y11700D03*
X210402D03*
X178691Y11914D03*
X206581Y30100D03*
X224013Y-3700D03*
X220667Y-9901D03*
X215502Y-7260D03*
Y-4651D03*
X220667Y-1751D03*
X215528Y-2050D03*
X215515Y-9864D03*
X227360Y-1751D03*
X230706Y-7851D03*
X224013D03*
X215478Y9100D03*
X220667Y9114D03*
X227360D03*
X230706Y-3700D03*
X227360Y-9901D03*
X224013Y29949D03*
X230706D03*
Y14814D03*
X227360Y27899D03*
X220667D03*
X215502Y30540D03*
Y33149D03*
X227360Y17157D03*
X230706Y12114D03*
X220667Y17157D03*
X224013Y12114D03*
X215502Y14514D03*
Y11914D03*
X224013Y14814D03*
X215502Y17114D03*
X215515Y27936D03*
X178691Y-7260D03*
Y92714D03*
X173591Y84698D03*
X178667Y84700D03*
X183856Y84714D03*
X173567Y92500D03*
X183856Y36049D03*
X173591Y46898D03*
X183856Y73849D03*
X178717Y73550D03*
X173591Y73799D03*
X178691Y54914D03*
X173591Y35999D03*
X183856Y46914D03*
X178717Y35750D03*
X178667Y46900D03*
X173567Y54700D03*
X173617Y65950D03*
X178704Y65736D03*
X206581Y52614D03*
X210378Y54700D03*
X210402Y46898D03*
X193895Y67749D03*
X200202D03*
X187202D03*
X203785Y46914D03*
X190549D03*
X197242D03*
X200238Y52514D03*
X193895Y52614D03*
X187202D03*
X190549Y36049D03*
X203935D03*
X190549Y65699D03*
X183856D03*
X203935D03*
X197242D03*
X173617Y68550D03*
X210428D03*
X178691Y68340D03*
X190549Y54957D03*
X193895Y34100D03*
Y49914D03*
X183856Y54957D03*
X187202Y34100D03*
Y49914D03*
X203935Y54957D03*
X206581Y49914D03*
X197242Y54957D03*
X200288Y49914D03*
X173591Y52100D03*
X210402D03*
X178691Y52314D03*
X173591Y49500D03*
X210402D03*
X178691Y49714D03*
X197242Y35999D03*
X206581Y67900D03*
X210428Y65950D03*
X210402Y35999D03*
X173591Y89900D03*
X210402D03*
X178691Y70949D03*
Y87514D03*
X173591Y71199D03*
Y87300D03*
X210402Y71199D03*
Y87300D03*
X178691Y90114D03*
X197242Y73799D03*
X203935Y73849D03*
X210402Y73799D03*
Y84698D03*
X210378Y92500D03*
X190549Y73849D03*
Y84714D03*
X197242D03*
X203785D03*
X193895Y90414D03*
X206581D03*
X200238Y90314D03*
X187202Y90414D03*
X193895Y71900D03*
X190549Y92757D03*
X193895Y87714D03*
X187202Y71900D03*
X183856Y92757D03*
X187202Y87714D03*
X206581Y71500D03*
X203935Y92757D03*
X206581Y87714D03*
X200202Y71500D03*
X197242Y92757D03*
X200288Y87714D03*
X215478Y46900D03*
X215502Y54914D03*
X215515Y65736D03*
X224013Y52614D03*
X220667Y46914D03*
X230706Y52614D03*
X224013Y67749D03*
X230706D03*
X227360Y46914D03*
Y65699D03*
X220667D03*
X215502Y68340D03*
X227360Y54957D03*
X230706Y34100D03*
Y49914D03*
X220667Y54957D03*
X224013Y34100D03*
Y49914D03*
X215502Y52314D03*
Y49714D03*
X227360Y36049D03*
X220667D03*
X215528Y35750D03*
X215502Y92714D03*
X230706Y71900D03*
X227360Y92757D03*
X230706Y87714D03*
X224013Y71900D03*
X220667Y92761D03*
X224013Y87714D03*
X215502Y70949D03*
Y87514D03*
Y90114D03*
X220667Y73849D03*
Y84714D03*
X227360D03*
X230706Y90414D03*
X215478Y84700D03*
X215528Y73550D03*
X227360Y73849D03*
X224013Y90414D03*
X197617Y243089D03*
X191537Y242989D03*
Y240489D03*
X197617Y240589D03*
X191537Y237989D03*
X197617Y238089D03*
X192037Y270750D03*
X194537D03*
X197037D03*
X206800Y246500D03*
X194537Y299750D03*
X197037D03*
X192037D03*
X194537Y332480D03*
X197037D03*
X192037D03*
X203947Y280933D03*
X194500Y360200D03*
X197137Y360350D03*
X191900Y360173D03*
X195200Y377800D03*
Y380300D03*
X177689Y404109D03*
X180799Y404049D03*
X174609Y404009D03*
X206600Y372400D03*
X195233Y348402D03*
X172697Y407196D03*
X197242Y510114D03*
X200238Y515714D03*
X203785Y510114D03*
X190549D03*
X187202Y515814D03*
X193895D03*
X183856Y510114D03*
X173591Y510098D03*
X173567Y517900D03*
X178691Y518114D03*
X206581Y515814D03*
X210402Y510098D03*
X210378Y517900D03*
X215502Y518114D03*
X215478Y510100D03*
X224013Y515814D03*
X220667Y510114D03*
X227360D03*
X230706Y515814D03*
X173591Y515300D03*
X200288Y513114D03*
X197242Y518157D03*
X230706Y513114D03*
X227360Y518157D03*
X206581Y513114D03*
X203935Y518157D03*
X187202Y513114D03*
X183856Y518157D03*
X193895Y513114D03*
X190549Y518157D03*
X215502Y515514D03*
X178691D03*
X210402Y512700D03*
X173591D03*
X215502Y512914D03*
X178691D03*
X210402Y515300D03*
X224013Y513114D03*
X220667Y518161D03*
X193895Y553614D03*
X200238Y553514D03*
X183856Y547914D03*
X190549D03*
X203785D03*
X197242D03*
X190549Y537049D03*
X183856D03*
X187202Y530949D03*
X193895D03*
X197242Y536999D03*
X203935Y537049D03*
X200202Y530949D03*
X206581Y553614D03*
X210402Y547898D03*
X178717Y536750D03*
X173617Y529150D03*
X173591Y536999D03*
X178704Y528936D03*
X178667Y547900D03*
X173591Y547898D03*
X206581Y531100D03*
X210402Y536999D03*
X210428Y529150D03*
X187202Y553614D03*
X173591Y553100D03*
X178691Y555914D03*
X173567Y555700D03*
X210378D03*
X203935Y574849D03*
X200202Y568749D03*
X197242Y574799D03*
X190549Y585714D03*
X183856D03*
X187202Y568749D03*
X193895D03*
X190549Y574849D03*
X183856D03*
X210402Y585698D03*
X206581Y568900D03*
X210428Y566950D03*
X210402Y574799D03*
X178667Y585700D03*
X178717Y574550D03*
X173591Y574799D03*
Y585698D03*
X173617Y566950D03*
X178704Y566736D03*
X197242Y585714D03*
X203785D03*
X173617Y569550D03*
X215515Y528936D03*
X215528Y536750D03*
X215478Y547900D03*
X224013Y530949D03*
X220667Y537049D03*
X230706Y530949D03*
X227360Y537049D03*
X230706Y553614D03*
X220667Y547914D03*
X227360D03*
X224013Y553614D03*
X215502Y555914D03*
X220667Y585714D03*
X215528Y574550D03*
X215478Y585700D03*
X215515Y566736D03*
X224013Y568749D03*
X220667Y574849D03*
X230706Y568749D03*
X227360Y574849D03*
Y585714D03*
X173617Y531750D03*
X224013Y535100D03*
X197242Y528899D03*
X200202Y534700D03*
X227360Y528899D03*
X230706Y535100D03*
X203935Y528899D03*
X206581Y534700D03*
X183856Y528899D03*
X187202Y535100D03*
X190549Y528899D03*
X193895Y535100D03*
X173591Y550500D03*
X215502Y550714D03*
X178691D03*
X210402Y553100D03*
X224013Y550914D03*
X220667Y555961D03*
X200288Y550914D03*
X197242Y555957D03*
X230706Y550914D03*
X227360Y555957D03*
X206581Y550914D03*
X203935Y555957D03*
X187202Y550914D03*
X183856Y555957D03*
X193895Y550914D03*
X190549Y555957D03*
X210402Y534399D03*
X215502Y534149D03*
X178691D03*
X210428Y531750D03*
X220667Y528899D03*
X215502Y553314D03*
X178691D03*
X210402Y550500D03*
X220667Y566699D03*
X224013Y572900D03*
X197242Y566699D03*
X200202Y572500D03*
X227360Y566699D03*
X230706Y572900D03*
X203935Y566699D03*
X206581Y572500D03*
X183856Y566699D03*
X187202Y572900D03*
X190549Y566699D03*
X193895Y572900D03*
X210402Y588300D03*
X173591D03*
X215502Y588514D03*
X178691D03*
X224013Y588714D03*
X200288D03*
X230706D03*
X206581D03*
X187202D03*
X193895D03*
X215502Y569340D03*
X178691D03*
X210402Y572199D03*
X173591D03*
X210428Y569550D03*
X215502Y531540D03*
X178691D03*
X173591Y534399D03*
X215502Y571949D03*
X178691D03*
X227360Y612649D03*
X220667D03*
X203935D03*
X197242Y612599D03*
X190549Y612649D03*
X183856D03*
X210402Y612599D03*
X173591D03*
X187202Y591414D03*
X193895D03*
X187202Y606549D03*
X193895D03*
X200202D03*
X210428Y604750D03*
X206581Y606700D03*
X210378Y593500D03*
X206581Y591414D03*
X178717Y612350D03*
X173617Y604750D03*
X178704Y604536D03*
X173567Y593500D03*
X178691Y593714D03*
X200238Y591314D03*
X224013Y606549D03*
X230706D03*
Y591414D03*
X215515Y604536D03*
X215528Y612350D03*
X215502Y593714D03*
X224013Y591414D03*
X173617Y607350D03*
X173591Y590900D03*
X215502Y607140D03*
Y591114D03*
X178691D03*
X173591Y609999D03*
X215502Y609749D03*
X178691D03*
X210402Y590900D03*
X210428Y607350D03*
X220667Y604499D03*
X224013Y610700D03*
X220667Y593761D03*
X197242Y604499D03*
Y593757D03*
X200202Y610300D03*
X227360Y604499D03*
X230706Y610700D03*
X227360Y593757D03*
X203935Y604499D03*
X206581Y610300D03*
X203935Y593757D03*
X183856Y604499D03*
Y593757D03*
X187202Y610700D03*
X190549Y604499D03*
Y593757D03*
X193895Y610700D03*
X178691Y607140D03*
X210402Y609999D03*
X243392Y-4100D03*
X240746Y-9901D03*
X267517Y-3700D03*
X264171Y-9901D03*
X237013Y-4100D03*
X234053Y-9901D03*
X260824Y-3700D03*
X257478Y-9901D03*
X252313Y-7260D03*
X247213Y-4401D03*
X252313Y-4651D03*
X270864Y-9901D03*
Y-1801D03*
X247213D03*
X240746Y-1751D03*
X264171D03*
X252339Y-2050D03*
X234053Y-1801D03*
X257478Y-1751D03*
X243392Y-7700D03*
X260824Y-7851D03*
X252326Y-9864D03*
X237013Y-7851D03*
X247239Y-9650D03*
X267517Y-7851D03*
X252289Y9100D03*
X264171Y9114D03*
X240596D03*
X247213Y9098D03*
X270864Y9114D03*
X234053D03*
X257478D03*
X267517Y14814D03*
Y29949D03*
X247189Y16900D03*
X252326Y27936D03*
X243392Y30100D03*
X247239Y28150D03*
X260824Y29949D03*
X237013D03*
X243392Y33700D03*
X240746Y27899D03*
X264171D03*
X237013Y33700D03*
X234053Y27899D03*
X257478D03*
X247239Y30750D03*
X252313Y33149D03*
X247213Y33399D03*
X252313Y30540D03*
X270864Y27899D03*
X240746Y17157D03*
X243392Y12114D03*
X264171Y17157D03*
X267517Y12114D03*
X234053Y17157D03*
X237099Y12114D03*
X257478Y17157D03*
X260824Y12114D03*
X247213Y14300D03*
X252313Y14514D03*
X247213Y11700D03*
X252313Y11914D03*
X270864Y17157D03*
X252313Y17114D03*
X243392Y14814D03*
X260824D03*
X237049Y14714D03*
X284050Y-9650D03*
X289137Y-9864D03*
X284050Y-7050D03*
X289124Y-7260D03*
Y-4651D03*
X280203Y-4100D03*
X277557Y-9901D03*
X273824Y-4100D03*
Y-7851D03*
X280203Y-7700D03*
X289100Y9100D03*
X284024Y9098D03*
X277407Y9114D03*
X277557Y-1751D03*
X289150Y-2050D03*
X284024Y-1801D03*
X273824Y29949D03*
X273860Y14714D03*
X284000Y16900D03*
X280203Y14814D03*
Y30100D03*
X289124Y17114D03*
X284050Y28150D03*
X289137Y27936D03*
X289124Y33149D03*
X284024Y33399D03*
X280203Y33700D03*
X277557Y27899D03*
X273824Y33700D03*
X284024Y14300D03*
X289124Y14514D03*
X284024Y11700D03*
X289124Y11914D03*
X277557Y17157D03*
X280203Y12114D03*
X273910D03*
X247239Y-7050D03*
X284024Y-4401D03*
X284050Y30750D03*
X289124Y30540D03*
X247213Y46898D03*
X257478Y46914D03*
X240596D03*
X243392Y67900D03*
X267517Y67749D03*
Y52614D03*
X270864Y46914D03*
X252326Y65736D03*
X237013Y67749D03*
X260824D03*
X247239Y65950D03*
X243392Y52614D03*
X264171Y46914D03*
X247213Y35999D03*
X257478Y36049D03*
X252339Y35750D03*
X234053Y35999D03*
X240746Y36049D03*
X264171D03*
X237049Y52514D03*
X252289Y46900D03*
X240746Y65699D03*
X264171D03*
X234053D03*
X257478D03*
X247239Y68550D03*
X270864Y65699D03*
X240746Y54957D03*
X243392Y49914D03*
X264171Y54957D03*
X267517Y34100D03*
Y49914D03*
X234053Y54957D03*
X237099Y49914D03*
X257478Y54957D03*
X260824Y34100D03*
Y49914D03*
X247213Y52100D03*
X252313Y49714D03*
X247213Y49500D03*
X252313Y52314D03*
X270864Y54957D03*
X247189Y54700D03*
X252313Y54914D03*
X260824Y52614D03*
X270864Y35999D03*
X234053Y46914D03*
X247213Y73799D03*
X243392Y71500D03*
X240746Y92757D03*
X243392Y87714D03*
X267517Y71900D03*
X264171Y92757D03*
X267517Y87714D03*
X237013Y71500D03*
X234053Y92757D03*
X237099Y87714D03*
X260824Y71900D03*
X257478Y92757D03*
X260824Y87714D03*
X247213Y89900D03*
X252313Y70949D03*
Y87514D03*
X247213Y71199D03*
Y87300D03*
X252313Y90114D03*
X270864Y92757D03*
X247213Y84698D03*
X264171Y84714D03*
X252339Y73550D03*
X257478Y84714D03*
X240746Y73849D03*
X257478D03*
X234053Y73799D03*
X264171Y73849D03*
X243392Y90414D03*
X252313Y92714D03*
X237049Y90314D03*
X270864Y84714D03*
X247189Y92500D03*
X240596Y84714D03*
X234053D03*
X252289Y84700D03*
X260824Y90414D03*
X267517D03*
X270864Y73799D03*
X273824Y67749D03*
X280203Y67900D03*
X284024Y35999D03*
X277557Y36049D03*
X277407Y46914D03*
X289137Y65736D03*
X284050Y65950D03*
X284024Y46898D03*
X284000Y54700D03*
X289100Y46900D03*
X289150Y35750D03*
X289124Y54914D03*
X280203Y52614D03*
X284050Y68550D03*
X289124Y68340D03*
X277557Y65699D03*
X284024Y52100D03*
X289124Y49714D03*
X284024Y49500D03*
X289124Y52314D03*
X277557Y54957D03*
X280203Y49914D03*
X273910D03*
X284024Y89900D03*
X289124Y70949D03*
Y87514D03*
X284024Y71199D03*
Y87300D03*
X289124Y90114D03*
X280203Y71500D03*
X277557Y92757D03*
X280203Y87714D03*
X273824Y71500D03*
X273910Y87714D03*
X273860Y90314D03*
X277407Y84714D03*
X289100Y84700D03*
X284024Y84698D03*
X284000Y92500D03*
X289150Y73550D03*
X284024Y73799D03*
X289124Y92714D03*
X280203Y90414D03*
X277407Y73849D03*
X252313Y68340D03*
X240746Y112327D03*
X243392Y106934D03*
X264171Y112327D03*
X267517Y107284D03*
X234053Y112327D03*
X237099Y107284D03*
X257478Y112327D03*
X260824Y107284D03*
X247213Y110514D03*
X252313Y107655D03*
X247239Y107865D03*
X252339Y110264D03*
X270864Y112327D03*
X264171Y104284D03*
X267517Y109984D03*
X270864Y104284D03*
X257478D03*
X260824Y109984D03*
X243392Y109534D03*
X252339Y112865D03*
X247213Y113114D03*
X237049Y109884D03*
X240596Y104284D03*
X247239Y105265D03*
X252326Y105051D03*
X234053Y104284D03*
X284024Y110514D03*
X289124Y107655D03*
X284050Y107865D03*
X289150Y110264D03*
X277557Y112327D03*
X280203Y106934D03*
X273910Y107284D03*
X273860Y109884D03*
X284050Y105265D03*
X289137Y105051D03*
X289150Y112865D03*
X284024Y113114D03*
X280203Y109534D03*
X277407Y104284D03*
X267859Y209109D03*
X271239Y203260D03*
X277999Y218860D03*
X281379Y209109D03*
X288139Y201309D03*
Y209109D03*
X277999Y199360D03*
X274619Y201309D03*
Y209109D03*
Y205210D03*
X271239Y207159D03*
Y211060D03*
X284759Y207159D03*
X291519D03*
X274619Y213009D03*
Y216909D03*
X277999Y211060D03*
Y214960D03*
Y203260D03*
Y207159D03*
X281379Y213009D03*
X288139Y216909D03*
X284759Y214960D03*
X281379Y216909D03*
X284759Y218860D03*
Y203260D03*
Y211060D03*
X281379Y205210D03*
X291519Y203260D03*
Y211060D03*
X288139Y213009D03*
Y205210D03*
X291519Y214960D03*
Y218860D03*
X281379Y201309D03*
X284759Y199360D03*
X291519D03*
X264092Y242260D03*
X271239D03*
X267859Y248109D03*
X264179Y261760D03*
X271239D03*
Y253960D03*
X288139Y228610D03*
X277999Y226660D03*
X288139Y220809D03*
X281379Y236409D03*
X284759Y250060D03*
X288139Y240309D03*
X281379Y244209D03*
X277999Y257860D03*
X288139Y267609D03*
Y259809D03*
X277999Y265660D03*
X274619Y271509D03*
X291519Y273460D03*
X277999D03*
X267859Y244209D03*
Y240309D03*
X271239Y238360D03*
X264179D03*
Y250060D03*
X264092Y222710D03*
X264179Y226660D03*
Y246160D03*
X271239D03*
Y250060D03*
Y269560D03*
Y273460D03*
Y265660D03*
X267859Y263709D03*
Y259809D03*
X264179Y265660D03*
X267859Y252009D03*
X264179Y253960D03*
Y257860D03*
X271239D03*
X267859Y255909D03*
X271239Y277360D03*
X267392Y276000D03*
X267359Y279310D03*
X267859Y271509D03*
X264179Y273460D03*
X291519Y238360D03*
X284759Y234460D03*
X288139Y232509D03*
X281379D03*
X277999Y234460D03*
X274619Y232509D03*
Y220809D03*
Y224709D03*
Y228610D03*
X277999Y230559D03*
X274619Y244209D03*
X277999Y250060D03*
X274619Y240309D03*
Y248109D03*
Y236409D03*
X291519Y246160D03*
Y250060D03*
X284759Y246160D03*
X291519Y242260D03*
X281379Y220809D03*
X284759Y226660D03*
Y230559D03*
X277999Y222760D03*
X281379Y224709D03*
X284759Y222760D03*
X277999Y238360D03*
X288139Y248109D03*
X277999Y242260D03*
X284759Y238360D03*
X281379Y248109D03*
X288139Y244209D03*
X277999Y246160D03*
X284759Y242260D03*
X288139Y236409D03*
X291519Y234460D03*
Y222760D03*
Y230559D03*
Y226660D03*
X281379Y240309D03*
Y228610D03*
X288139Y224709D03*
X281379Y252009D03*
X274619D03*
X277999Y253960D03*
X284759D03*
X291519D03*
X284759Y265660D03*
X291519D03*
Y277360D03*
X281379Y275409D03*
Y271509D03*
X284759Y277360D03*
Y273460D03*
X288139Y275409D03*
Y271509D03*
X277999Y277360D03*
X274619Y255909D03*
Y259809D03*
X277999Y269560D03*
X274619Y275409D03*
Y267609D03*
Y263709D03*
X288139Y255909D03*
X291519Y269560D03*
Y257860D03*
Y261760D03*
X281379Y259809D03*
Y267609D03*
Y255909D03*
X284759Y269560D03*
X277999Y261760D03*
X284759Y257860D03*
Y261760D03*
X281379Y263709D03*
X288139Y279310D03*
X274619D03*
X288139Y252009D03*
X281379Y279310D03*
X288139Y263709D03*
X239778Y274478D03*
X288139Y322209D03*
X281379D03*
X284759Y335860D03*
X277999D03*
X288139Y330009D03*
X281379Y341709D03*
Y330009D03*
X271239Y339760D03*
X291519Y320260D03*
X284759D03*
X291519Y324160D03*
X277999D03*
X264179Y331960D03*
X271239D03*
Y328060D03*
X267859Y333909D03*
Y341709D03*
Y330009D03*
X264179Y328060D03*
Y339760D03*
X271239Y320260D03*
Y324160D03*
X270939Y316160D03*
X267359Y318309D03*
X267859Y326110D03*
X267392Y322000D03*
X270892Y304660D03*
Y311960D03*
Y300760D03*
Y308560D03*
Y292959D03*
Y289060D03*
X271239Y281260D03*
X270892Y285500D03*
Y296860D03*
X267359Y283209D03*
X291519Y285160D03*
Y292959D03*
X284759Y285160D03*
X277999Y308560D03*
Y300760D03*
Y292959D03*
Y285160D03*
X291519Y308560D03*
X284759D03*
Y300760D03*
X291519D03*
X284759Y292959D03*
X281379Y302709D03*
X288139D03*
X291519Y304660D03*
X281379Y306609D03*
Y310509D03*
X288139Y306609D03*
Y310509D03*
X284759Y304660D03*
X281379Y287109D03*
X288139Y291009D03*
X284759Y289060D03*
Y281260D03*
X291519Y289060D03*
Y281260D03*
Y296860D03*
X288139Y298809D03*
X274619Y306609D03*
Y310509D03*
X277999Y304660D03*
X274619Y302709D03*
Y298809D03*
Y294909D03*
X277999Y289060D03*
Y281260D03*
X274619Y283209D03*
Y287109D03*
Y291009D03*
X277999Y296860D03*
X288139Y283209D03*
Y287109D03*
X281379Y298809D03*
Y294909D03*
X288139D03*
X284759Y296860D03*
X281379Y291009D03*
Y283209D03*
X291519Y316360D03*
X281379Y318309D03*
X291519Y328060D03*
X288139Y341709D03*
X274619Y330009D03*
Y326110D03*
Y322209D03*
X277999Y328060D03*
X274619Y341709D03*
X277999Y320260D03*
Y316360D03*
X274619Y333909D03*
Y337809D03*
X284759Y324160D03*
X288139Y318309D03*
X284759Y316360D03*
X281379Y337809D03*
X291519Y339760D03*
Y335860D03*
X284759Y331960D03*
X291519D03*
X281379Y326110D03*
X288139D03*
X291519Y312460D03*
X284759D03*
X277999D03*
X274619Y314409D03*
X281379D03*
X288139D03*
X274619Y318309D03*
X264179Y335860D03*
X288139Y337809D03*
X281379Y333909D03*
X277999Y331960D03*
X284759Y339760D03*
Y328060D03*
X277999Y339760D03*
X288139Y333909D03*
X267859Y337809D03*
X271239Y335860D03*
Y394359D03*
X267859Y392410D03*
X271239Y398260D03*
X284759Y355360D03*
X274619Y400209D03*
X281379D03*
X277999Y398260D03*
X274619Y396309D03*
X288139Y388509D03*
X291519Y394359D03*
X281379Y388509D03*
X284759Y394359D03*
X277999Y355360D03*
X284759Y347560D03*
X281379Y361209D03*
X284759Y374860D03*
X271239Y347560D03*
X264179D03*
X277999Y374860D03*
X288139Y369010D03*
X281379Y380709D03*
Y369010D03*
X267859Y345609D03*
X267559Y369010D03*
X271239Y355360D03*
X267859Y349509D03*
Y353409D03*
X267559Y361209D03*
X264179Y343660D03*
Y355360D03*
X267492Y380709D03*
X271239Y390460D03*
X267859Y388509D03*
X271239Y382660D03*
X284759Y351460D03*
X281379Y345609D03*
X291519Y359260D03*
Y355360D03*
Y351460D03*
X284759Y343660D03*
X274619Y365109D03*
X277999Y363160D03*
Y367060D03*
X274619Y369010D03*
Y361209D03*
Y345609D03*
X277999Y347560D03*
X274619Y353409D03*
Y357309D03*
Y349509D03*
X277999Y343660D03*
X291519Y347560D03*
Y343660D03*
X288139Y365109D03*
X281379D03*
X284759Y363160D03*
X291519D03*
X284759Y370959D03*
X291519Y367060D03*
Y370959D03*
X288139Y361209D03*
X281379Y357309D03*
X288139Y345609D03*
Y380709D03*
Y400209D03*
X274619Y380709D03*
X277999Y394359D03*
X274619Y392410D03*
X277999Y390460D03*
Y386560D03*
X274619Y376809D03*
Y372909D03*
X291519Y374860D03*
X277999Y382660D03*
X284759Y398260D03*
X281379Y396309D03*
X291519Y398260D03*
X284759Y390460D03*
X291519D03*
X281379Y376809D03*
Y384609D03*
X284759Y382660D03*
X291519D03*
Y378760D03*
X288139Y392410D03*
X281379Y353409D03*
X288139Y384609D03*
Y357309D03*
Y396309D03*
X277999Y351460D03*
X281379Y349509D03*
X288139Y353409D03*
X291519Y386560D03*
X281379Y392410D03*
X284759Y386560D03*
X277999Y359260D03*
X288139Y349509D03*
X284759Y359260D03*
X281379Y372909D03*
X288139Y376809D03*
X277999Y370959D03*
X271239Y343660D03*
Y351460D03*
X264179D03*
X284759Y378760D03*
Y367060D03*
X277999Y378760D03*
X288139Y372909D03*
X264171Y510114D03*
X257478D03*
X260824Y515814D03*
X247213Y515300D03*
X260824Y491044D03*
X247177Y490514D03*
X252313D03*
X236892Y493400D03*
X243392Y493094D03*
X267584Y491219D03*
X271092Y495944D03*
X257392Y495800D03*
X264192D03*
X233292Y495900D03*
X239492Y498500D03*
X247177Y498514D03*
X252313D03*
X252289Y510100D03*
X267517Y515814D03*
X270864Y510114D03*
X247189Y517900D03*
X252313Y518114D03*
X247213Y510098D03*
X240596Y510114D03*
X243392Y515814D03*
X234053Y510114D03*
X237049Y515714D03*
X284024Y490644D03*
X289124D03*
X273860Y515714D03*
X277557Y495944D03*
X277407Y510114D03*
X289100Y510100D03*
X289124Y518114D03*
X284024Y510098D03*
X280203Y515814D03*
X273992Y491144D03*
X280203Y490644D03*
X284024Y498644D03*
X289124D03*
X284000Y517900D03*
X247228Y495909D03*
X289124Y493344D03*
X252313Y493214D03*
X284039Y495944D03*
X260824Y493744D03*
X257478Y498487D03*
X236892Y490800D03*
X233292Y498500D03*
X267584Y493919D03*
X264171Y498487D03*
X243392Y495694D03*
X239592Y495900D03*
X273910Y513114D03*
X270864Y518157D03*
X280203Y513114D03*
X277557Y518157D03*
X289124Y515514D03*
X252313D03*
X284024Y512700D03*
X247213D03*
X289124Y512914D03*
X252313D03*
X284024Y515300D03*
X260824Y513114D03*
X257478Y518157D03*
X237099Y513114D03*
X234053Y518157D03*
X267517Y513114D03*
X264171Y518157D03*
X243392Y513114D03*
X240746Y518157D03*
X273992Y493744D03*
X271092Y498644D03*
X280203Y493244D03*
X277557Y498644D03*
X289124Y495944D03*
X252313Y495814D03*
X284039Y493344D03*
X247228Y493209D03*
X257478Y537049D03*
X237013Y530949D03*
X252339Y536750D03*
X243392Y531100D03*
X247213Y536999D03*
X252326Y528936D03*
X240746Y537049D03*
X234053Y536999D03*
X267517Y553614D03*
X270864Y547914D03*
X267517Y530949D03*
X270864Y536999D03*
X260824Y553614D03*
X237049Y553514D03*
X243392Y553614D03*
X264171Y547914D03*
X257478D03*
X252289Y547900D03*
X240596Y547914D03*
X247213Y547898D03*
X234053Y547914D03*
X264171Y537049D03*
X260824Y530949D03*
X247189Y555700D03*
X252313Y555914D03*
X270864Y574799D03*
Y585714D03*
X267517Y568749D03*
X247239Y566950D03*
X252326Y566736D03*
X234053Y574799D03*
X240746Y574849D03*
X247213Y574799D03*
X234053Y585714D03*
X237013Y568749D03*
X264171Y585714D03*
X257478D03*
X264171Y574849D03*
X257478D03*
X260824Y568749D03*
X252339Y574550D03*
X252289Y585700D03*
X240596Y585714D03*
X247213Y585698D03*
X243392Y568900D03*
X277407Y537049D03*
X273824Y530949D03*
X273860Y553514D03*
X284024Y547898D03*
X289100Y547900D03*
X280203Y553614D03*
Y531100D03*
X284024Y536999D03*
X289137Y528936D03*
X284050Y529150D03*
X289150Y536750D03*
X277407Y547914D03*
X273824Y568749D03*
X284000Y555700D03*
X289124Y555914D03*
X280203Y568900D03*
X277407Y574849D03*
Y585714D03*
X289100Y585700D03*
X289150Y574550D03*
X284024Y574799D03*
Y585698D03*
X284050Y566950D03*
X289137Y566736D03*
X284024Y588300D03*
X247213Y553100D03*
X247239Y569550D03*
X289124Y550714D03*
X252313D03*
X284024Y553100D03*
X260824Y550914D03*
X257478Y555957D03*
X237099Y550914D03*
X234053Y555957D03*
X267517Y550914D03*
X264171Y555957D03*
X243392Y550914D03*
X240746Y555957D03*
X270864Y528899D03*
X273824Y534700D03*
X277557Y528899D03*
X280203Y534700D03*
X289124Y531540D03*
X252313D03*
X247213Y534399D03*
X289124Y534149D03*
X252313D03*
X284050Y531750D03*
X257478Y528899D03*
X260824Y535100D03*
X234053Y528899D03*
X237013Y534700D03*
X264171Y528899D03*
X267517Y535100D03*
X240746Y528899D03*
X243392Y534700D03*
X273910Y550914D03*
X270864Y555957D03*
X280203Y550914D03*
X277557Y555957D03*
X289124Y553314D03*
X252313D03*
X284024Y550500D03*
X247213D03*
X264171Y566699D03*
X267517Y572900D03*
X240746Y566699D03*
X243392Y572500D03*
X280203Y588714D03*
X247213Y588300D03*
X289124Y588514D03*
X252313D03*
X260824Y588714D03*
X237099D03*
X267517D03*
X243392D03*
X270864Y566699D03*
X273824Y572500D03*
X277557Y566699D03*
X280203Y572500D03*
X289124Y569340D03*
X284024Y572199D03*
X252313Y571949D03*
X257478Y566699D03*
X260824Y572900D03*
X234053Y566699D03*
X237013Y572500D03*
X273910Y588714D03*
X247239Y531750D03*
X284024Y534399D03*
X252313Y569340D03*
X247213Y572199D03*
X289124Y571949D03*
X284050Y569550D03*
X284024Y612599D03*
X240746Y612649D03*
X247213Y612599D03*
X234053D03*
X257478Y612649D03*
X247239Y604750D03*
X252326Y604536D03*
X260824Y606549D03*
X237013D03*
X243392Y606700D03*
X264171Y612449D03*
X252339Y612350D03*
X267517Y591414D03*
X260824D03*
X237049Y591314D03*
X247189Y593500D03*
X252313Y593714D03*
X243392Y591414D03*
X267517Y606549D03*
X270864Y612399D03*
X273824Y606549D03*
X273860Y591314D03*
X284050Y604750D03*
X289150Y612350D03*
X280203Y606700D03*
Y591414D03*
X277407Y612449D03*
X289124Y593714D03*
X284000Y593500D03*
X289137Y604536D03*
X247213Y590900D03*
X247239Y607350D03*
X277557Y604499D03*
X280203Y610300D03*
X277557Y593757D03*
X289124Y607140D03*
Y591114D03*
X252313Y607140D03*
Y591114D03*
X289124Y609749D03*
X252313D03*
X284050Y607350D03*
X284024Y590900D03*
X257478Y604499D03*
Y593757D03*
X260824Y610700D03*
X234053Y604499D03*
Y593757D03*
X237013Y610300D03*
X264171Y604499D03*
X267517Y610700D03*
X264171Y593757D03*
X240746Y604499D03*
Y593757D03*
X243392Y610300D03*
X270864Y604499D03*
X273824Y610300D03*
X270864Y593757D03*
X284024Y609999D03*
X247213D03*
X297635Y-7851D03*
X304328D03*
X300982Y-1751D03*
X294289D03*
X308157Y-7180D03*
X324407Y-4536D03*
X304328Y-3700D03*
X300982Y-9901D03*
X297635Y-3700D03*
X294289Y-9901D03*
X321061Y-1743D03*
X314368Y-1843D03*
X331100Y-4536D03*
X327754Y-7108D03*
X317714Y-9786D03*
X311021D03*
X314368Y9114D03*
X321061D03*
X331100D03*
X317714Y-4536D03*
X294289Y9114D03*
X300982D03*
X307675Y-1843D03*
X311021Y28014D03*
X307675Y9300D03*
X304328Y29949D03*
X307992Y13200D03*
X297635Y14814D03*
X321192Y13200D03*
X321334Y32100D03*
X308092D03*
X297635Y29949D03*
X304328Y14814D03*
X300982Y27899D03*
X294289D03*
X300982Y17157D03*
X304328Y12114D03*
X294289Y17157D03*
X297635Y12114D03*
X317714Y28014D03*
X311021Y17057D03*
X317714D03*
X327754D03*
Y28014D03*
X334447Y-1743D03*
Y-7108D03*
X347833D03*
X351179Y9122D03*
Y-4536D03*
X341140Y-1743D03*
X337793Y-9901D03*
X341140Y9122D03*
X334292Y13200D03*
Y32100D03*
X347833Y17057D03*
Y28022D03*
X337793Y17057D03*
Y28014D03*
X314368Y-7108D03*
X324407Y-9901D03*
X327754Y-1743D03*
X321061Y-7108D03*
X341140D03*
X337793Y-4536D03*
X344486Y-9786D03*
Y-4536D03*
X351179Y-9901D03*
X354525Y-1742D03*
X354526Y-7108D03*
X331100Y-9786D03*
X311021Y-4536D03*
X347833Y-1743D03*
X311021Y65814D03*
X317714D03*
X321061Y35957D03*
X307950Y50729D03*
X300982Y36049D03*
X294289Y46914D03*
X304328Y52614D03*
X321192Y51000D03*
X307675Y35957D03*
X304328Y67749D03*
X297635D03*
X294289Y36049D03*
X300982Y46914D03*
X297635Y52614D03*
X300982Y65699D03*
X294289D03*
X300982Y54957D03*
X304328Y34100D03*
Y49914D03*
X294289Y54957D03*
X297635Y34100D03*
Y49914D03*
X314368Y35957D03*
Y46914D03*
X311021Y54857D03*
X317714D03*
X321061Y46914D03*
X331100D03*
X327754Y65814D03*
X331100Y35957D03*
X327754Y54857D03*
X304328Y71900D03*
X300982Y92757D03*
X304328Y87714D03*
X297635Y71900D03*
X294289Y92757D03*
X297635Y87714D03*
X331100Y89964D03*
X327754Y92757D03*
X331100Y84714D03*
Y73757D03*
X314368D03*
Y87392D03*
X311021Y89964D03*
X317714D03*
X321061Y87392D03*
Y73757D03*
X317714Y84714D03*
X307992Y70400D03*
X321334Y69900D03*
X304278Y90414D03*
X307592Y73800D03*
X300982Y84714D03*
X294289D03*
X300982Y73849D03*
X294289D03*
X308166Y87394D03*
X297635Y90414D03*
X307675Y92657D03*
X321061Y92757D03*
X327754Y87392D03*
X324407Y89964D03*
Y84599D03*
X314368Y92657D03*
X311021Y84714D03*
X334292Y51000D03*
X341140Y35957D03*
X337793Y65814D03*
Y54857D03*
X351179Y46922D03*
X347833Y54857D03*
X341140Y46922D03*
X347833Y65822D03*
X351179Y35957D03*
X354415Y87392D03*
X351179Y89964D03*
X347833Y87392D03*
X344486Y84714D03*
Y89964D03*
X337793Y84599D03*
X341140Y92757D03*
X334447D03*
X347833D03*
X351179Y84599D03*
Y73757D03*
X337793Y89964D03*
X341140Y87392D03*
Y73757D03*
X334292Y69900D03*
X334447Y87392D03*
X354415Y92757D03*
X300982Y109700D03*
X304178Y107684D03*
X294889Y110927D03*
X297635Y105084D03*
X326592Y105600D03*
X313637Y105725D03*
X300992Y112300D03*
X297642Y107700D03*
X304192Y105000D03*
X324492Y103500D03*
X327092Y103021D03*
X308418Y216909D03*
X294899D03*
X301659D03*
X294899Y205210D03*
Y197409D03*
X352357Y218860D03*
X345598D03*
X338838Y214960D03*
X342218Y216909D03*
X338838Y207158D03*
Y203258D03*
X345598Y211060D03*
X348978Y213009D03*
X342218Y205210D03*
X294899Y213009D03*
X308418Y201309D03*
X317428Y193507D03*
X301648Y194841D03*
X332078Y218860D03*
X329818Y214958D03*
X298279Y214960D03*
X305039D03*
X301659Y213009D03*
X294899Y209109D03*
X298279Y218860D03*
X311798Y211060D03*
Y218860D03*
Y214960D03*
X308418Y213009D03*
X305039Y211060D03*
Y218860D03*
X324200Y201308D03*
X298279Y199360D03*
X294899Y201309D03*
X312918Y205210D03*
X315178Y209109D03*
X298279Y207159D03*
Y203260D03*
Y211060D03*
X318558Y218860D03*
X315178Y216909D03*
Y213009D03*
X301659Y209109D03*
X325318Y211060D03*
X348978Y205210D03*
Y216909D03*
X342218Y213009D03*
X355737Y216909D03*
Y213009D03*
X338838Y218860D03*
X345598Y214960D03*
X352357D03*
X334328Y199108D03*
X348978Y209109D03*
X352357Y211060D03*
X345598Y203260D03*
X355737Y205210D03*
X338838Y211058D03*
X335458Y216909D03*
X355737Y209109D03*
X345598Y207159D03*
X342218Y209109D03*
X298279Y222760D03*
X305039D03*
X328698Y236409D03*
Y244209D03*
X321938Y240309D03*
X294899Y232509D03*
X301659Y244209D03*
Y232509D03*
X318558Y222760D03*
X311798Y234460D03*
X305039Y238360D03*
X294899Y240309D03*
X311798Y226660D03*
X318558Y230559D03*
X332078Y222760D03*
X328698Y224709D03*
Y228610D03*
X332078Y230560D03*
X311798Y242260D03*
X315178Y248109D03*
X308418D03*
X305039Y257860D03*
X328698Y255909D03*
X325318Y261760D03*
X294899Y252009D03*
X301659Y263709D03*
Y252009D03*
X294899Y259809D03*
X332078Y261760D03*
X315178Y271509D03*
X311798Y265660D03*
X321938Y271509D03*
X308418D03*
X318558Y265660D03*
X294899Y271509D03*
Y267609D03*
X332078Y273460D03*
X298279D03*
X328698Y275409D03*
X332078Y277360D03*
X325318D03*
X328698Y279310D03*
X321938D03*
X301659Y271509D03*
X328698D03*
X298279Y269560D03*
X342218Y224709D03*
X345598Y230559D03*
X348978Y224709D03*
X355737D03*
X352357Y230559D03*
X335458Y220809D03*
X345598Y222760D03*
X335458Y228610D03*
X338838Y230560D03*
Y273460D03*
Y269560D03*
X335458Y275409D03*
X338838Y277360D03*
X335458Y279310D03*
Y271509D03*
X348978Y236409D03*
X355737D03*
X342218D03*
X332078Y226660D03*
X315178Y244209D03*
X311798Y246160D03*
X321938Y252009D03*
X345598Y242260D03*
X335458Y232510D03*
X352357Y250060D03*
X345598D03*
X342218Y248109D03*
X335458Y240309D03*
X338838Y261760D03*
X335458Y255909D03*
X355737Y252009D03*
X348978D03*
X352357Y253960D03*
X345598D03*
X355737Y255909D03*
X348978D03*
X345598Y261760D03*
X348978Y259809D03*
X345598Y257860D03*
X352357D03*
X342218Y252009D03*
X338838Y250060D03*
X345598Y234460D03*
X352357Y242260D03*
X294899Y224709D03*
X332078Y242260D03*
Y250060D03*
X328698Y232509D03*
Y220809D03*
X332078Y234460D03*
X298279Y246160D03*
X325318Y250060D03*
X321938Y248109D03*
X305039Y246160D03*
X308418Y244209D03*
X294899D03*
Y248109D03*
X325318Y242260D03*
Y226660D03*
X308418Y220809D03*
X294899D03*
X301659Y224709D03*
X328698Y248109D03*
Y240309D03*
X301659Y220809D03*
X325318Y238360D03*
Y246160D03*
X321938Y244209D03*
X332078Y238360D03*
Y246160D03*
X298279Y230559D03*
X305039Y242260D03*
X294899Y236409D03*
X311798Y230559D03*
X318558Y234460D03*
X321938Y224709D03*
X315178Y236409D03*
Y224709D03*
X298279Y234460D03*
X308418Y228610D03*
Y224709D03*
X305039Y230559D03*
X311798Y222760D03*
X308418Y232509D03*
X294899Y228610D03*
X325318Y234460D03*
Y230559D03*
Y222760D03*
X321938Y228610D03*
X298279Y250060D03*
Y242260D03*
X305039Y234460D03*
X321938Y232509D03*
X298279Y238360D03*
X315178Y228610D03*
X301659Y236409D03*
X318558Y250060D03*
X305039D03*
X318558Y246160D03*
X301659Y248109D03*
X308418Y240309D03*
X315178D03*
X301659D03*
X318558Y242260D03*
X298279Y226660D03*
X318558D03*
X315178Y220809D03*
X321938D03*
X315178Y232509D03*
X301659Y228610D03*
X308418Y236409D03*
X321938D03*
X311798Y238360D03*
X318558D03*
X305039Y226660D03*
X308418Y252009D03*
X298279Y253960D03*
X325318D03*
X308418Y275409D03*
X301659D03*
X308418Y255909D03*
X321938Y275409D03*
X315178Y279310D03*
X318558Y277360D03*
X311798Y261760D03*
X321938Y259809D03*
X301659D03*
X308418Y263709D03*
X325318Y269560D03*
X305039D03*
X318558D03*
X328698Y267609D03*
Y259809D03*
X332078Y269560D03*
X321938Y255909D03*
X308418Y259809D03*
X325318Y273460D03*
Y265660D03*
X301659Y267609D03*
X321938Y263709D03*
X294899Y275409D03*
Y263709D03*
X298279Y265660D03*
X305039Y273460D03*
Y277360D03*
X311798D03*
Y269560D03*
X305039Y265660D03*
X298279Y277360D03*
X328698Y252009D03*
X298279Y261760D03*
X328698Y263709D03*
X325318Y257860D03*
X305039Y261760D03*
X294899Y255909D03*
X305039Y253960D03*
X332078D03*
X315178Y263709D03*
X332078Y265660D03*
X315178Y275409D03*
X301659Y255909D03*
X332078Y257860D03*
X315178Y267609D03*
X298279Y257860D03*
X311798Y273460D03*
X321938Y267609D03*
X308418D03*
X318558Y273460D03*
X301659Y279310D03*
X308418D03*
X294899D03*
X338838Y222760D03*
X352357D03*
X348978Y228610D03*
X352357Y246160D03*
X345598D03*
X342218Y244209D03*
Y232509D03*
X355737Y244209D03*
X348978D03*
X345598Y226660D03*
X352357D03*
X348978Y232509D03*
Y220809D03*
X352357Y238360D03*
X345598D03*
X342218Y220809D03*
X355737Y232509D03*
X338838Y246160D03*
X335458Y248109D03*
X338838Y242260D03*
Y234460D03*
X335458Y236409D03*
X338838Y238360D03*
X335458Y224709D03*
X355737Y248109D03*
X348978D03*
X355737Y220809D03*
X335458Y244209D03*
X338838Y253960D03*
X335458Y252009D03*
X338838Y265660D03*
X335458Y259809D03*
Y267609D03*
X345598Y265660D03*
X348978Y263709D03*
X355737Y259809D03*
X352357Y261760D03*
X345598Y273460D03*
Y269560D03*
X342218Y263709D03*
Y271509D03*
Y259809D03*
Y255909D03*
Y267609D03*
Y279310D03*
Y275409D03*
X338838Y257860D03*
X335458Y263709D03*
X348978Y267609D03*
X345598Y277360D03*
X348978Y279310D03*
Y275409D03*
Y271509D03*
X352357Y265660D03*
X355737Y263709D03*
X342218Y240309D03*
X352357Y234460D03*
X348978Y240309D03*
X355737D03*
Y228610D03*
X342218D03*
X354607Y277360D03*
Y273460D03*
Y269560D03*
X298279Y320260D03*
X294899Y330009D03*
X352357Y339760D03*
X355737Y341709D03*
X298279Y335860D03*
X321938Y326110D03*
X311798Y331960D03*
X325318D03*
X315178Y326110D03*
X318558Y331960D03*
X335458Y341709D03*
X301659D03*
X294899D03*
X305039Y335860D03*
X338838D03*
X328698Y341709D03*
X342218D03*
X332078Y335860D03*
X298279Y324160D03*
X294899Y326109D03*
X321938Y341709D03*
X335458Y322209D03*
X311798Y292959D03*
X305039D03*
X321938Y283209D03*
X315178D03*
X318558Y281260D03*
Y292959D03*
X311798Y285160D03*
X328698Y310509D03*
X332078Y300760D03*
X328698Y283209D03*
X332078Y292959D03*
Y281260D03*
X298279Y308560D03*
X321938Y310509D03*
X315178D03*
X305039Y308560D03*
X311798D03*
X305039Y300760D03*
X325318D03*
X311798D03*
X298279D03*
X318558D03*
X325318Y292959D03*
Y281260D03*
X305039Y285160D03*
X298279D03*
Y292959D03*
X308418Y306609D03*
X301659Y310509D03*
Y306609D03*
X311798Y304660D03*
X305039D03*
X321938Y306609D03*
X325318Y304660D03*
Y308560D03*
X298279Y304660D03*
X294899Y302709D03*
X308418D03*
X301659D03*
X315178D03*
X321938D03*
X294899Y310509D03*
Y306609D03*
X318558Y304660D03*
Y308560D03*
X321938Y291009D03*
X318558Y296860D03*
X315178Y294909D03*
X321938D03*
X301659D03*
X325318Y285160D03*
Y289060D03*
Y296860D03*
X298279D03*
Y289060D03*
Y281260D03*
X308418Y298809D03*
X301659D03*
X308418Y283209D03*
X305039Y281260D03*
Y289060D03*
X308418Y291009D03*
Y287109D03*
X311798Y281260D03*
Y289060D03*
X308418Y294909D03*
X311798Y296860D03*
X305039D03*
X315178Y287109D03*
X318558Y285160D03*
X321938Y287109D03*
X301659Y283209D03*
Y287109D03*
Y291009D03*
X294899Y298809D03*
Y294909D03*
Y291009D03*
Y283209D03*
Y287109D03*
X315178Y298809D03*
X321938D03*
X318558Y289060D03*
X315178Y291009D03*
X332078Y308560D03*
Y304660D03*
X328698Y302709D03*
Y306609D03*
Y287109D03*
Y291009D03*
Y294909D03*
Y298809D03*
X332078Y296860D03*
Y285160D03*
Y289060D03*
X315178Y306609D03*
X308418Y310509D03*
X318558Y312460D03*
X325318D03*
X308418Y333909D03*
Y341709D03*
X325318Y339760D03*
Y335860D03*
X301659Y337809D03*
X315178Y330009D03*
X301659D03*
X308418Y337809D03*
X305039Y331960D03*
X298279Y328060D03*
Y331960D03*
X311798Y324160D03*
X308418Y330009D03*
X315178Y322209D03*
X321938D03*
X294899Y333909D03*
X305039Y328060D03*
X321938Y330009D03*
Y337809D03*
X328698Y330009D03*
Y326110D03*
Y333909D03*
X325318Y324160D03*
X318558Y320260D03*
X301659Y318309D03*
X308418D03*
X305039Y316360D03*
X332078Y331960D03*
Y339760D03*
X298279Y316360D03*
X294899Y322209D03*
Y318309D03*
X311798Y316360D03*
X308418Y326110D03*
X318558Y324160D03*
X311798Y312460D03*
X305039D03*
X298279D03*
X294899Y314409D03*
X308418D03*
X301659D03*
X328698D03*
X321938D03*
X332078Y328060D03*
X328698Y322209D03*
Y318309D03*
X332078Y324160D03*
Y320260D03*
Y316360D03*
X325318Y320260D03*
X305039D03*
X321938Y318309D03*
X315178D03*
X318558Y316360D03*
X301659Y322209D03*
X315178Y314409D03*
X332078Y312460D03*
X325318Y316360D03*
X305039Y324160D03*
X311798Y320260D03*
X308418Y322209D03*
X301659Y326110D03*
X335458Y310509D03*
X338838Y300760D03*
Y292959D03*
Y281260D03*
X335458Y283209D03*
X342218Y310509D03*
Y283209D03*
X335458Y298809D03*
X348978Y287109D03*
X345598Y285160D03*
Y281260D03*
X348978Y283209D03*
Y298809D03*
Y291009D03*
X345598Y289060D03*
Y292959D03*
Y296860D03*
X348978Y294909D03*
X345598Y300760D03*
X348978Y302709D03*
Y306609D03*
X345598Y304660D03*
Y308560D03*
X348978Y310509D03*
X342218Y302709D03*
Y306609D03*
Y291009D03*
Y287109D03*
Y294909D03*
Y298809D03*
X338838Y308560D03*
X335458Y302709D03*
X338838Y304660D03*
X335458Y306609D03*
Y287109D03*
X338838Y289060D03*
Y285160D03*
X335458Y291009D03*
X338838Y296860D03*
X335458Y294909D03*
X345598Y335860D03*
Y331960D03*
X348978Y314409D03*
X345598Y312460D03*
X348978Y322209D03*
X355737Y333909D03*
X345598Y316360D03*
X348978Y318309D03*
Y330009D03*
X352357Y331960D03*
X348978Y326110D03*
X335458Y314409D03*
Y326110D03*
Y318309D03*
X338838Y320260D03*
Y324160D03*
Y328060D03*
X342218Y314409D03*
X338838Y312460D03*
Y316360D03*
X335458Y330009D03*
X338838Y331960D03*
Y339760D03*
X345598Y328060D03*
Y339760D03*
X352357Y335860D03*
X348978Y333909D03*
X342218Y322209D03*
Y318309D03*
Y330009D03*
Y326110D03*
Y333909D03*
X355737Y337809D03*
X345598Y320260D03*
Y324160D03*
X335458Y337809D03*
X348978Y341709D03*
Y337809D03*
X305039Y339760D03*
X321938Y333909D03*
X311798Y328060D03*
X325318D03*
X315178Y333909D03*
X335458D03*
X298279Y339760D03*
X318558Y335860D03*
Y328060D03*
X294899Y337809D03*
X301659Y333909D03*
X328698Y337809D03*
X342218D03*
X354607Y328060D03*
Y324160D03*
Y320260D03*
Y316360D03*
Y312460D03*
Y308560D03*
Y304660D03*
Y300760D03*
Y296860D03*
Y292959D03*
Y289060D03*
Y285160D03*
Y281260D03*
X332078Y370959D03*
X328698Y369010D03*
X294899Y400209D03*
X315178Y384609D03*
Y380709D03*
X332078Y374860D03*
X328698Y372909D03*
X355737Y345609D03*
X335458Y369010D03*
X338838Y363160D03*
X352357Y343660D03*
X348978Y384609D03*
X335458Y376809D03*
X345598Y374860D03*
X301659Y361209D03*
X332078Y351460D03*
X321938Y357309D03*
X335458D03*
X325318Y351460D03*
X301659Y380709D03*
X328698Y361209D03*
X305039Y374860D03*
X294899Y380709D03*
X308418D03*
X298279Y374860D03*
X345598Y386560D03*
X341892Y396301D03*
X311798Y363160D03*
X318558Y374860D03*
Y363160D03*
X294899Y361209D03*
X305039Y355360D03*
X298279Y367060D03*
X342218Y369010D03*
Y357309D03*
X345598Y363160D03*
Y351460D03*
X348978Y357309D03*
Y369010D03*
X355737Y380709D03*
X352357Y374860D03*
X294899Y388509D03*
X338838Y374860D03*
X348978Y380709D03*
X351192Y402800D03*
X342218Y380709D03*
X355737Y357309D03*
Y369010D03*
X352357Y363160D03*
Y351460D03*
X315178Y369010D03*
X298279Y355360D03*
Y347560D03*
X321938Y369010D03*
X308418Y349509D03*
X332078Y367060D03*
X321938Y345609D03*
X342218Y349509D03*
X345598Y347560D03*
X335458Y365109D03*
X352357Y347560D03*
X308418Y357309D03*
X311798Y359260D03*
X298279Y351460D03*
X294899Y349509D03*
Y353409D03*
X321938Y349509D03*
X318558Y359260D03*
X321938Y361209D03*
X298279Y343660D03*
X315178Y357309D03*
X301659D03*
Y349509D03*
X308418Y361209D03*
Y353409D03*
Y345609D03*
X305039Y347560D03*
X325318Y343660D03*
Y347560D03*
X328698Y365109D03*
X332078Y363160D03*
X328698Y345609D03*
X325318Y355360D03*
X332078Y347560D03*
Y355360D03*
X294899Y369010D03*
X325318Y367060D03*
Y370959D03*
X318558D03*
X308418Y365109D03*
X315178D03*
X325318Y363160D03*
X298279D03*
X305039Y370959D03*
X308418Y369010D03*
X305039Y367060D03*
X301659Y369010D03*
X298279Y370959D03*
X318558Y351460D03*
Y355360D03*
X315178Y349509D03*
Y353409D03*
X311798Y355360D03*
Y347560D03*
Y351460D03*
X305039D03*
X301659Y388509D03*
X308418D03*
X318558Y394359D03*
X324458Y399911D03*
X332078Y378760D03*
X318558Y386560D03*
X325318D03*
X301659Y376809D03*
X311798Y374860D03*
X325318D03*
X294899Y372909D03*
X308418D03*
X321938Y376809D03*
X318558Y382660D03*
Y378760D03*
X298279D03*
X305039D03*
X308418Y384609D03*
X311798Y382660D03*
Y378760D03*
X315178Y376809D03*
X328698D03*
X294899Y384609D03*
X318558Y390460D03*
X320808Y401941D03*
X298279Y386560D03*
Y390460D03*
X315178Y392410D03*
Y388509D03*
X311798Y386560D03*
X298279Y398260D03*
Y394359D03*
X294899Y396309D03*
X325318Y378760D03*
X321938Y380709D03*
X305039Y394359D03*
X302608Y402421D03*
X352357Y359260D03*
X345598Y370959D03*
X355737Y353409D03*
X348978D03*
X342218Y365109D03*
X338838Y347560D03*
X335458Y361209D03*
X338838Y359260D03*
Y355360D03*
Y351460D03*
X335458Y349509D03*
X345598Y359260D03*
X348978Y349509D03*
X345598Y343660D03*
X342218Y345609D03*
X355737Y349509D03*
X342218Y353409D03*
X338838Y367060D03*
X348978Y365109D03*
X355737D03*
X352357Y370959D03*
X355737Y376809D03*
Y388509D03*
X348978Y376809D03*
X342218Y388509D03*
Y376809D03*
Y384609D03*
X338838Y382660D03*
X345598D03*
X352357D03*
X348978Y392410D03*
X355737D03*
X335458Y372909D03*
Y384609D03*
Y380709D03*
X345598Y390460D03*
X352357Y386560D03*
X348978Y361209D03*
X355737D03*
X332078Y359260D03*
X321938Y353409D03*
X335458D03*
X325318Y359260D03*
X328698Y357309D03*
Y349509D03*
X301659Y372909D03*
Y384609D03*
X328698Y353409D03*
X305039Y382660D03*
X294899Y376809D03*
X308418D03*
X298279Y382660D03*
X315178Y361209D03*
X321938Y372909D03*
X311798Y367060D03*
X294899Y365109D03*
X301659Y353409D03*
Y365109D03*
X342218Y361209D03*
X345598Y355360D03*
X355737Y384609D03*
X352357Y367060D03*
X355737Y372909D03*
X352357Y378760D03*
X294899Y392410D03*
X338838Y378760D03*
Y370959D03*
X342218Y372909D03*
X348978D03*
X345598Y367060D03*
Y378760D03*
X348978Y388509D03*
X352357Y355360D03*
X305039Y343660D03*
X298279Y359260D03*
X321938Y365109D03*
X305039Y363160D03*
X335458Y345609D03*
X311798Y370959D03*
X294899Y357309D03*
X318558Y367060D03*
X305039Y359260D03*
X301659Y345609D03*
X294899D03*
X338838Y343660D03*
X332078D03*
X315178Y372909D03*
X348978Y345609D03*
X294289Y490444D03*
X301092Y490700D03*
X307675Y518057D03*
X326797Y499767D03*
X317714Y515364D03*
X321061Y512792D03*
X311701Y499136D03*
X331100Y510114D03*
X327754Y518157D03*
X314368Y512792D03*
X311021Y515364D03*
X317714Y510114D03*
X297835Y497644D03*
X308166Y512794D03*
X300982Y510114D03*
X304278Y515814D03*
X297635D03*
X294289Y510114D03*
X304392Y497300D03*
X324187Y499793D03*
X337793Y515364D03*
X350882Y509999D03*
X347833Y518157D03*
X341140Y512792D03*
X327754D03*
X321061Y518157D03*
X297835Y494944D03*
X294392Y493100D03*
X304392Y494700D03*
X301092Y493300D03*
X334447Y518157D03*
X341140D03*
X337793Y509999D03*
X344486Y515364D03*
Y510114D03*
X347833Y512792D03*
X351179Y515364D03*
X354307Y512792D03*
X354526Y518157D03*
X331100Y515364D03*
X334447Y512792D03*
X297635Y513114D03*
X294289Y518157D03*
X304328Y513114D03*
X300982Y518157D03*
X311021Y510114D03*
X314368Y518057D03*
X324407Y509999D03*
Y515364D03*
X326922Y497170D03*
X321061Y536957D03*
X317714Y529014D03*
X331100Y547914D03*
Y536957D03*
X327754Y529014D03*
X321061Y547914D03*
X314368D03*
Y536957D03*
X311021Y529014D03*
X307675Y548200D03*
X304278Y553614D03*
X297635D03*
X300982Y547914D03*
X294289D03*
X307675Y536957D03*
X304328Y530949D03*
X300982Y537049D03*
X297635Y530949D03*
X294289Y537049D03*
X307992Y533100D03*
X321334D03*
X321123Y552000D03*
X308100D03*
X307992Y570900D03*
X321334D03*
X294289Y574849D03*
Y585714D03*
X304328Y568749D03*
X307675Y574757D03*
X300982Y574849D03*
X307848Y588334D03*
X300982Y585714D03*
X297635Y568749D03*
X327754Y555857D03*
X317714D03*
X311021D03*
X327754Y566814D03*
X331100Y574757D03*
Y585714D03*
X314368D03*
Y574757D03*
X317714Y566814D03*
X311021D03*
X321061Y585714D03*
Y574757D03*
X334292Y533100D03*
Y552000D03*
X337793Y529014D03*
X351179Y547922D03*
Y536957D03*
X347833Y529022D03*
X341140Y547922D03*
Y536957D03*
X334292Y570900D03*
X337793Y555857D03*
X347833D03*
X337793Y566814D03*
X341140Y574757D03*
Y585722D03*
X351179Y574757D03*
Y585722D03*
X347833Y566822D03*
X297635Y550914D03*
X294289Y555957D03*
X304328Y550914D03*
X300982Y555957D03*
X294289Y528899D03*
X297635Y535100D03*
X300982Y528899D03*
X304328Y535100D03*
X297635Y588714D03*
X304328D03*
X294289Y566699D03*
X297635Y572900D03*
X300982Y566699D03*
X304328Y572900D03*
X317714Y609864D03*
X304328Y606549D03*
X297635D03*
X294289Y612249D03*
X300982D03*
X307675Y611600D03*
X307892Y591000D03*
X321192Y589800D03*
X304278Y591414D03*
X297635D03*
X308157Y607220D03*
X327754Y607292D03*
X331100Y609864D03*
X327754Y593657D03*
X317714D03*
X311021D03*
X317714Y604614D03*
X311021D03*
X314368Y612457D03*
X321061D03*
X334292Y589800D03*
X337793Y593657D03*
Y604499D03*
X352109Y609918D03*
X347833Y607292D03*
X341140Y612457D03*
X347833Y593657D03*
X324407Y609864D03*
X334447Y607292D03*
X341140D03*
X337793Y609864D03*
X344486Y604614D03*
X347833Y612357D03*
X351179Y604499D03*
X354525Y612358D03*
X354526Y607292D03*
X331100Y604614D03*
X334447Y612457D03*
X294289Y604499D03*
X297635Y610700D03*
X294289Y593757D03*
X300982Y604499D03*
X304328Y610700D03*
X300982Y593757D03*
X311021Y609864D03*
X314368Y607292D03*
X324407Y604499D03*
X327754Y612457D03*
X321061Y607292D03*
X344486Y609864D03*
X375792Y6500D03*
X377592Y-10880D03*
X380232Y-10900D03*
X380200Y-1200D03*
X378792Y6500D03*
X357872Y-9786D03*
X367911D03*
Y-1858D03*
X357872D03*
X367911Y9114D03*
X357672D03*
X371258Y-1858D03*
Y-9800D03*
X376700Y-1300D03*
X374401Y-11346D03*
X373670Y17580D03*
X374773Y19819D03*
X358592Y30736D03*
X380792Y27812D03*
X357492Y14314D03*
X380792Y24933D03*
X357492Y11714D03*
X358619Y33342D03*
X357872Y28014D03*
X367911D03*
Y17042D03*
X357872Y17014D03*
X404722Y-4536D03*
X398029D03*
X401375Y-7108D03*
X408068Y-1743D03*
X411415Y-9786D03*
X398029Y9107D03*
X408069D03*
X411415Y-4536D03*
X394192Y-9700D03*
X409522Y-20794D03*
X401375Y-1743D03*
X411416Y17057D03*
X401376Y17042D03*
X394682Y17157D03*
X408184Y32100D03*
Y13200D03*
X398029Y28007D03*
X408069D03*
X365311Y17042D03*
X404722Y-9901D03*
X394682Y11792D03*
X394683Y-2200D03*
X408068Y-7108D03*
X414761Y-1743D03*
X398029Y-9901D03*
X361218Y9114D03*
X362662Y17014D03*
X361218Y-9786D03*
X364565Y9114D03*
Y-1858D03*
Y-9786D03*
X414761Y-7108D03*
X361218Y-1858D03*
X380600Y37400D03*
X380980Y60210D03*
X380892Y63200D03*
X357762Y49659D03*
X357772Y68335D03*
X371042Y46900D03*
X380792Y56500D03*
X357762Y52333D03*
X364565Y54842D03*
X361218D03*
Y35942D03*
X367911Y46914D03*
Y54842D03*
Y35942D03*
X358619Y36031D03*
X358618Y54842D03*
X357872Y65736D03*
X366992Y65950D03*
X357872Y46914D03*
X357965Y92500D03*
X367911Y87500D03*
X368311Y92500D03*
X367742Y73450D03*
X357872Y87500D03*
X358491Y73479D03*
X384992Y81600D03*
X375337Y86377D03*
Y83877D03*
X357772Y70935D03*
X374292Y77200D03*
Y74100D03*
X365607Y92500D03*
X365234Y87500D03*
X362792Y92500D03*
X362435Y87500D03*
X408069Y35942D03*
X401376Y54842D03*
X408069Y46907D03*
X394682Y68492D03*
X408184Y51000D03*
X394492Y54700D03*
X398029Y65807D03*
X408069D03*
X394682Y49592D03*
X398029Y35942D03*
Y46907D03*
X411416Y54857D03*
X394682Y87392D03*
X401375Y92757D03*
X398029Y84800D03*
Y73742D03*
X408068Y87392D03*
X411415Y89964D03*
X408069Y73742D03*
X411415Y84714D03*
X408184Y69900D03*
X404722Y89964D03*
X401375Y87392D03*
X414761Y92757D03*
X398029Y89964D03*
X404722Y84599D03*
X414761Y87392D03*
X408068Y92757D03*
X364565Y35942D03*
X386292Y98800D03*
X408126Y103116D03*
Y105750D03*
X414820Y105800D03*
X401375D03*
Y103116D03*
X414819D03*
X365877Y218860D03*
X372637D03*
X386157Y211060D03*
X379397Y207159D03*
Y218860D03*
X359117Y211060D03*
Y218860D03*
X386157D03*
X357987Y193507D03*
X378267D03*
X372637Y211060D03*
X399676D03*
X392916D03*
X399676Y218860D03*
X407706Y216909D03*
X392916Y218860D03*
X369257Y213009D03*
X376017Y216909D03*
X362497D03*
X382777Y213009D03*
X369257Y216909D03*
X382777D03*
X362497Y213009D03*
X389537Y216909D03*
X376017Y213009D03*
X386157Y207159D03*
X362497Y209109D03*
X382777D03*
X376017D03*
X382777Y201309D03*
X365877Y214960D03*
X372637D03*
X379397D03*
X359117D03*
X365877Y203260D03*
X376017Y205211D03*
X362497Y205210D03*
X386157Y214960D03*
X389537Y209109D03*
X372637Y207159D03*
X389537Y213009D03*
X415634Y204496D03*
Y212296D03*
X396296Y209109D03*
X404392Y199100D03*
X415634Y208397D03*
X407706Y209109D03*
X399676Y207159D03*
X396296Y213009D03*
Y216909D03*
X415634Y216196D03*
X392898Y195041D03*
X392916Y214960D03*
Y203260D03*
X396296Y197359D03*
X399676Y203260D03*
Y214960D03*
X405306Y216909D03*
Y213009D03*
Y209109D03*
Y205210D03*
X376017Y224709D03*
X369257D03*
X362497D03*
X389537D03*
X382777D03*
X396296D03*
X407706Y236409D03*
Y244209D03*
X415634Y243496D03*
Y231797D03*
X396296Y236409D03*
X359117Y230559D03*
X379397Y234460D03*
X386157Y230559D03*
X407706Y224709D03*
X392916Y230559D03*
X399676D03*
X389537Y236409D03*
X362497D03*
X369257D03*
X365877Y230559D03*
X372637D03*
X365877Y242260D03*
X372637D03*
X362497Y248109D03*
X359117Y250060D03*
X389537Y240309D03*
X382777D03*
X386157Y242260D03*
X379397D03*
X389537Y244209D03*
X382777D03*
X376017D03*
X386157Y246160D03*
X379397D03*
X372637D03*
X365877D03*
X369257Y248109D03*
X365877Y250060D03*
X359117Y253960D03*
X362497Y252009D03*
X399676Y242260D03*
X392916D03*
Y246160D03*
X396296Y244209D03*
Y240309D03*
X359117Y242260D03*
X372637Y222760D03*
X365877D03*
X386157D03*
X379397D03*
X359117D03*
X369257Y240309D03*
X376017D03*
X359117Y246160D03*
X386157Y226660D03*
X389537Y232509D03*
X369257Y244209D03*
X362497D03*
X379397Y238360D03*
X362497Y220809D03*
X379397Y250060D03*
X369257Y220809D03*
X382777D03*
X376017D03*
X386157Y238360D03*
X372637Y226660D03*
X365877D03*
X369257Y232509D03*
X362497D03*
X379397Y226660D03*
X382777Y232509D03*
X376017D03*
X359117Y226660D03*
X372637Y250060D03*
X389537Y248109D03*
Y220809D03*
X376017Y248109D03*
X382777D03*
X386157Y250060D03*
X359117Y238360D03*
X365877D03*
X372637D03*
X365877Y253960D03*
X362497Y255909D03*
X359117Y257860D03*
X372637Y253960D03*
X376017Y252009D03*
X357057Y277360D03*
X368127Y264300D03*
X364747Y266300D03*
X361492Y268100D03*
X362497Y259809D03*
X365877Y257860D03*
X369257Y255909D03*
X357092Y270700D03*
X391787Y254259D03*
X388407Y256500D03*
X359648Y269777D03*
X374887Y260300D03*
X385027Y254259D03*
X359117Y261760D03*
X371507Y262300D03*
X381647Y256400D03*
X378267Y258400D03*
X357057Y273460D03*
X390894Y264899D03*
X369257Y252009D03*
X392916Y222760D03*
Y250060D03*
Y238360D03*
X396296Y248109D03*
Y220809D03*
X399676Y250060D03*
X407706Y248109D03*
Y240309D03*
Y232509D03*
X399676Y246160D03*
X415634Y247396D03*
Y235696D03*
Y223996D03*
X407706Y220809D03*
X415634Y239596D03*
X396296Y228610D03*
X399676Y222760D03*
X415634Y220096D03*
Y227896D03*
X399676Y238360D03*
X392916Y226660D03*
X396296Y232509D03*
X399676Y226660D03*
X395166Y256400D03*
X398546Y254259D03*
X405306Y254500D03*
X401926Y256500D03*
X397394Y264899D03*
X400394D03*
X393894D03*
X379397Y230559D03*
X389537Y228610D03*
X392916Y234460D03*
X386157D03*
X359117D03*
X362497Y240309D03*
X376017Y236409D03*
X407706Y228610D03*
X382777Y236409D03*
X399676Y234460D03*
X382777Y228610D03*
X362497D03*
X369257D03*
X365877Y234460D03*
X372637D03*
X376017Y228610D03*
X405306Y232509D03*
Y228610D03*
Y224709D03*
Y220809D03*
X357987Y267609D03*
X361367Y265660D03*
X364747Y263709D03*
X368127Y261760D03*
X371507Y259809D03*
X374887Y257860D03*
X378267Y255909D03*
X381647Y253960D03*
X388407D03*
X395166D03*
X401926D03*
X405306Y252009D03*
Y248109D03*
Y244209D03*
Y240309D03*
Y236409D03*
X407448Y338641D03*
X416448D03*
X413948D03*
X410948D03*
X357057Y281260D03*
Y296860D03*
Y285160D03*
Y292959D03*
Y300760D03*
Y308560D03*
Y304660D03*
Y289060D03*
Y312460D03*
X364747Y331509D03*
X361367Y329560D03*
X357987Y327609D03*
X371507Y335409D03*
X362497Y337809D03*
X369257Y341709D03*
X368127Y333460D03*
X365877Y339760D03*
X374887Y337360D03*
X381647Y341260D03*
X378267Y339309D03*
X359117Y335860D03*
X357057Y320260D03*
Y324160D03*
X370650Y312441D03*
X378156D03*
X375674D03*
X373162Y312400D03*
X368165Y312504D03*
X359117Y339760D03*
X362497Y341709D03*
X357057Y316360D03*
X414294Y292904D03*
X411294D03*
Y309904D03*
X414294D03*
X403648Y338341D03*
X401148D03*
X398148D03*
X394648D03*
X378267Y341709D03*
X374887Y339760D03*
X371507Y337809D03*
X368127Y335860D03*
X364747Y333909D03*
X361367Y331960D03*
X357987Y330009D03*
X389537Y357309D03*
X365877Y351460D03*
X372637D03*
X362497Y345609D03*
X359117Y343660D03*
X403056Y396309D03*
X411086Y394359D03*
X399676Y386560D03*
X411086D03*
Y382660D03*
Y378760D03*
X398546Y402900D03*
X402892Y400400D03*
X403056Y369010D03*
X399676Y363160D03*
X382777Y369010D03*
X365877Y363160D03*
X372637D03*
X362497Y369010D03*
X369257D03*
X389537Y380709D03*
X392916Y374860D03*
X359117D03*
Y386560D03*
X379397Y374860D03*
X382777Y380709D03*
X369257D03*
X379397Y386560D03*
X399676Y374860D03*
X403056Y380709D03*
X386157Y386560D03*
X396296Y369010D03*
X386157Y374860D03*
X376017Y380709D03*
X365877Y374860D03*
X372637D03*
X362497Y380709D03*
X396296D03*
X392916Y386560D03*
X372637D03*
X376017Y369010D03*
X389537D03*
X392916Y363160D03*
X386157D03*
X359117Y351460D03*
Y363160D03*
X362497Y357309D03*
X379397Y363160D03*
X369257Y357309D03*
X379397Y351460D03*
X362497Y349509D03*
X376017D03*
X382777Y353409D03*
Y357309D03*
X379397Y355360D03*
X359117Y347560D03*
X396296Y357309D03*
X399676Y355360D03*
X369257Y361209D03*
X376017Y357309D03*
X379397Y359260D03*
X382777Y349509D03*
X379397Y347560D03*
X391787Y347109D03*
X388407Y345160D03*
X372637Y343660D03*
X385027Y343209D03*
X379397Y370959D03*
X372637D03*
X365877D03*
X359117D03*
X386157D03*
X362497Y353409D03*
X376017D03*
X369257D03*
Y349509D03*
X386157Y355360D03*
X365877Y347560D03*
X369257Y345609D03*
X376017D03*
X386157Y351460D03*
Y359260D03*
X372637Y347560D03*
X389537Y353409D03*
X372637Y359260D03*
X365877D03*
X359117D03*
X365877Y343660D03*
X389537Y365109D03*
X382777D03*
X369257D03*
X362497D03*
X376017D03*
Y376809D03*
X369257D03*
X382777Y388509D03*
X369257D03*
X362497D03*
X376017D03*
X390657Y394359D03*
X391787Y402800D03*
X357987D03*
X369257Y392410D03*
X362497D03*
X379397Y382660D03*
X372637D03*
X365877D03*
X359117D03*
X379397Y390460D03*
X378267Y402800D03*
X376017Y392410D03*
X386157Y382660D03*
X389537Y388509D03*
Y376809D03*
X382777D03*
X362497D03*
X396296Y353409D03*
X411086Y351460D03*
X405306Y347109D03*
X399676Y351460D03*
X392916Y355360D03*
X395166Y345160D03*
X398546Y347109D03*
X401926Y345160D03*
X392916Y370959D03*
X399676D03*
X396296Y365109D03*
X403056D03*
Y357309D03*
X392916Y351460D03*
Y359260D03*
X396296Y388509D03*
Y376809D03*
X392916Y382660D03*
Y390460D03*
X399676Y382660D03*
X406568Y402471D03*
X403056Y392410D03*
X411086Y390460D03*
Y374860D03*
X403056Y376809D03*
Y388509D03*
X411547Y368260D03*
Y365660D03*
X403056Y353409D03*
X411447Y363160D03*
X411431Y359351D03*
X411086Y355360D03*
X386157Y367060D03*
X396296Y384609D03*
X372637Y390460D03*
X403056Y372909D03*
X392916Y367060D03*
X382777Y361209D03*
X399676Y367060D03*
X389537Y361209D03*
X365877Y367060D03*
X372637D03*
X362497Y361209D03*
X403056D03*
X365877Y355360D03*
X379397Y367060D03*
X376017Y384609D03*
X396296Y372909D03*
X386157Y378760D03*
X359117D03*
X362497Y384609D03*
X392916Y378760D03*
X379397D03*
X382777Y372909D03*
X389537D03*
X399676Y378760D03*
X382777Y384609D03*
X365877Y378760D03*
X372637D03*
X362497Y372909D03*
X369257D03*
Y384609D03*
X376017Y372909D03*
X399676Y390460D03*
X389537Y384609D03*
X396296Y361209D03*
X359117Y367060D03*
Y355360D03*
X399676Y359260D03*
X372637Y355360D03*
X376017Y361209D03*
X408686Y394359D03*
Y390460D03*
Y386560D03*
Y382660D03*
Y378760D03*
Y374860D03*
Y370959D03*
Y367060D03*
Y363160D03*
Y359260D03*
Y355360D03*
Y351460D03*
X405306Y349509D03*
X388407Y347560D03*
X395166D03*
X401926D03*
X385027Y345609D03*
X381647Y343660D03*
X385244Y504027D03*
X386630Y521860D03*
X359042Y515200D03*
X358918Y510114D03*
X366865D03*
Y515152D03*
X375192Y516356D03*
Y518856D03*
X401375Y518157D03*
X398029Y509999D03*
X411415Y515364D03*
X408068Y512792D03*
X411415Y510114D03*
X364265Y515152D03*
X401375Y512792D03*
X404722Y515364D03*
X394682Y512792D03*
X408068Y518157D03*
X414761Y512792D03*
X404722Y509999D03*
X398029Y515364D03*
X414761Y518157D03*
X364265Y510114D03*
X361642Y515200D03*
X361518Y510114D03*
X370596Y585614D03*
X370080Y555700D03*
X366890Y586000D03*
X376892Y581127D03*
X357539Y550511D03*
X357661Y534000D03*
X376829Y546303D03*
X357661Y531546D03*
X357539Y553111D03*
X376785Y538305D03*
X363760Y529293D03*
X367692Y547914D03*
X357672D03*
X357872Y528942D03*
X367911Y529057D03*
X367692Y536200D03*
X357910Y536727D03*
X376792Y543700D03*
X357724Y569474D03*
X376892Y577500D03*
X356798Y588366D03*
X357724Y571973D03*
X367211Y555842D03*
X357910D03*
X367192Y566814D03*
X357910D03*
X367192Y574742D03*
X357872D03*
X357025Y585714D03*
X398029Y536942D03*
X408069Y547907D03*
Y536942D03*
X394587Y529026D03*
X408184Y533100D03*
Y552000D03*
X398029Y547907D03*
X394682Y569492D03*
X408184Y570900D03*
X401376Y555842D03*
X411416Y555857D03*
X398029Y574742D03*
Y585707D03*
X408069D03*
Y574742D03*
X394682Y550592D03*
X361518Y547914D03*
X361320Y555842D03*
X364265Y547914D03*
X364565Y555842D03*
X394595Y537058D03*
X398029Y529007D03*
X361218Y566814D03*
X394682Y588392D03*
X361518Y585714D03*
X364265D03*
X408069Y566807D03*
X398029D03*
X361218Y574742D03*
X408069Y529007D03*
X364565Y574742D03*
Y566814D03*
X386970Y623539D03*
X378600Y606200D03*
X408068Y612657D03*
X413324Y623559D03*
X399824D03*
X356798Y590939D03*
X373400Y593800D03*
X376204Y593650D03*
X374039Y611186D03*
X357872Y604614D03*
X367170Y611759D03*
X357872Y612242D03*
X367911Y593642D03*
X357026D03*
X367911Y604614D03*
X371134Y612453D03*
X370659Y593691D03*
X371312Y604709D03*
X411415Y609864D03*
X394682Y607292D03*
X408184Y589800D03*
X398029Y609864D03*
X401376Y593642D03*
X401375Y607292D03*
X411416Y593657D03*
X411415Y604614D03*
X414761Y612657D03*
X394682D03*
X408068Y607292D03*
X404722Y609864D03*
X414761Y607292D03*
X361218Y612242D03*
X361964Y593642D03*
X364565Y612242D03*
X365311Y593642D03*
X364565Y604614D03*
X401376Y612658D03*
X404722Y604499D03*
X398029D03*
X361218Y604614D03*
X438187Y-4536D03*
X451573Y-9901D03*
X428147Y-1743D03*
X421454Y-7108D03*
X434840Y-1743D03*
X418108Y-4536D03*
X431494D03*
X424801D03*
X428147Y-7108D03*
X434840D03*
X431494Y9107D03*
X424801D03*
X418108D03*
Y-9701D03*
X441533Y-1843D03*
Y9107D03*
X447744Y-7180D03*
X451573Y-1801D03*
Y9114D03*
X436392Y-20760D03*
X422892Y-20789D03*
X421454Y-1817D03*
X434842Y17057D03*
X441533Y17042D03*
X418108D03*
X428149Y17057D03*
X448226Y11100D03*
Y28100D03*
X433508Y32100D03*
X448292Y31900D03*
X421368Y32100D03*
X433508Y13200D03*
X448292Y13700D03*
X421368Y13200D03*
X448892Y17000D03*
X451573Y27899D03*
X424801Y28007D03*
X451573Y17157D03*
X418108Y28007D03*
X441533D03*
X458266Y-1751D03*
X460912Y-7700D03*
Y-4100D03*
X458266Y-9901D03*
X454533Y-4100D03*
X478344Y-3700D03*
X474998Y-9901D03*
X464758Y-7050D03*
X469832Y-7260D03*
X464732Y-4401D03*
X469832Y-4651D03*
X454533Y-7851D03*
X458116Y9114D03*
X469832Y-2051D03*
X464732Y-1801D03*
X474998Y-1751D03*
X469845Y-9864D03*
X478344Y-7851D03*
X464758Y-9652D03*
X474998Y9114D03*
X464732Y9098D03*
X478344Y29949D03*
X460912Y30100D03*
Y14814D03*
X469832Y17114D03*
X454569Y14714D03*
X460912Y33700D03*
X458266Y27899D03*
X454533Y33700D03*
X474998Y27899D03*
X464758Y30750D03*
X469832Y33149D03*
X464732Y33399D03*
X454533Y29949D03*
X469792Y9300D03*
X469832Y30540D03*
X458266Y17157D03*
X460912Y12114D03*
X454619D03*
X474998Y17157D03*
X478344Y12114D03*
X464732Y14300D03*
X469832Y14514D03*
X464732Y11700D03*
X469832Y11914D03*
X478344Y14814D03*
X469845Y27936D03*
X464792Y28100D03*
X464692Y16900D03*
X444880Y-9786D03*
X431494Y-9901D03*
Y28007D03*
X438187Y-9786D03*
X424801D03*
X444880Y-4536D03*
X434842Y54857D03*
X441533Y54842D03*
X424801Y46907D03*
X431494D03*
X428149Y54857D03*
X441533Y46907D03*
X448414Y35761D03*
X448973Y54883D03*
X451573Y35999D03*
X448627Y68090D03*
X448517Y46975D03*
X448492Y51000D03*
X421368D03*
X433508D03*
X451573Y46900D03*
X431494Y65807D03*
X451573Y65699D03*
X424801Y65807D03*
X451573Y54957D03*
X418108Y65807D03*
Y54842D03*
X441533Y65807D03*
X431494Y35942D03*
X441533D03*
X424801D03*
X418108D03*
Y46907D03*
X424801Y89964D03*
X438187D03*
X428147Y92500D03*
X424801Y84800D03*
X431400D03*
X431494Y73742D03*
X441533Y87392D03*
Y92500D03*
Y73742D03*
X418108Y89964D03*
Y84599D03*
Y73742D03*
X424801D03*
X434840Y92500D03*
X448651Y70896D03*
X433508Y69900D03*
X421368D03*
X451573Y84714D03*
Y73799D03*
X448610Y85296D03*
X448599Y73589D03*
X448692Y89900D03*
X438187Y84714D03*
X431494Y89964D03*
X444880D03*
Y84714D03*
X451573Y92757D03*
X428147Y87392D03*
X421454Y92757D03*
X434840Y87392D03*
X474998Y36049D03*
X464732Y46898D03*
X460912Y52614D03*
X458266Y36049D03*
X458116Y46914D03*
X464758Y65950D03*
X474998Y46914D03*
X458266Y65699D03*
X474998D03*
X464758Y68550D03*
X469832Y68340D03*
X458266Y54957D03*
X460912Y49914D03*
X454619Y49564D03*
X474998Y54957D03*
X478344Y34100D03*
Y49914D03*
X464732Y52100D03*
X469832Y49714D03*
X464732Y49500D03*
X454533Y67749D03*
X454569Y52514D03*
X469832Y52314D03*
Y54914D03*
X469792Y47100D03*
Y35800D03*
X464692Y54700D03*
X464732Y35999D03*
X478344Y52614D03*
X460912Y67900D03*
X478344Y67749D03*
X469845Y65736D03*
X478344Y87714D03*
X464732Y89900D03*
X469832Y70949D03*
Y87514D03*
X464732Y71199D03*
Y87300D03*
X469832Y90114D03*
X458116Y84714D03*
X464708Y92500D03*
X464732Y84698D03*
X469808Y84700D03*
X474998Y73849D03*
X469858Y73550D03*
X474998Y84714D03*
X478344Y90414D03*
X469832Y92714D03*
X460912Y90314D03*
X464732Y73799D03*
X458266Y73849D03*
X454569Y90314D03*
X460912Y71500D03*
X458266Y92757D03*
X460912Y87714D03*
X454533Y71500D03*
X454619Y87714D03*
X478344Y71900D03*
X474998Y92757D03*
X421512Y103116D03*
X427696Y105800D03*
X421503D03*
X427696Y103100D03*
X419214Y218147D03*
X441743Y199841D03*
X421464Y199583D03*
X446253Y206446D03*
X425974D03*
X453013Y218147D03*
X449633Y212296D03*
Y216196D03*
X422594D03*
X419214Y214247D03*
X436113Y212296D03*
X432733Y214247D03*
X429354Y216196D03*
X432733Y218147D03*
X425974D03*
X429353Y212296D03*
X446253Y218147D03*
X442873Y216196D03*
X439493Y214247D03*
X436113Y216196D03*
X453013Y214247D03*
X439493Y210346D03*
X434983Y198931D03*
X439493Y218147D03*
X459773D03*
X455263Y198050D03*
X473292Y218147D03*
X469913Y216196D03*
X469912Y212296D03*
X475692Y199900D03*
X466533Y218147D03*
X473292Y214247D03*
X476672Y212296D03*
Y216196D03*
X459773Y214247D03*
X466533Y206446D03*
X456393Y216196D03*
X462023Y198327D03*
X456393Y212296D03*
X463153Y216196D03*
X436113Y235696D03*
Y220096D03*
Y227896D03*
X446253Y222047D03*
Y225947D03*
X432733Y222047D03*
Y225947D03*
X442873Y220096D03*
Y227896D03*
X453013Y225947D03*
X439493Y229847D03*
Y222047D03*
Y225947D03*
X425974Y222047D03*
X419214Y225947D03*
X442873Y235696D03*
X429354Y231797D03*
X449633D03*
Y239596D03*
X452865Y270081D03*
X439764Y263699D03*
X449288Y266435D03*
X444752Y264188D03*
X453013Y253247D03*
X463153Y220096D03*
Y227896D03*
X473292Y222047D03*
Y225947D03*
X459773Y229847D03*
Y222047D03*
X466533Y241547D03*
X463153Y235696D03*
X473292Y241547D03*
X469913Y235696D03*
X456393D03*
Y247396D03*
X463153D03*
X476672D03*
X456393Y220096D03*
X466533Y225947D03*
Y253247D03*
X473292D03*
X459773D03*
X476672Y262996D03*
X469913Y266896D03*
X422594Y235696D03*
Y247396D03*
X429354Y239596D03*
X425974Y233746D03*
Y241547D03*
X436113Y239596D03*
X422594D03*
X432733Y233746D03*
X429354Y251296D03*
X453013Y245447D03*
Y229847D03*
Y237647D03*
X449633Y251296D03*
Y247396D03*
Y227896D03*
Y223996D03*
X436113Y243496D03*
X442873D03*
X422594D03*
X425974Y245447D03*
Y249347D03*
X432733D03*
X436113Y251296D03*
X429354Y247396D03*
X422594Y251296D03*
X446253Y245447D03*
X419214Y249347D03*
X432733Y245447D03*
X439493Y237647D03*
X446253D03*
X422594Y223996D03*
Y231797D03*
X419214Y233746D03*
Y237647D03*
X436113Y231797D03*
X439493Y241547D03*
X419214D03*
X436113Y223996D03*
X429354D03*
Y220096D03*
Y227896D03*
X446253Y229847D03*
X432733D03*
X425974D03*
X439493Y233746D03*
X442873Y231797D03*
Y223996D03*
X425974Y237647D03*
X432733D03*
X449633Y220096D03*
X419214Y245447D03*
X453013Y222047D03*
X425974Y225947D03*
X422594Y220096D03*
Y227896D03*
X419214Y222047D03*
Y229847D03*
X432733Y241547D03*
X446253Y233746D03*
Y241547D03*
X442873Y239596D03*
X453013Y233746D03*
Y241547D03*
Y249347D03*
X429354Y243496D03*
X449633D03*
X429354Y235696D03*
X449633D03*
X436113Y247396D03*
X446253Y249347D03*
X442873Y251296D03*
X439493Y249347D03*
X442873Y247396D03*
X439493Y245447D03*
X444408Y267305D03*
X440500Y266500D03*
X418084Y253546D03*
X451883Y265246D03*
X434983Y255497D03*
X438363Y257446D03*
X421464Y255497D03*
X431604Y257446D03*
X448503Y263297D03*
X445123Y261346D03*
X441743Y259397D03*
X446253Y253247D03*
X447148Y278841D03*
X449848D03*
X450800Y275600D03*
X429781Y264793D03*
X439493Y253247D03*
X449633Y255196D03*
Y259096D03*
X446253Y257147D03*
X442873Y255196D03*
X453013Y257147D03*
Y261047D03*
X448900Y269600D03*
X476672Y227896D03*
X459773Y225947D03*
X466533Y233746D03*
X476672Y239596D03*
X463153D03*
X473292Y233746D03*
X469913Y231797D03*
Y243496D03*
Y239596D03*
X456393D03*
X469913Y251296D03*
X466533Y245447D03*
X473292D03*
X466533Y249347D03*
X473292D03*
X459773Y245447D03*
Y249347D03*
X476672Y223996D03*
Y243496D03*
Y251296D03*
X469913Y247396D03*
Y223996D03*
X473292Y229847D03*
X469913Y227896D03*
X466533Y229847D03*
X473292Y237647D03*
X466533D03*
X469913Y220096D03*
X456393Y243496D03*
Y251296D03*
X459773Y233746D03*
Y241547D03*
Y237647D03*
X456393Y223996D03*
Y231797D03*
X476672D03*
X463153Y243496D03*
Y251296D03*
Y231797D03*
Y223996D03*
X456393Y227896D03*
X466533Y222047D03*
X476672Y259096D03*
X463153D03*
X458408Y278940D03*
X477792Y272747D03*
X462023Y271097D03*
X458643Y269146D03*
X456393Y262996D03*
Y259096D03*
X459773Y261047D03*
X469913Y255196D03*
X473292Y257147D03*
X466533D03*
X468783Y274997D03*
X469913Y270796D03*
X466533Y264947D03*
X456393Y255196D03*
X463153D03*
X476672D03*
X459773Y257147D03*
X465100Y280300D03*
X455263Y267197D03*
X466533Y261047D03*
X463153Y262996D03*
X477792Y276646D03*
Y280547D03*
X453400Y275600D03*
X473292Y261047D03*
X469913Y259096D03*
X476672Y266896D03*
X473292Y268847D03*
Y264947D03*
X474413Y274696D03*
X469913Y278596D03*
X466533Y268847D03*
X469913Y262996D03*
X458400Y276400D03*
X459773Y264947D03*
X447800Y335900D03*
X466066Y292452D03*
X466734Y287074D03*
X466100Y300021D03*
X471033Y339047D03*
X426494Y338361D03*
X430089Y338428D03*
X442020Y339220D03*
X419400Y338600D03*
X438240Y339380D03*
X449500Y309800D03*
X451648Y308341D03*
X447000Y309800D03*
X421494Y292904D03*
X435894D03*
X432894D03*
X440094D03*
X443094D03*
X425694D03*
X418494D03*
X428694D03*
X418494Y309904D03*
X421494D03*
X425694D03*
X428694D03*
X432894D03*
X435894D03*
X440094Y309841D03*
X443148D03*
X450700Y335550D03*
X453200D03*
X469913Y305896D03*
X477792Y307851D03*
X469913Y286396D03*
X477792Y303947D03*
Y288347D03*
X464000Y294500D03*
X454148Y310341D03*
Y307841D03*
X469913Y298096D03*
Y301996D03*
X477792Y284447D03*
Y296147D03*
Y300047D03*
Y292247D03*
Y311747D03*
X469913Y309797D03*
X453400Y293686D03*
X469913Y282496D03*
Y294196D03*
Y290296D03*
X477792Y315647D03*
Y319547D03*
X458643Y338746D03*
X477792Y327347D03*
X462948Y315251D03*
X463671Y319386D03*
X474413Y329296D03*
X468783Y332897D03*
X474413Y333196D03*
Y325396D03*
X477792Y323446D03*
X456900Y333000D03*
X469913Y313696D03*
Y317596D03*
X455263Y340697D03*
X462848Y312741D03*
X467653Y340996D03*
X474413D03*
Y337096D03*
X469913Y321496D03*
X477792Y331247D03*
Y335147D03*
Y339047D03*
X463800Y289500D03*
X430474Y358547D03*
X433854Y356596D03*
X467653Y379996D03*
X443993Y354647D03*
X460893Y368296D03*
X450753Y374146D03*
X464273D03*
X454133Y368296D03*
X423714Y366347D03*
Y358547D03*
X437233Y366347D03*
X477792Y374146D03*
X427094Y387796D03*
X471033Y374146D03*
X474413Y368296D03*
X430474Y381947D03*
X423714Y378047D03*
X433854Y387796D03*
X423714Y393647D03*
X467653Y387796D03*
X447373Y383896D03*
X460893D03*
X474413D03*
X450753Y389747D03*
X440613Y383896D03*
X454133D03*
X443993Y389747D03*
X467653Y360496D03*
X447373D03*
X457513Y374146D03*
X430474Y362447D03*
Y370247D03*
X471033Y354647D03*
X460893Y360496D03*
X474413D03*
X464273Y354647D03*
X450753D03*
X440613Y360496D03*
X454133D03*
X443993Y370247D03*
X437233Y378047D03*
X440613Y376096D03*
X443993Y374147D03*
X464273Y342947D03*
X457513Y350747D03*
X460893Y344896D03*
X474413D03*
X443993Y358547D03*
X441743Y348497D03*
X440613Y352696D03*
X437233Y358547D03*
X450753Y366347D03*
Y350747D03*
Y358547D03*
X437233Y362447D03*
X423714D03*
X433854Y368296D03*
X427094D03*
X440613Y364396D03*
X427094Y372197D03*
X447373D03*
Y368296D03*
X440613Y372197D03*
Y368296D03*
X443993Y366347D03*
X427094Y356596D03*
X433854Y352696D03*
X437233Y354647D03*
X423714D03*
X430474D03*
X427094Y360496D03*
X433854D03*
X445123Y346546D03*
X427094Y352696D03*
X447373Y356596D03*
X451883Y342646D03*
X448503Y344597D03*
X421464Y348497D03*
X438363Y346546D03*
X424844D03*
X434983Y348497D03*
X428224D03*
X431604Y346546D03*
X430474Y385847D03*
X450753Y397547D03*
X440613Y395595D03*
X429354Y399496D03*
X433854Y379996D03*
X423714Y381947D03*
X430474Y374146D03*
X423714D03*
X437233D03*
X430474Y378047D03*
X433854Y376096D03*
X443993Y397546D03*
Y401447D03*
Y393647D03*
X440613Y391696D03*
X443993Y385847D03*
X427094Y376096D03*
X437233Y381947D03*
X447373Y376096D03*
X440613Y379996D03*
X443993Y378047D03*
X423715Y397548D03*
X430474Y393647D03*
X433854Y391696D03*
X423715Y401449D03*
X450753Y385847D03*
Y393647D03*
Y378047D03*
X437233Y389747D03*
Y385847D03*
X423714D03*
X477792Y342947D03*
Y362447D03*
Y354647D03*
Y358547D03*
X457513Y362447D03*
X464273Y346847D03*
X471033Y342947D03*
X454133Y372197D03*
Y364396D03*
Y348796D03*
Y352696D03*
X464273Y366347D03*
X474413Y372197D03*
X471033Y366347D03*
X467653Y372197D03*
X474413Y364396D03*
X464273Y350747D03*
X474413Y348796D03*
X471033Y350747D03*
X474413Y352696D03*
X471033Y358547D03*
X464273D03*
X467653Y368296D03*
Y348796D03*
X460893Y372197D03*
Y364396D03*
Y352696D03*
X457513Y354647D03*
Y358547D03*
Y346847D03*
X477792Y389747D03*
X457513D03*
X471033Y393647D03*
X460893Y395595D03*
X464273Y401447D03*
X471033D03*
X460893Y391696D03*
X457513Y385847D03*
Y381947D03*
X460893Y379996D03*
X477792Y381947D03*
X474413Y391696D03*
X464273Y385847D03*
X454133Y391696D03*
Y379996D03*
X471033Y385847D03*
X464273Y393647D03*
X474413Y379996D03*
X471033Y378047D03*
X467653Y376096D03*
X464273Y378047D03*
Y397546D03*
X477792Y385847D03*
Y346847D03*
Y350747D03*
X471033Y346847D03*
X454133Y356596D03*
X443993Y362447D03*
X460893Y376096D03*
X450753Y370247D03*
X464273D03*
X454133Y376096D03*
X433854Y372197D03*
Y364396D03*
X437233Y370247D03*
X423714D03*
X427094Y364396D03*
X477792Y366347D03*
X427094Y379996D03*
X477792Y378047D03*
X427094Y391696D03*
X477792Y370247D03*
X427094Y383896D03*
X471033Y370247D03*
X474413Y376096D03*
X430474Y389747D03*
X433854Y383896D03*
X423714Y389747D03*
X447373Y387796D03*
X467653Y383896D03*
X447373Y379996D03*
X467653Y391696D03*
X447373D03*
X471033Y389747D03*
Y381947D03*
X460893Y387796D03*
X474413D03*
X464273Y389747D03*
Y381947D03*
X450753D03*
X440613Y387796D03*
X454133D03*
X443993Y381947D03*
X467653Y352696D03*
X447373D03*
X457513Y366347D03*
X467653Y364396D03*
X447373D03*
X457513Y378047D03*
X467653Y356596D03*
X457513Y370247D03*
X430474Y366347D03*
X471033Y362447D03*
X460893Y356596D03*
X474413D03*
X464273Y362447D03*
X450753D03*
X440613Y356596D03*
X447091Y407782D03*
X428224Y407800D03*
X443993Y405347D03*
X467653Y407296D03*
X464273Y405347D03*
X441533Y512792D03*
Y518057D03*
X433192Y497650D03*
X434840Y518157D03*
X431494Y509999D03*
X424801Y510114D03*
X418108Y515364D03*
Y509999D03*
X428147Y518157D03*
X451573Y510114D03*
X448692Y515300D03*
X447735Y512794D03*
X474998Y510114D03*
X464732Y510098D03*
X460912Y515714D03*
X458116Y510114D03*
X454569Y515714D03*
X478344Y515814D03*
X464708Y517900D03*
X469832Y518114D03*
X464732Y512700D03*
X469832Y512914D03*
X464732Y515300D03*
X478344Y513114D03*
X474998Y518157D03*
X454619Y513114D03*
X451573Y518157D03*
X460912Y513114D03*
X458266Y518157D03*
X444880Y510114D03*
Y515364D03*
X431494D03*
X435192Y499400D03*
X438187Y510114D03*
Y515364D03*
X424801D03*
X434840Y512792D03*
X421454Y518157D03*
X428147Y512792D03*
X469832Y515514D03*
X418108Y536942D03*
Y547907D03*
X431494D03*
X424801D03*
X441533D03*
X418108Y529007D03*
X431494Y536942D03*
X424801D03*
X441533Y536957D03*
Y529007D03*
X451573Y547914D03*
Y536999D03*
X448510Y549843D03*
X448410Y531156D03*
X448432Y536723D03*
X448692Y553100D03*
X448557Y534061D03*
X421368Y533100D03*
X434395Y532904D03*
X433508Y552000D03*
X421368D03*
X447735Y588394D03*
X433508Y570900D03*
X421368D03*
X451573Y585714D03*
Y574799D03*
X448226Y569200D03*
X448291Y574773D03*
X451573Y566699D03*
X418108Y555842D03*
X428149Y555857D03*
X434842D03*
X441533Y555842D03*
Y585707D03*
Y574742D03*
X418108Y566807D03*
X441533D03*
X424801Y574742D03*
X418108Y585599D03*
Y574742D03*
X431494D03*
Y585707D03*
X424801D03*
X464732Y536999D03*
X460912Y553514D03*
X458116Y547914D03*
X454619Y550914D03*
X454569Y553514D03*
X454533Y530949D03*
X460912Y531100D03*
X458266Y537049D03*
X469845Y528936D03*
X474998Y537049D03*
X464758Y529150D03*
X469858Y536750D03*
X478344Y553614D03*
X464732Y547898D03*
X474998Y547914D03*
X469808Y547900D03*
X478344Y530949D03*
Y568749D03*
X464732Y574799D03*
X469808Y585700D03*
X469858Y574550D03*
X474998Y574849D03*
Y585714D03*
X464732Y585698D03*
X464758Y566950D03*
X469845Y566736D03*
X458266Y574849D03*
X460912Y568900D03*
X458116Y585714D03*
X454533Y568749D03*
X464708Y555700D03*
X469832Y555914D03*
Y534149D03*
X464758Y531750D03*
X474998Y528899D03*
X478344Y535100D03*
X451573Y528899D03*
X454533Y534700D03*
X458266Y528899D03*
X460912Y534700D03*
X469832Y553314D03*
X464732Y550500D03*
X469832Y550714D03*
X464732Y553100D03*
X478344Y550914D03*
X474998Y555957D03*
X451573D03*
X460912Y550914D03*
X458266Y555957D03*
X478344Y588714D03*
X454619D03*
X460912D03*
X469832Y569340D03*
Y571949D03*
X464758Y569550D03*
X474998Y566699D03*
X478344Y572900D03*
X454533Y572500D03*
X458266Y566699D03*
X460912Y572500D03*
X431494Y566807D03*
X464732Y588300D03*
X469832Y588514D03*
X464732Y534399D03*
X469832Y531540D03*
X424801Y566807D03*
X464732Y572199D03*
X421454Y612560D03*
X441533Y612557D03*
X447766Y612659D03*
X453250Y623320D03*
X474998Y612649D03*
X464732Y612599D03*
X458266Y612649D03*
X456910Y623320D03*
X427324Y623541D03*
X451573Y612599D03*
X441533Y607292D03*
X434840D03*
X428147D03*
X418108Y609864D03*
X424801D03*
X447744Y607220D03*
X448692Y590900D03*
X420634Y589800D03*
X433500D03*
X431494Y609864D03*
X418108Y593642D03*
X434842Y593657D03*
X428149D03*
X441533Y593642D03*
X418108Y604499D03*
X478344Y591414D03*
X464708Y593500D03*
X469832Y593714D03*
X464758Y604750D03*
X469845Y604536D03*
X478344Y606549D03*
X469858Y612350D03*
X460912Y591314D03*
Y606700D03*
X469832Y591114D03*
X469833Y607140D03*
X454533Y606549D03*
X454569Y591314D03*
X478344Y610700D03*
X474998Y593757D03*
X451573Y604499D03*
X454533Y610300D03*
X451573Y593757D03*
X458266Y604499D03*
Y593757D03*
X460912Y610300D03*
X444880Y609864D03*
X438187Y604614D03*
X424801D03*
X434840Y612657D03*
X421454Y607292D03*
X428147Y612657D03*
X464732Y609999D03*
X469832Y609749D03*
X464732Y590900D03*
X474998Y604499D03*
X444880Y604614D03*
X431494Y604499D03*
X464758Y607350D03*
X438187Y609864D03*
X511809Y-1751D03*
X485037Y-3700D03*
X481691Y-9901D03*
X497723Y-4100D03*
X495077Y-9901D03*
X491344Y-4100D03*
X488384Y-9901D03*
X511809D03*
X501570Y-7050D03*
X506644Y-7260D03*
X501544Y-4401D03*
X506644Y-4651D03*
X511809Y9114D03*
X495077Y-1751D03*
X501544Y-1801D03*
X506692Y-2000D03*
X488384Y-1801D03*
X481691Y-1751D03*
X485037Y-7851D03*
X491344D03*
X506657Y-9864D03*
X497723Y-7700D03*
X501592Y-9700D03*
X481691Y9114D03*
X494927D03*
X488384D03*
X501544Y9098D03*
X497723Y14814D03*
X506644Y17114D03*
X506657Y27936D03*
X497723Y30100D03*
X491380Y14714D03*
X481691Y27899D03*
X497723Y33700D03*
X495077Y27899D03*
X491344Y33700D03*
X488384Y27899D03*
X511809D03*
X501569Y30750D03*
X506643Y33149D03*
X506604Y9300D03*
X481691Y17157D03*
X485037Y12114D03*
X495077Y17157D03*
X497723Y12114D03*
X488384Y17157D03*
X491430Y12114D03*
X511809Y17157D03*
X501544Y14300D03*
X506644Y14514D03*
X501544Y11700D03*
X506644Y11914D03*
X485037Y14814D03*
X501504Y16900D03*
X485037Y29949D03*
X491344D03*
X501603Y28100D03*
X515155Y-7851D03*
X538355Y9098D03*
X518502Y-1751D03*
X521848Y-7851D03*
X538355Y-1801D03*
X531888Y-1751D03*
X525195Y-1801D03*
X538403Y-9700D03*
X528155Y-7851D03*
X534534Y-7700D03*
X518502Y9114D03*
X531738D03*
X525195D03*
X521848Y-3700D03*
X518502Y-9901D03*
X515155Y-3700D03*
X534534Y-4100D03*
X531888Y-9901D03*
X528155Y-4100D03*
X525195Y-9901D03*
X538381Y-7050D03*
X521848Y14814D03*
Y29949D03*
X528191Y14714D03*
X538315Y16900D03*
X534534Y30100D03*
X518502Y27899D03*
X534534Y33700D03*
X531888Y27899D03*
X528155Y33700D03*
X525195Y27899D03*
X538381Y30750D03*
X538355Y33399D03*
X518502Y17157D03*
X521848Y12114D03*
X515155D03*
X531888Y17157D03*
X534534Y12114D03*
X525195Y17157D03*
X528241Y12114D03*
X538355Y14300D03*
Y11700D03*
X515155Y29949D03*
Y14814D03*
X534534D03*
X528155Y29949D03*
X538415Y28100D03*
X501543Y33399D03*
X506643Y30540D03*
X538355Y-4401D03*
X488384Y35999D03*
X501492Y54700D03*
X497723Y52614D03*
Y67900D03*
X501544Y46898D03*
X511809Y46914D03*
X491344Y67749D03*
X506657Y65736D03*
X501570Y65950D03*
X481691Y36049D03*
Y65699D03*
X495077D03*
X488384D03*
X511809D03*
X501570Y68550D03*
X506644Y68340D03*
X485037Y34100D03*
X481691Y54957D03*
X485037Y49914D03*
X495077Y54957D03*
X497723Y49914D03*
X488384Y54957D03*
X491430Y49914D03*
X511809Y54957D03*
X501543Y52100D03*
X506643Y49714D03*
X501543Y49500D03*
X495077Y36049D03*
X506643Y52314D03*
X506644Y54914D03*
X494927Y46914D03*
X485037Y52614D03*
X481691Y46914D03*
X511809Y36049D03*
X485037Y67749D03*
X488384Y46914D03*
X506603Y35800D03*
X506592Y47000D03*
X501544Y35999D03*
X497723Y71500D03*
X495077Y92757D03*
X497723Y87714D03*
X491344Y71500D03*
X488384Y92757D03*
X491430Y87714D03*
X511809Y92757D03*
X501544Y89900D03*
X506644Y70949D03*
Y87514D03*
X501544Y71199D03*
Y87300D03*
X506644Y90114D03*
X511809Y84714D03*
X501544Y84698D03*
X494927Y84714D03*
X506670Y73550D03*
X481691Y84714D03*
X488384D03*
X501520Y92500D03*
X506620Y84700D03*
X511809Y73849D03*
X488384Y73799D03*
X481691Y73849D03*
X506644Y92714D03*
X491380Y90314D03*
X497723Y90414D03*
X485037D03*
X495077Y73849D03*
X501544Y73799D03*
X485037Y71900D03*
X481691Y92757D03*
X485037Y87714D03*
X518502Y36049D03*
Y46914D03*
X521848Y67749D03*
X531888Y36049D03*
X538355Y35999D03*
X534534Y52614D03*
X531738Y46914D03*
X525195Y35999D03*
X518502Y65699D03*
X531888D03*
X525195D03*
X538381Y68550D03*
X521848Y34100D03*
X518502Y54957D03*
X521848Y49914D03*
X515155Y34100D03*
Y49914D03*
X531888Y54957D03*
X534534Y49914D03*
X525195Y54957D03*
X528241Y49914D03*
X538355Y52100D03*
Y49500D03*
X515155Y67749D03*
Y52614D03*
X521848D03*
X538355Y89900D03*
X534534Y67900D03*
X538381Y65950D03*
X528155Y67749D03*
X538355Y46898D03*
X538304Y54700D03*
X525195Y46914D03*
X538355Y71199D03*
Y87300D03*
X515155Y90414D03*
X534534D03*
X528191Y90314D03*
X521848Y90414D03*
X518502Y73849D03*
Y84714D03*
X531738D03*
X525195D03*
X538355Y84698D03*
X538331Y92500D03*
X531888Y73849D03*
X525195Y73799D03*
X538355D03*
X521848Y71900D03*
X518502Y92757D03*
X521848Y87714D03*
X515155Y71900D03*
Y87714D03*
X534534Y71500D03*
X531888Y92757D03*
X534534Y87714D03*
X528155Y71500D03*
X525195Y92757D03*
X528241Y87714D03*
X494927Y112357D03*
X497723Y106964D03*
X488634Y112357D03*
X491430Y106964D03*
X512024Y112357D03*
X501544Y110514D03*
X506644Y107655D03*
X501570Y107865D03*
X506670Y110264D03*
X512024Y104314D03*
X497723Y109564D03*
X501544Y113114D03*
X506670Y112865D03*
X501570Y105265D03*
X491430Y109564D03*
X506657Y105051D03*
X488634Y104314D03*
X495077D03*
X518317Y112357D03*
X521113Y106964D03*
X514820D03*
X531888Y112357D03*
X534534Y106964D03*
X525134Y112357D03*
X528241Y107314D03*
X538355Y110514D03*
X538381Y107865D03*
X514820Y109564D03*
X521113D03*
X528191Y109914D03*
X534534Y109564D03*
X538355Y113114D03*
X531738Y104314D03*
X525134D03*
X538381Y105265D03*
X518467Y104314D03*
X518352Y210345D03*
X528491Y212296D03*
X494692D03*
X501452Y216196D03*
X504832Y218147D03*
X511592Y214247D03*
X514972Y216196D03*
X518352Y214247D03*
X531871D03*
X514972Y212296D03*
Y208397D03*
X521731Y212296D03*
X525111Y210346D03*
X504832Y214247D03*
X498072D03*
X508212Y216196D03*
X535251Y212296D03*
X480052Y218147D03*
X511592Y206447D03*
Y210346D03*
Y218147D03*
X486812Y214247D03*
Y218147D03*
X498350Y209900D03*
X501452Y212296D03*
X480052Y214247D03*
Y206447D03*
X486812Y210346D03*
X508212Y212296D03*
X518352Y218147D03*
Y206445D03*
X538631Y210346D03*
Y214247D03*
Y206447D03*
X528491Y208397D03*
X525111Y218147D03*
X528491Y216196D03*
X535251Y204496D03*
X525111Y206447D03*
X531871D03*
X521731Y208397D03*
Y216196D03*
X531871Y218147D03*
X528491Y204496D03*
X538631Y202247D03*
X498072Y218147D03*
X494692Y216196D03*
X525111Y214247D03*
X531871Y210346D03*
X535251Y216196D03*
X538631Y218147D03*
X535251Y208397D03*
X483432Y247396D03*
X508212Y243496D03*
X486812Y253247D03*
X480052D03*
X491312Y272747D03*
X494692Y266896D03*
X528491Y259096D03*
X483432Y220096D03*
X480052Y222047D03*
X501452Y251296D03*
Y255196D03*
X491312Y280547D03*
X486812Y261047D03*
X483432Y262996D03*
X498072Y280547D03*
X511592Y272747D03*
X504832Y276647D03*
X498072D03*
X491312D03*
X511592D03*
X504832Y272747D03*
X498072Y253247D03*
Y257147D03*
X504832Y280547D03*
X511592D03*
X498072Y272747D03*
X501452Y262996D03*
X498072Y261047D03*
X494692Y259096D03*
X525111Y249347D03*
X528491Y251296D03*
X525111Y241547D03*
X528491Y239596D03*
X531871Y253247D03*
X521731Y262996D03*
X525111Y264947D03*
X528491Y266896D03*
X521731Y278596D03*
X518352Y280547D03*
Y276646D03*
X484552D03*
X504832Y249347D03*
X501452Y270796D03*
X518352Y268847D03*
X538631Y276646D03*
Y245447D03*
X535251Y274696D03*
X494692Y239596D03*
Y231797D03*
X504832Y237647D03*
X508212Y227896D03*
X525111Y233746D03*
X511592Y237647D03*
X538631Y268847D03*
Y264947D03*
X531871Y245447D03*
X501452Y243496D03*
X535251Y262996D03*
X538631Y253247D03*
X531871Y280547D03*
X538631Y241547D03*
X521731Y270796D03*
X504832Y257147D03*
X508212Y251296D03*
X518352Y225947D03*
X531871Y233746D03*
Y225947D03*
X538631Y233746D03*
X531871Y272747D03*
X501452Y227896D03*
X514972Y231797D03*
X525111Y225947D03*
X494692Y220096D03*
X535251D03*
X504832Y222047D03*
X538631Y272747D03*
X494692Y274696D03*
X483432Y227896D03*
X480052Y229847D03*
X511592Y241547D03*
Y249347D03*
X486812Y245447D03*
X494692Y247396D03*
X483432Y251296D03*
X501452Y247396D03*
X480052Y237647D03*
X508212Y239596D03*
X498072Y233746D03*
X486812D03*
Y229847D03*
X494692Y235696D03*
X504832Y229847D03*
X486812Y225947D03*
Y249347D03*
X480052Y245447D03*
Y249347D03*
X498072Y245447D03*
X494692Y223996D03*
X504832Y225947D03*
X511592Y222047D03*
X498072Y249347D03*
Y222047D03*
Y225947D03*
X486812Y222047D03*
Y237647D03*
X480052Y233746D03*
X504832Y241547D03*
X480052D03*
X486812D03*
X494692Y243496D03*
X483432D03*
X504832Y245447D03*
X501452Y223996D03*
X508212Y231797D03*
Y220096D03*
Y223996D03*
X483432Y235696D03*
Y223996D03*
X494692Y251296D03*
X501452Y274696D03*
X508212Y278596D03*
X484552Y268847D03*
X494692Y255196D03*
X486812Y257147D03*
X511592Y268847D03*
X483432Y255196D03*
X480052Y257147D03*
X508212Y274696D03*
X504832Y268847D03*
X508707Y258532D03*
X504832Y253247D03*
X487932Y278596D03*
Y274696D03*
X494692Y278596D03*
X501452Y266896D03*
Y259096D03*
X484552Y280547D03*
X511592Y253247D03*
X508212Y266896D03*
X513857Y260881D03*
X504832Y261047D03*
X501452Y278596D03*
X504832Y264947D03*
X487932Y270796D03*
X498072Y268847D03*
X491312D03*
X487932Y266896D03*
X491312Y264947D03*
X480052D03*
X481172Y270796D03*
X494692Y262996D03*
X483432Y259096D03*
X481172Y274696D03*
Y278596D03*
X508212Y270796D03*
X494692D03*
X480052Y261047D03*
X518352Y229847D03*
X521731Y231797D03*
Y235696D03*
Y247396D03*
Y220096D03*
X538631Y225947D03*
Y222047D03*
Y237647D03*
X528491Y247396D03*
Y243496D03*
X538631Y249347D03*
X535251Y235696D03*
X528491Y227896D03*
Y235696D03*
Y220096D03*
X535251Y247396D03*
Y251296D03*
Y239596D03*
X531871Y222047D03*
X525111Y237647D03*
X514972Y220096D03*
X518352Y233746D03*
Y222047D03*
X531871Y241547D03*
Y249347D03*
X528491Y223996D03*
X531871Y237647D03*
X535251Y223996D03*
X518352Y245447D03*
Y241547D03*
Y237647D03*
X521731Y239596D03*
Y243496D03*
X525111Y245447D03*
X518352Y249347D03*
X514972Y247396D03*
Y227896D03*
Y235696D03*
Y239596D03*
Y223996D03*
X535251Y259096D03*
X531871Y261047D03*
X514972Y255196D03*
Y270796D03*
Y278596D03*
X525111Y253247D03*
X518352D03*
X528491Y274696D03*
X531871Y268847D03*
Y276646D03*
X535251Y266896D03*
X525111Y280547D03*
X521731Y266896D03*
Y259096D03*
Y274696D03*
X538631Y257147D03*
X521731Y255196D03*
X514972Y274696D03*
X518352Y257147D03*
X528491Y270796D03*
Y278596D03*
X535251Y255196D03*
X531871Y264947D03*
X518352D03*
X531871Y257147D03*
X528491Y255196D03*
X525111Y268847D03*
X528491Y262996D03*
X525111Y276646D03*
X484552Y272747D03*
X525111D03*
X518352D03*
X514972Y251296D03*
X510401Y260511D03*
X498072Y264947D03*
X518352Y261047D03*
X498072Y229847D03*
X501452Y239596D03*
Y231797D03*
X511592Y233746D03*
X525111Y229847D03*
X521731Y223996D03*
X525111Y222047D03*
X531871Y229847D03*
X535251Y227896D03*
Y231797D03*
X498072Y241547D03*
Y237647D03*
X501452Y235696D03*
X508212D03*
X511592Y225947D03*
Y229847D03*
X535251Y270796D03*
X538631Y261047D03*
X504832Y233746D03*
X501452Y220096D03*
X525111Y257147D03*
Y261047D03*
X521731Y251296D03*
X511592Y245447D03*
X514972Y243496D03*
X508212Y247396D03*
X521731Y227896D03*
X538631Y229847D03*
Y280547D03*
X535251Y243496D03*
X494692Y227896D03*
X528491Y231797D03*
X535251Y278596D03*
X504832Y307847D03*
X487932Y305896D03*
X491312Y303947D03*
X501452Y305896D03*
X494692Y298096D03*
X498072Y307847D03*
X484552Y303947D03*
X487932Y294196D03*
X491312Y296147D03*
X494692Y301996D03*
X487932D03*
X501452Y309797D03*
X487932Y298096D03*
X511592Y311747D03*
Y303947D03*
X481172Y321496D03*
X487932Y313696D03*
X481172Y325396D03*
X491312Y315647D03*
X481172Y317596D03*
X518352Y311747D03*
X528491Y305896D03*
X484552Y311747D03*
X481172Y286396D03*
X491312Y288347D03*
Y284447D03*
X498072D03*
Y288347D03*
X501452Y286396D03*
X494692Y290296D03*
X498072Y292247D03*
X504832D03*
X508212Y282496D03*
X504832Y288347D03*
Y284447D03*
X494692Y282496D03*
X508212Y286396D03*
X511592Y292245D03*
X484552Y319546D03*
X481172Y333196D03*
X484552Y331247D03*
X514972Y282496D03*
X521731D03*
X518352Y284447D03*
X538631Y307847D03*
Y303947D03*
Y300047D03*
X535251Y298096D03*
Y305896D03*
X538631Y296147D03*
X531871D03*
X535251Y317596D03*
X525111Y315647D03*
X531871D03*
X535251Y313696D03*
X538631Y315647D03*
X528491Y282496D03*
X535251Y286396D03*
Y282496D03*
X504832Y300045D03*
Y303947D03*
Y311747D03*
X508212Y301996D03*
Y305896D03*
X494692Y294196D03*
X501452Y290296D03*
Y282496D03*
X491312Y292245D03*
Y300047D03*
X508212Y290296D03*
Y294196D03*
X511592Y307847D03*
Y284447D03*
X481172Y309797D03*
X494692D03*
X481172Y301996D03*
X487932Y309797D03*
X498072Y303947D03*
X487932Y286396D03*
X481172Y298096D03*
X487932Y282496D03*
X481172Y305896D03*
X487932Y290296D03*
X484552Y288347D03*
Y296147D03*
X481172Y294196D03*
X508212Y309797D03*
X511592Y300047D03*
Y288347D03*
X494692Y305896D03*
X491312Y311747D03*
X501452Y301996D03*
X491312Y307847D03*
X498072Y311747D03*
X511592Y296147D03*
X501452Y294196D03*
X498072Y296147D03*
X504832D03*
X508212Y298096D03*
X498072Y300047D03*
X484552Y307847D03*
Y300047D03*
Y292245D03*
X494692Y286396D03*
X501452Y298096D03*
X481172Y290296D03*
X508212Y329296D03*
X487932Y317596D03*
X504832Y319547D03*
X484552Y323446D03*
X508212Y317596D03*
Y325396D03*
X491312Y339047D03*
X494692Y337096D03*
X511592Y327347D03*
Y339047D03*
Y331247D03*
Y335147D03*
Y315647D03*
Y323446D03*
X508212Y340996D03*
X498072Y339047D03*
X504832Y327347D03*
X508212Y321496D03*
X481172Y329296D03*
X491312Y323446D03*
X501452Y313696D03*
X508212D03*
X481172D03*
X494692Y340996D03*
Y313696D03*
X501452Y329296D03*
X487932Y340996D03*
Y329296D03*
X494692D03*
X491312Y327347D03*
X498072Y331247D03*
X484552Y335147D03*
X481172Y337096D03*
X501452Y321496D03*
X481172Y340996D03*
X484552Y339047D03*
X487932Y337096D03*
Y333196D03*
X491312Y335147D03*
X494692Y333196D03*
X498072Y335147D03*
X491312Y319547D03*
X494692Y321496D03*
X501452Y317596D03*
X498072Y315647D03*
Y323446D03*
X494692Y325396D03*
X501452D03*
X494692Y317596D03*
X487932Y321496D03*
X484552Y327347D03*
X487932Y325396D03*
X504832Y331247D03*
X508212Y337096D03*
Y333196D03*
X504832Y335147D03*
X501452Y333196D03*
X504832Y339047D03*
X501452Y340996D03*
X504832Y315647D03*
X498072Y319547D03*
X504832Y323446D03*
X498072Y327347D03*
X491312Y331247D03*
X511592Y319547D03*
X538631Y311747D03*
X535251Y290296D03*
X514972Y305896D03*
Y309797D03*
X528491Y301996D03*
Y309797D03*
X525111Y311747D03*
Y307847D03*
Y303947D03*
X521731Y305896D03*
Y309797D03*
X518352Y307847D03*
X514972Y298096D03*
X518352Y292245D03*
Y288347D03*
X521731Y286396D03*
Y290296D03*
Y298096D03*
X525111Y292245D03*
Y296147D03*
X528491Y290296D03*
X525111Y288347D03*
X521731Y294196D03*
X518352Y300047D03*
Y296147D03*
X514972Y301996D03*
Y290296D03*
Y286396D03*
Y294196D03*
X525111Y284447D03*
X531871Y288347D03*
Y292245D03*
X528491Y294196D03*
X525111Y300047D03*
X531871D03*
X521731Y301996D03*
X528491Y286396D03*
Y298096D03*
X535251Y294196D03*
X538631Y292245D03*
Y288347D03*
Y284447D03*
X531871Y303947D03*
X535251Y301996D03*
X531871Y311747D03*
Y307847D03*
X535251Y309797D03*
X514972Y333196D03*
Y321496D03*
Y317596D03*
Y329296D03*
Y325396D03*
Y337096D03*
X518352Y319547D03*
X514972Y313696D03*
X528491D03*
X521731D03*
X518352Y323446D03*
Y315647D03*
X521731Y317596D03*
Y325396D03*
X518352Y327347D03*
Y339047D03*
X531871Y335147D03*
X525111D03*
X528491Y337096D03*
X531871Y327347D03*
X535251Y329296D03*
X538631Y335147D03*
Y339047D03*
X528491Y317596D03*
X531871Y319547D03*
X535251Y321496D03*
X538631Y319547D03*
X514972Y340996D03*
X518352Y331247D03*
X521731Y321496D03*
X525111Y339047D03*
X535251Y333196D03*
Y325396D03*
X484552Y315647D03*
X481172Y282496D03*
X518352Y303947D03*
X531871Y284447D03*
X484552D03*
Y342947D03*
X481172Y364396D03*
Y383896D03*
X535251Y376096D03*
X518352Y401447D03*
X504832Y385847D03*
Y393647D03*
X508212Y376096D03*
X498072Y370247D03*
X504832D03*
X501452Y372197D03*
X504832Y342947D03*
X491312Y370247D03*
X498072Y366347D03*
X494692Y372197D03*
X504832Y366347D03*
X501452Y368296D03*
X487932D03*
X484552Y362447D03*
X498072D03*
X491312D03*
X494692Y360496D03*
X487932D03*
X501452Y344896D03*
X504832Y354647D03*
X494692Y344896D03*
Y348796D03*
X491312Y350747D03*
X508212Y344896D03*
Y348796D03*
X511592Y346847D03*
Y350747D03*
Y342947D03*
X504832Y362447D03*
X494692Y368296D03*
Y352696D03*
X508212Y356596D03*
X504832Y350747D03*
X491312Y366347D03*
X487932Y372197D03*
X484552Y370247D03*
X481172Y372197D03*
X484552Y366347D03*
X487932Y364396D03*
X494692D03*
X501452D03*
X491312Y358547D03*
X498072Y350747D03*
Y346847D03*
X501452Y360496D03*
X498072Y342947D03*
X487932Y348796D03*
X481172Y356596D03*
X484552Y358547D03*
Y350747D03*
Y354647D03*
X487932Y352696D03*
Y344896D03*
X491312Y346847D03*
X494692Y356596D03*
X498072Y358547D03*
Y354647D03*
X481172Y344896D03*
Y360496D03*
X484552Y346847D03*
X508212Y352696D03*
Y360496D03*
X504832Y346847D03*
Y358547D03*
X501452Y356596D03*
Y348796D03*
Y352696D03*
X511592Y370247D03*
X481172Y352696D03*
X484552Y393647D03*
X481172Y391696D03*
X484552Y385847D03*
X498072Y393647D03*
X494692Y391696D03*
X491312Y385847D03*
X498072D03*
X508212Y387796D03*
X501452Y391696D03*
Y395597D03*
X491312Y389747D03*
X504832Y381947D03*
Y378047D03*
X501452Y379996D03*
X481172Y395596D03*
X511592Y378047D03*
Y397546D03*
X491312Y378047D03*
X484552D03*
X481172Y379996D03*
X487932Y376096D03*
X491312Y381947D03*
X511592Y374146D03*
X501452Y383896D03*
X498072Y389747D03*
X494692Y376096D03*
X508212Y379996D03*
X491312Y374146D03*
X498072Y397546D03*
X487932Y403396D03*
Y399496D03*
X491312Y397546D03*
X487932Y395597D03*
X521731Y368296D03*
X518352Y366347D03*
X514972Y372197D03*
Y356596D03*
X521731Y360496D03*
Y356596D03*
Y348796D03*
X518352Y342947D03*
Y362447D03*
X521731Y372197D03*
X518352Y370247D03*
X525111Y354647D03*
X531871Y346847D03*
X535251Y356596D03*
X538631Y366347D03*
X528491Y364396D03*
X525111Y342947D03*
X514972Y348796D03*
Y344896D03*
Y352696D03*
X518352Y358547D03*
X521731Y344896D03*
X538631Y370247D03*
X525111Y350747D03*
Y370247D03*
X531871D03*
X525111Y362447D03*
X528491Y360496D03*
Y356596D03*
X525111Y366347D03*
X528491Y368296D03*
X521731Y364396D03*
X525111Y358547D03*
X531871Y354647D03*
X528491Y372197D03*
X525111Y378047D03*
Y374146D03*
X521731Y376096D03*
X514972Y403396D03*
Y379996D03*
X531871Y374146D03*
X521731Y399496D03*
X518352Y397546D03*
Y389747D03*
X535251Y383896D03*
X525111Y381947D03*
X538631Y393647D03*
Y378047D03*
X528491Y403396D03*
X531871Y401447D03*
Y389747D03*
X525111Y393647D03*
X514972Y399496D03*
X538631Y381947D03*
X531871Y385847D03*
X528491Y391696D03*
X525111Y397546D03*
X481172Y348796D03*
X535251Y395597D03*
Y387796D03*
Y391696D03*
Y352696D03*
X531871Y350747D03*
Y397546D03*
X528491Y399496D03*
X521731Y403396D03*
X538631Y385847D03*
Y389747D03*
X531871Y393647D03*
X535251Y399496D03*
X528491Y395597D03*
X525111Y401447D03*
X518352Y374146D03*
X521731Y379996D03*
X514972Y383896D03*
X511592Y381947D03*
X508212Y391696D03*
X504832Y389747D03*
X508212Y395597D03*
X518352Y378047D03*
Y381947D03*
Y385847D03*
X511592D03*
X501452Y387796D03*
X511592Y393647D03*
X504832Y397546D03*
X481172Y376096D03*
Y368296D03*
X487932Y387796D03*
Y391696D03*
Y379996D03*
X491312Y401447D03*
X481172Y387796D03*
X494692Y395597D03*
X484552Y381947D03*
X518352Y405347D03*
X484552D03*
X538750Y406200D03*
X531871Y405347D03*
X525111D03*
X511712Y495800D03*
X488384Y495887D03*
X494777D03*
X491380Y493744D03*
X506644Y490867D03*
X501560D03*
X497723Y493494D03*
X506620Y510100D03*
X506644Y518114D03*
X501544Y510098D03*
X485037Y515814D03*
X481691Y510114D03*
X491380Y515714D03*
X511809Y510114D03*
X497723Y515814D03*
X494927Y510114D03*
X488384D03*
X501520Y517900D03*
X506644Y498867D03*
X501560D03*
X514755Y491044D03*
X521048Y491144D03*
X538370Y490609D03*
X528241Y490944D03*
X534534Y490794D03*
X515155Y515814D03*
X530792Y495787D03*
X524595D03*
X517892Y495800D03*
X534534Y515814D03*
X528191Y515714D03*
X531738Y510114D03*
X525195D03*
X538355Y510098D03*
X538331Y517900D03*
X521848Y515814D03*
X518502Y510114D03*
X538370Y498609D03*
Y495909D03*
X538355Y515300D03*
X501544Y512700D03*
X506644Y512914D03*
X501544Y515300D03*
X528241Y513114D03*
X525195Y518157D03*
X534534Y513114D03*
X531888Y518157D03*
X515155Y513114D03*
X511809Y518157D03*
X491430Y513114D03*
X488384Y518157D03*
X521848Y513114D03*
X518502Y518157D03*
X497723Y513114D03*
X495077Y518157D03*
X485037Y513114D03*
X481691Y518157D03*
X506644Y496167D03*
X538370Y493209D03*
X501560Y493467D03*
X506644Y493567D03*
X501560Y496167D03*
X528191Y493544D03*
X524595Y498387D03*
X534534Y493394D03*
X530792Y498387D03*
X514755Y493744D03*
X511809Y498487D03*
X491430Y491144D03*
X488384Y498487D03*
X521048Y493844D03*
X517902Y498487D03*
X497723Y490894D03*
X494777Y498487D03*
X506644Y515514D03*
X538355Y512700D03*
X506670Y536750D03*
X501570Y529150D03*
X506657Y528936D03*
X501544Y536999D03*
X511809Y547914D03*
Y537049D03*
X491380Y553514D03*
X497723Y553614D03*
X485037D03*
X506620Y547900D03*
X501544Y547898D03*
X481691Y547914D03*
X494927D03*
X488384D03*
X481691Y537049D03*
X491344Y530949D03*
X488384Y536999D03*
X495077Y537049D03*
X497723Y531100D03*
X485037Y530949D03*
Y568749D03*
X481691Y574849D03*
Y585714D03*
X501544Y585698D03*
Y574799D03*
X506657Y566736D03*
X501570Y566950D03*
X506670Y574550D03*
X506620Y585700D03*
X488384Y585714D03*
X511809D03*
Y574849D03*
X494927Y585714D03*
X491344Y568749D03*
X501520Y555700D03*
X506644Y555914D03*
X497723Y568900D03*
X488384Y574799D03*
X495077Y574849D03*
X515155Y553614D03*
Y530949D03*
X534534Y531100D03*
X531888Y537049D03*
X528155Y530949D03*
X525195Y536999D03*
X538355D03*
X538381Y529150D03*
X525195Y547914D03*
X531738D03*
X538355Y547898D03*
X534534Y553614D03*
X528191Y553514D03*
X518502Y547914D03*
X521848Y553614D03*
X518502Y537049D03*
X521848Y530949D03*
X515155Y568749D03*
X538331Y555700D03*
X518502Y585714D03*
Y574849D03*
X521848Y568749D03*
X538355Y585698D03*
Y574799D03*
X538381Y566950D03*
X531738Y585714D03*
X525195D03*
X534534Y568900D03*
X525195Y574799D03*
X528155Y568749D03*
X531888Y574849D03*
X538355Y553100D03*
X538381Y531750D03*
X538355Y534399D03*
X501544D03*
X506644Y534149D03*
X501570Y531750D03*
X525195Y528899D03*
X528155Y534700D03*
X531888Y528899D03*
X534534Y534700D03*
X511809Y528899D03*
X515155Y535100D03*
X488384Y528899D03*
X491344Y534700D03*
X518502Y528899D03*
X521848Y535100D03*
X495077Y528899D03*
X497723Y534700D03*
X481691Y528899D03*
X485037Y535100D03*
X506644Y553314D03*
X538355Y550500D03*
X501544D03*
X506644Y550714D03*
X501544Y553100D03*
X528241Y550914D03*
X525195Y555957D03*
X534534Y550914D03*
X531888Y555957D03*
X515155Y550914D03*
X511809Y555957D03*
X491430Y550914D03*
X488384Y555957D03*
X521848Y550914D03*
X518502Y555957D03*
X497723Y550914D03*
X495077Y555957D03*
X485037Y550914D03*
X481691Y555957D03*
X497723Y588714D03*
X485037D03*
X506644Y569340D03*
X538355Y572199D03*
X501544D03*
X525195Y566699D03*
X528155Y572500D03*
X531888Y566699D03*
X534534Y572500D03*
X511809Y566699D03*
X515155Y572900D03*
X488384Y566699D03*
X491344Y572500D03*
X518502Y566699D03*
X521848Y572900D03*
X495077Y566699D03*
X497723Y572500D03*
X481691Y566699D03*
X485037Y572900D03*
X538355Y588300D03*
X501544D03*
X506644Y588514D03*
X528241Y588714D03*
X534534D03*
X515155D03*
X491430D03*
X521848D03*
X538381Y569550D03*
X506644Y531540D03*
Y571949D03*
X501570Y569550D03*
X525195Y612599D03*
X518502Y612649D03*
X538355Y612599D03*
X531888Y612649D03*
X501544Y612599D03*
X495077Y612649D03*
X488384Y612599D03*
X511809Y612649D03*
X497723Y591414D03*
X486250Y591020D03*
X491380Y591314D03*
X501520Y593500D03*
X506644Y593714D03*
X501570Y604750D03*
X506657Y604536D03*
X491344Y606549D03*
X497723Y606700D03*
X485037Y607230D03*
X506670Y612350D03*
X480950Y612430D03*
X515155Y606549D03*
Y591414D03*
X521848D03*
Y606549D03*
X534534Y591414D03*
X528191Y591314D03*
X538331Y593500D03*
X538381Y604750D03*
X534534Y606700D03*
X528155Y606549D03*
X538355Y590900D03*
X521848Y610700D03*
X495077Y604499D03*
Y593757D03*
X498092Y611200D03*
X481691Y604499D03*
Y593757D03*
X485037Y610700D03*
X506644Y591114D03*
Y607140D03*
X538355Y609999D03*
X501544D03*
Y590900D03*
X525195Y604499D03*
Y593757D03*
X531888Y604499D03*
X534534Y610300D03*
X531888Y593757D03*
X511809Y604499D03*
X515155Y610700D03*
X511809Y593757D03*
X488384Y604499D03*
Y593757D03*
X491724Y611668D03*
X518502Y604499D03*
Y593757D03*
X538381Y607350D03*
X506644Y609749D03*
X501570Y607350D03*
X528155Y610300D03*
X562006Y9114D03*
X568549D03*
X555313D03*
X548620D03*
X571345Y-7700D03*
X551966Y-7851D03*
X564966D03*
X558659D03*
X562006Y-1801D03*
X555313Y-1751D03*
X568699D03*
X548620D03*
X543503Y-2000D03*
X543468Y-9864D03*
X558659Y-3700D03*
X555313Y-9901D03*
X551966Y-3700D03*
X548620Y-9901D03*
X571345Y-4100D03*
X568699Y-9901D03*
X564966Y-4100D03*
X562006Y-9901D03*
X543455Y-7260D03*
Y-4651D03*
Y17114D03*
X564992Y14714D03*
X555313Y27899D03*
X548620D03*
X571345Y33700D03*
X568699Y27899D03*
X564966Y33700D03*
X562006Y27899D03*
X543455Y33149D03*
Y30540D03*
X555313Y17157D03*
X558659Y12114D03*
X548620Y17157D03*
X551966Y12114D03*
X568699Y17157D03*
X571345Y12114D03*
X561868Y17019D03*
X565052Y12114D03*
X543455Y14514D03*
Y11914D03*
X543415Y9300D03*
X558659Y14814D03*
Y29949D03*
X551966Y14814D03*
Y29949D03*
X564966D03*
X571345Y14814D03*
Y30100D03*
X543468Y27936D03*
X575166Y9098D03*
X595470Y-3700D03*
X592124Y-9901D03*
X588777Y-3700D03*
X585431Y-9901D03*
X575192Y-7050D03*
X580266Y-7260D03*
Y-4651D03*
X602163Y-1743D03*
Y9157D03*
Y16999D03*
X592124Y27899D03*
X585431D03*
X575192Y30750D03*
X575166Y33399D03*
X580266Y33149D03*
X592124Y17157D03*
X595470Y12114D03*
X585431Y17157D03*
X588777Y12114D03*
X575166Y14300D03*
X575214Y-9700D03*
X575166Y-1801D03*
X580279Y-9864D03*
X580314Y-2000D03*
X588777Y-7851D03*
X598817Y-9901D03*
X595470Y-7851D03*
X592124Y-1751D03*
X598817D03*
X585431D03*
X602163Y-9901D03*
X598817Y9157D03*
X592124Y9114D03*
X585431D03*
X580266Y14514D03*
X575166Y11700D03*
X580266Y11914D03*
X598817Y17057D03*
X602163Y27899D03*
X575182Y16900D03*
X575192Y28100D03*
X580192Y9300D03*
X588777Y29949D03*
X580279Y27936D03*
X595470Y29949D03*
Y14814D03*
X598817Y27899D03*
X588777Y14814D03*
X580266Y17114D03*
X575166Y-4401D03*
X580266Y30540D03*
X562006Y46914D03*
X555313Y65699D03*
X548620D03*
X568699D03*
X562006D03*
X543455Y68340D03*
X558659Y34100D03*
X555313Y54957D03*
X558659Y49914D03*
X551966Y34100D03*
X548620Y54957D03*
X551966Y49914D03*
X568699Y54957D03*
X571345Y49914D03*
X562006Y54957D03*
X565052Y49914D03*
X543455Y49714D03*
Y52314D03*
X551966Y52614D03*
X565352Y52864D03*
X548620Y46914D03*
Y36049D03*
X558659Y52614D03*
X568699Y36049D03*
X555313D03*
X562006Y35999D03*
X551966Y67749D03*
X564966D03*
X571345Y52614D03*
Y67900D03*
X558659Y67749D03*
X568549Y46914D03*
X555313D03*
X565266Y87374D03*
X543455Y70949D03*
X543468Y65736D03*
X543404Y47000D03*
X543415Y35800D03*
X543455Y54914D03*
Y87514D03*
Y90114D03*
Y92714D03*
X548620Y84714D03*
X568549D03*
X555313D03*
X562006D03*
X543481Y73550D03*
X543431Y84700D03*
X548620Y73849D03*
X568699D03*
X562006Y73799D03*
X555313Y73849D03*
X558659Y90414D03*
X551966D03*
X571345D03*
X558659Y71900D03*
X555313Y92757D03*
X558659Y87714D03*
X551966Y71900D03*
X548620Y92757D03*
X551966Y87714D03*
X571345Y71500D03*
X568699Y92757D03*
X571345Y87714D03*
X564966Y71500D03*
X562006Y92757D03*
X592124Y65699D03*
X585431D03*
X575192Y68550D03*
X580266Y68340D03*
X592124Y54957D03*
X595470Y34100D03*
Y49914D03*
X585431Y54957D03*
X588777Y34100D03*
Y49914D03*
X575166Y52100D03*
X580266Y52314D03*
X575166Y49500D03*
X580266Y49714D03*
X598817Y54857D03*
X602163Y46957D03*
Y54799D03*
Y36057D03*
X575166Y46898D03*
Y35999D03*
X575192Y65950D03*
X585431Y46914D03*
X595470Y52614D03*
X588777D03*
X585431Y36049D03*
X592124D03*
X598817D03*
Y46957D03*
X592124Y46914D03*
X598817Y65699D03*
X595470Y67749D03*
X588777D03*
X580266Y54914D03*
X580192Y35750D03*
X580279Y65736D03*
X602163Y65699D03*
X592124Y84714D03*
X585431D03*
X598817Y84757D03*
X580242Y84700D03*
X580266Y92714D03*
X588777Y90414D03*
X602163Y92599D03*
X595470Y71900D03*
X592124Y92757D03*
X595470Y87714D03*
X588777Y71900D03*
X585431Y92757D03*
X588777Y87714D03*
X575166Y89900D03*
X580266Y70949D03*
Y87514D03*
X575166Y71199D03*
Y87300D03*
X580266Y90114D03*
X598817Y92657D03*
X602163Y84757D03*
Y73857D03*
X575166Y73799D03*
X575142Y92500D03*
X575166Y84698D03*
X595470Y90414D03*
X585431Y73849D03*
X592124D03*
X598817D03*
X580292Y73550D03*
X555313Y112357D03*
X558659Y107314D03*
X548620Y112357D03*
X551966Y107314D03*
X543455Y107655D03*
X543481Y110264D03*
X548620Y104314D03*
X555313D03*
X558659Y110014D03*
X551966D03*
X543481Y112865D03*
X543468Y105051D03*
X602100Y109600D03*
X566051Y211555D03*
X562861Y205503D03*
X545391Y214247D03*
Y218147D03*
X548771Y216196D03*
X542011Y212296D03*
X555531Y216196D03*
X557000Y206800D03*
X548771Y212296D03*
X552151Y214247D03*
X547800Y201400D03*
X545391Y210346D03*
X558911Y218147D03*
X542011Y208396D03*
X563900Y213500D03*
X560739Y207625D03*
X552151Y218147D03*
X590500Y215800D03*
Y213000D03*
X599773Y199596D03*
X600286Y202921D03*
X577375Y204125D03*
X542011Y216196D03*
X579497Y202003D03*
X578980Y217884D03*
X552151Y237647D03*
X542011Y231797D03*
X548771D03*
X552151Y280547D03*
X548771Y274696D03*
Y220096D03*
X555531D03*
Y227896D03*
X542011Y278596D03*
Y262996D03*
X555531Y270796D03*
X552151Y264947D03*
X542011Y259096D03*
X545391Y257147D03*
Y249347D03*
X548771Y223996D03*
X542011Y243496D03*
X552151Y222047D03*
X562616Y223996D03*
X542011Y251296D03*
X545391Y245447D03*
X555531Y243496D03*
Y259096D03*
X552151Y253247D03*
X548771Y259096D03*
X562640Y231735D03*
X542011Y220096D03*
X552151Y225947D03*
X558911Y222047D03*
X552151Y233746D03*
X548771Y235696D03*
X558911Y229847D03*
X552151D03*
X562591Y220096D03*
X564084Y235685D03*
X545391Y225947D03*
Y222047D03*
Y233746D03*
X542011Y239596D03*
Y247396D03*
X552151Y241547D03*
X548771Y239596D03*
X552151Y249347D03*
X570400Y243500D03*
X555531Y231797D03*
X548771Y227896D03*
X552151Y245447D03*
X548771Y251296D03*
X542011Y223996D03*
X545391Y237647D03*
X555531Y247396D03*
X562591Y251296D03*
X548771Y243496D03*
X562591D03*
X572930Y232750D03*
Y228130D03*
X552151Y257147D03*
X562591Y255196D03*
X548771D03*
X573200Y262600D03*
X573100Y258600D03*
X548771Y266896D03*
X558911Y264947D03*
X563800Y275900D03*
X559211Y280547D03*
X548771Y278596D03*
X558911Y272747D03*
X555531Y274696D03*
X564500Y264800D03*
Y268800D03*
X552151Y261047D03*
X545391Y272747D03*
Y280547D03*
Y264947D03*
Y268847D03*
X542011Y274696D03*
X548771Y270796D03*
Y262996D03*
X545391Y276646D03*
X542011Y270796D03*
X600400Y226800D03*
X580360Y234590D03*
Y230060D03*
X581102Y220006D03*
X542011Y227896D03*
X545391Y229847D03*
X558911Y253247D03*
X548771Y247396D03*
X545391Y241547D03*
X562630Y227896D03*
X555531Y223996D03*
X542011Y235696D03*
X552151Y272747D03*
X566926Y268055D03*
X555531Y262996D03*
X558911Y225947D03*
X575600Y261800D03*
X555531Y251296D03*
X565124Y243496D03*
X558911Y241547D03*
X577849Y231119D03*
X545391Y261047D03*
X555531Y255196D03*
X545391Y253247D03*
X558911Y268847D03*
X570404Y229015D03*
X577832Y233729D03*
X558911Y249347D03*
X570528Y231543D03*
X567868Y243482D03*
X566926Y265555D03*
X552151Y276646D03*
X555531Y266896D03*
X558911Y257147D03*
X555531Y278596D03*
X552151Y268847D03*
X542011Y255196D03*
Y266896D03*
X575600Y259300D03*
X592300Y220500D03*
X548771Y305896D03*
X552151Y300047D03*
X548771Y301996D03*
X552151Y307847D03*
Y303947D03*
X555831Y301996D03*
X548771Y298096D03*
X542011Y317596D03*
Y309797D03*
X545391Y311747D03*
X542011Y305896D03*
Y301996D03*
X552151Y311747D03*
X542011Y313696D03*
X548771Y321496D03*
X545391Y323446D03*
X552151Y319547D03*
Y315647D03*
X559211Y331103D03*
X555531Y329296D03*
X559211Y323446D03*
X555531Y321496D03*
X548771Y317596D03*
X555831Y313696D03*
X559211Y327347D03*
X552151D03*
X555531Y325396D03*
X555831Y317446D03*
X552151Y292245D03*
X559211Y284447D03*
X542011Y290296D03*
X560884D03*
X542011Y282496D03*
X545391Y307847D03*
X555831Y309797D03*
Y305896D03*
X548771Y309797D03*
X555831Y298096D03*
X552151Y284447D03*
X548771Y286396D03*
X552151Y288347D03*
Y296147D03*
X558145Y286727D03*
X545391Y296147D03*
Y288347D03*
Y292245D03*
Y300047D03*
X542011Y294196D03*
Y298096D03*
X545391Y303947D03*
X548771Y282496D03*
Y290296D03*
Y294196D03*
Y337096D03*
Y313696D03*
X561971Y317320D03*
X548771Y325396D03*
X558911Y335147D03*
X555531Y333196D03*
X562591D03*
X548771Y340996D03*
X561966Y325502D03*
X559211Y319547D03*
X552151Y323446D03*
X545391Y319547D03*
X542011Y321496D03*
X545391Y335147D03*
Y331247D03*
Y315647D03*
X548771Y329296D03*
X560884Y286396D03*
X545391Y284447D03*
X555531Y282496D03*
X555831Y294196D03*
X542011Y286396D03*
X545391Y389747D03*
X542011Y391696D03*
Y395597D03*
Y387796D03*
X545391Y393647D03*
X552151Y366347D03*
Y370247D03*
X563500Y360500D03*
X555531Y372197D03*
X548771Y364396D03*
X552151Y393647D03*
X559212Y389747D03*
X548990Y403670D03*
X555750Y399770D03*
X552151Y350747D03*
X558911Y342947D03*
X562591Y348796D03*
X559212Y370247D03*
X548771Y368296D03*
X562591Y352696D03*
Y344896D03*
X563200Y356596D03*
X545391Y354647D03*
Y346847D03*
X542011Y368296D03*
X545391Y366347D03*
Y358547D03*
X542011Y360496D03*
Y348796D03*
Y364396D03*
Y372197D03*
Y352696D03*
X545391Y342947D03*
X548771Y372196D03*
X545391Y362447D03*
Y378047D03*
X552151Y374146D03*
X548771Y376096D03*
X559212Y374146D03*
X555531Y387797D03*
X559212Y381947D03*
Y393647D03*
X552151Y378047D03*
X545391Y397546D03*
Y385847D03*
X542011Y376096D03*
X559212Y385847D03*
X542011Y383896D03*
X545391Y374146D03*
X548771Y360496D03*
Y356596D03*
X542011Y379996D03*
X548771Y383896D03*
X545391Y370247D03*
X552151Y358547D03*
X548771Y352696D03*
X545391Y381947D03*
X548771Y379996D03*
X573867Y459903D03*
X575614Y461694D03*
X584076Y443828D03*
X588285Y448306D03*
X586136Y446335D03*
X592216Y445152D03*
X595070Y447970D03*
X558659Y493444D03*
X551366Y490744D03*
X543455Y490909D03*
X555313Y510114D03*
X548492Y495800D03*
X554792Y495887D03*
X543431Y510100D03*
X543455Y518114D03*
X551966Y515814D03*
X548620Y510114D03*
X543455Y498909D03*
X568549Y510114D03*
X562006D03*
X571345Y515814D03*
X558659D03*
X582912Y468948D03*
X581032Y467202D03*
X575166Y510098D03*
X575142Y517900D03*
X580266Y518114D03*
X580242Y510100D03*
X598817Y510157D03*
X595470Y515814D03*
X588777D03*
X602163Y517999D03*
X592124Y510114D03*
X585431D03*
X598817Y518057D03*
X602163Y510157D03*
X562006Y518157D03*
X595470Y513114D03*
X592124Y518157D03*
X571345Y513114D03*
X568699Y518157D03*
X551966Y513114D03*
X548620Y518157D03*
X558659Y513114D03*
X555313Y518157D03*
X543455Y496209D03*
Y493509D03*
X551366Y493344D03*
X548492Y498400D03*
X558659Y496144D03*
X554792Y498487D03*
X580266Y515514D03*
X543455D03*
X575166Y512700D03*
X580266Y512914D03*
X543455D03*
X575166Y515300D03*
X588777Y513114D03*
X585431Y518157D03*
X565266Y512774D03*
X543468Y528936D03*
X543481Y536750D03*
X543431Y547900D03*
X548620Y547914D03*
X551966Y553614D03*
X548620Y537049D03*
X551966Y530949D03*
X558659D03*
X555313Y537049D03*
X562006Y536999D03*
X564966Y530949D03*
X568699Y537049D03*
X571345Y553614D03*
Y531100D03*
X558659Y553614D03*
X555313Y547914D03*
X568549D03*
X562006D03*
X543455Y555914D03*
X571345Y568900D03*
X564966Y568749D03*
X562006Y574799D03*
X555313Y585714D03*
Y574849D03*
X558659Y568749D03*
X568549Y585714D03*
X562006D03*
X568699Y574849D03*
X551966Y568749D03*
X548620Y574849D03*
Y585714D03*
X543481Y574550D03*
X543431Y585700D03*
X543468Y566736D03*
X575166Y547898D03*
X575192Y529150D03*
X575166Y536999D03*
X598817Y547957D03*
X592124Y547914D03*
X595470Y530949D03*
X580242Y547900D03*
X580279Y528936D03*
X580292Y536750D03*
X592124Y537049D03*
X588777Y530949D03*
X598817Y528899D03*
Y537049D03*
X602163Y528899D03*
X585431Y547914D03*
Y537049D03*
X588777Y553614D03*
X595470D03*
X602163Y547957D03*
Y537057D03*
X580279Y566736D03*
X585431Y574849D03*
Y585714D03*
X598817Y585757D03*
Y574849D03*
Y566699D03*
X592124Y585714D03*
X595470Y568749D03*
X588777D03*
X592124Y574849D03*
X602163Y566699D03*
X598817Y555857D03*
X602163Y555799D03*
Y574857D03*
Y585757D03*
X575142Y555700D03*
X575192Y566950D03*
X575166Y585698D03*
Y574799D03*
X580266Y555914D03*
X580292Y574550D03*
X580242Y585700D03*
X562006Y528899D03*
X564966Y534700D03*
X592124Y528899D03*
X595470Y535100D03*
X568699Y528899D03*
X571345Y534700D03*
X548620Y528899D03*
X551966Y535100D03*
X555313Y528899D03*
X558659Y535100D03*
X580266Y553314D03*
X543455D03*
X575166Y550500D03*
X580266Y550714D03*
X543455D03*
X575166Y553100D03*
X588777Y550914D03*
X585431Y555957D03*
X565266Y550574D03*
X562006Y555957D03*
X595470Y550914D03*
X592124Y555957D03*
X571345Y550914D03*
X568699Y555957D03*
X551966Y550914D03*
X548620Y555957D03*
X558659Y550914D03*
X555313Y555957D03*
X580266Y531540D03*
X543455D03*
X575166Y534399D03*
X543455Y534149D03*
X575192Y531750D03*
X585431Y528899D03*
X588777Y535100D03*
X558659Y572900D03*
X575166Y588300D03*
X580266Y588514D03*
X543455D03*
X588777Y588714D03*
X565052D03*
X595470D03*
X571345D03*
X551966D03*
X558659D03*
X580266Y569340D03*
X575166Y572199D03*
X580266Y571949D03*
X543455D03*
X585431Y566699D03*
X588777Y572900D03*
X562006Y566699D03*
X564966Y572500D03*
X592124Y566699D03*
X595470Y572900D03*
X568699Y566699D03*
X571345Y572500D03*
X548620Y566699D03*
X551966Y572900D03*
X555313Y566699D03*
X580266Y534149D03*
X543455Y569340D03*
X575192Y569550D03*
X575166Y612599D03*
X585431Y612649D03*
X592124D03*
X598817D03*
X602163Y612657D03*
X555313Y612649D03*
X562006Y612599D03*
X568699Y612649D03*
X548620D03*
X571345Y591414D03*
X558659D03*
X571345Y606700D03*
X558659Y606549D03*
X564966D03*
X551966D03*
Y591414D03*
X543455Y593714D03*
X543468Y604536D03*
X543481Y612350D03*
X580292D03*
X580266Y593714D03*
X595470Y591414D03*
X588777D03*
X598817Y604499D03*
X595470Y606549D03*
X588777D03*
X598817Y593657D03*
X575192Y604750D03*
X575142Y593500D03*
X602163Y593599D03*
Y604499D03*
X580279Y604536D03*
X580266Y591114D03*
Y607140D03*
X543455Y591114D03*
Y607140D03*
X575166Y609999D03*
Y590900D03*
X585431Y604499D03*
Y593757D03*
X588777Y610700D03*
X562006Y604499D03*
Y593757D03*
X592124Y604499D03*
Y593757D03*
X595470Y610700D03*
X568699Y604499D03*
X571345Y610300D03*
X568699Y593757D03*
X548620Y604499D03*
X551966Y610700D03*
X548620Y593757D03*
X555313Y604499D03*
X558659Y610700D03*
X555313Y593757D03*
X580266Y609749D03*
X543455D03*
X575192Y607350D03*
X564966Y610300D03*
X608856Y-9901D03*
X612203D03*
X608856Y-1743D03*
X612203D03*
X615549D03*
Y9157D03*
X608856D03*
X612203D03*
X615549Y-9901D03*
X623000Y-3000D03*
X624770Y-640D03*
X620092Y13078D03*
X620192Y31978D03*
Y-5822D03*
X612203Y16999D03*
X608856D03*
X612203Y27899D03*
X608856D03*
X615549D03*
Y16999D03*
X647317Y-1310D03*
X660676Y-2600D03*
X656807Y-20652D03*
X657250Y-2050D03*
X663699Y3861D03*
X660000Y-17500D03*
X648550Y8550D03*
X651100Y8650D03*
X662700Y-17900D03*
X651300Y20000D03*
X659200Y31500D03*
X651300Y17500D03*
X661494Y32946D03*
X645430Y31067D03*
X656300Y22800D03*
X653800D03*
X656600Y31500D03*
X663300Y10000D03*
X651100Y11700D03*
X648500Y11600D03*
X648867Y31258D03*
X651442Y31225D03*
X659700Y22900D03*
X654016Y31150D03*
X647400Y-6900D03*
X605510Y27899D03*
Y9157D03*
X647000Y-9500D03*
X605510Y-1743D03*
Y-9901D03*
Y16999D03*
X647000Y-12100D03*
X659747Y-12132D03*
X620070Y50878D03*
X620192Y69778D03*
X612203Y54799D03*
X615549Y46957D03*
X608856Y54799D03*
X612203Y46957D03*
X608856D03*
X615549Y36057D03*
X608856D03*
X612203D03*
X608856Y65699D03*
X612203D03*
X615549D03*
Y54799D03*
X612203Y92599D03*
X608856D03*
X612203Y84757D03*
X608856D03*
X615549D03*
Y73857D03*
X608856D03*
X612203D03*
X615549Y92599D03*
X620092Y88678D03*
X663500Y48000D03*
X663700Y65600D03*
X663476Y45296D03*
X655600Y69100D03*
X658100D03*
X655600Y66100D03*
X658100D03*
X658567Y47639D03*
Y44639D03*
X656067D03*
Y47639D03*
X647600Y84200D03*
X647304Y91882D03*
X650204Y91282D03*
X649200Y88800D03*
Y86300D03*
X656500Y75300D03*
X652500D03*
X650000D03*
X652804Y90482D03*
X659000Y75300D03*
X646200Y86300D03*
Y88800D03*
X644904Y92382D03*
X650000Y72300D03*
X659000D03*
X656500D03*
X652500D03*
X652718Y93881D03*
X662352Y89566D03*
X605510Y92599D03*
Y73857D03*
Y36057D03*
Y46957D03*
Y84757D03*
Y65699D03*
Y54799D03*
X618800Y100100D03*
X616115Y108339D03*
X603163Y103971D03*
X608600Y103000D03*
X620054Y114096D03*
X633800Y119000D03*
X609482Y124568D03*
X622200Y112200D03*
X616167Y118627D03*
X605300Y124600D03*
X630000Y126572D03*
X624500Y129400D03*
X626900Y128300D03*
X633580Y125560D03*
X628673Y142718D03*
X632173Y142018D03*
X661700Y142300D03*
X644055Y144493D03*
X642673Y139811D03*
X639173Y140618D03*
X654555Y142193D03*
X651055Y142893D03*
X647555Y143643D03*
X658055Y141493D03*
X635673Y141318D03*
X636481Y124951D03*
X635951Y127419D03*
X661053Y115971D03*
X658490Y115432D03*
X650307Y115518D03*
X647809Y116121D03*
X645311Y116724D03*
X650120Y122700D03*
X660900Y123650D03*
Y126650D03*
X647120Y122700D03*
X657900Y126650D03*
Y123650D03*
X651920Y125750D03*
X656111Y121550D03*
X653111D03*
X654558Y115101D03*
X640043Y117728D03*
X639100Y124200D03*
X638800Y126700D03*
X648690Y125590D03*
X643674Y123573D03*
X644950Y125750D03*
X641950D03*
X642899Y117112D03*
X626040Y98281D03*
X613602Y118047D03*
Y109247D03*
X617400Y115800D03*
X605028Y119000D03*
X604977Y110200D03*
X660600Y170000D03*
X609860Y201356D03*
X613082Y200676D03*
X613773Y196796D03*
X610273Y197496D03*
X606400Y201000D03*
X606773Y198196D03*
X603273Y198896D03*
X613648Y204494D03*
X608648D03*
X604453Y202983D03*
X623648Y209494D03*
Y216994D03*
Y211994D03*
Y214494D03*
X613648Y209494D03*
Y211994D03*
X618648Y209494D03*
Y214494D03*
X621148Y211994D03*
Y216994D03*
X613648Y214494D03*
Y216994D03*
X623648Y206994D03*
X611148D03*
X618648D03*
X621148D03*
X616148D03*
Y211994D03*
Y216994D03*
X644750Y175650D03*
X660600Y175000D03*
X662786Y278084D03*
X660901Y279856D03*
X616148Y221994D03*
X623648Y224494D03*
Y226994D03*
X611148Y224494D03*
X613648D03*
X618648D03*
Y226994D03*
X621148D03*
X616148D03*
X608648D03*
Y224494D03*
X603300Y226700D03*
X613648Y226994D03*
X617235Y247735D03*
X614456Y244956D03*
X632500Y238500D03*
Y235000D03*
X632692Y248172D03*
X632532Y241717D03*
X630200Y248100D03*
X613648Y229494D03*
X621148D03*
X618648D03*
X611148D03*
X623648Y221994D03*
Y219494D03*
X611148Y221994D03*
X618648Y219494D03*
X621148Y221994D03*
X633308Y263808D03*
X621165Y256075D03*
X620850Y253416D03*
X613648Y219494D03*
Y221994D03*
X651235Y249165D03*
X657700Y250172D03*
X660588Y250312D03*
X662800Y248600D03*
X643500Y272262D03*
X654950Y253446D03*
X639320Y268000D03*
X652500Y273600D03*
X647487Y280308D03*
X643591Y266983D03*
X643500Y274868D03*
X642855Y269660D03*
X647469Y277639D03*
X642800Y264000D03*
X643100Y253700D03*
X642800Y261100D03*
X624500Y240500D03*
X627529Y280441D03*
X659900Y256900D03*
Y269200D03*
X606148Y229494D03*
X633410Y269610D03*
Y274610D03*
X656100Y275500D03*
X649800Y252600D03*
X652700Y270600D03*
X618279Y251393D03*
X662238Y296146D03*
X628950Y293550D03*
X654600Y296000D03*
X656042Y287439D03*
X664267Y292668D03*
X661232Y287321D03*
X655000Y284600D03*
X646700Y308850D03*
X652000Y284500D03*
X663200Y298600D03*
X644800Y292150D03*
X654500Y298600D03*
X652100Y288300D03*
X639045Y299555D03*
X639100Y309500D03*
X639622Y290210D03*
X643823Y289650D03*
X658500Y284500D03*
X658853Y294305D03*
X648900Y336600D03*
X646900Y320100D03*
Y317300D03*
X646800Y326100D03*
X646272Y328800D03*
X658900Y339150D03*
X636100Y329800D03*
X649000Y339400D03*
X638790Y329500D03*
X639350Y339980D03*
X639100Y319500D03*
X637143Y322000D03*
X637561Y312000D03*
X637600Y307000D03*
X662200Y284800D03*
X631250Y289650D03*
X628525Y287832D03*
X636799Y285670D03*
X636985Y288264D03*
X634407Y287915D03*
X641665Y281139D03*
X655900Y307700D03*
X656300Y312300D03*
X660700Y307700D03*
X655900Y316500D03*
X656000Y329800D03*
X655900Y320500D03*
X656000Y325100D03*
X660900Y329800D03*
X637561Y317000D03*
X637600Y302000D03*
X632869Y293720D03*
X646520Y297400D03*
X657950Y296850D03*
X637681Y332390D03*
Y337390D03*
X637143Y327000D03*
X664100Y348000D03*
X648800D03*
X658900D03*
X662936Y367171D03*
X659936Y364171D03*
X662936D03*
X654000Y348000D03*
X649600Y391200D03*
X664194Y351206D03*
X654194D03*
X659694D03*
X649194D03*
X609191Y451454D03*
X615300Y457900D03*
X624600Y419400D03*
X626737Y421000D03*
X619800Y416200D03*
X624300Y422100D03*
X627000Y423436D03*
X622900Y424200D03*
X619680Y422600D03*
X625200Y425400D03*
X621800Y421100D03*
X619700Y419500D03*
X634200Y436800D03*
X637300Y437200D03*
X640300Y437600D03*
X620400Y463990D03*
X629600Y425100D03*
X622100Y417900D03*
X608800Y463475D03*
X625430Y490100D03*
X607012Y465997D03*
X623660Y466746D03*
X605249Y480891D03*
X605826Y475894D03*
Y473394D03*
X634967Y470790D03*
X605206Y483291D03*
X618430Y491550D03*
X623400Y476300D03*
X619260Y466610D03*
X629300Y490000D03*
X612000Y484000D03*
X632113Y496892D03*
X619392Y514700D03*
X612515Y498752D03*
X612203Y510157D03*
X608856D03*
X615549D03*
X612203Y517999D03*
X608856D03*
X615549D03*
X623600Y521700D03*
X656900Y482290D03*
X649600Y492400D03*
X660500Y492000D03*
X656100Y486900D03*
X656050Y489500D03*
X637148Y472809D03*
X657227Y479116D03*
X662181Y479149D03*
X659770D03*
X648500Y477400D03*
X659070Y488709D03*
X639197Y490367D03*
X652000Y513900D03*
X655000D03*
X661500D03*
X658500D03*
X658900Y509300D03*
X646200Y499700D03*
X648025Y501575D03*
X609470Y484060D03*
X625569Y481568D03*
X628700Y482000D03*
X653800Y496600D03*
X641150Y484300D03*
X611250Y476750D03*
X605510Y517999D03*
Y510157D03*
X609284Y480055D03*
X618800Y474500D03*
X619390Y469450D03*
X639120Y475620D03*
X608800Y468475D03*
Y473475D03*
X636500Y493924D03*
X627000Y478300D03*
X620192Y532978D03*
X608856Y547957D03*
X615549D03*
X612203D03*
X608856Y528899D03*
X612203D03*
X608856Y537057D03*
X615549D03*
X612203D03*
X615549Y528899D03*
X608856Y566699D03*
X612203D03*
Y555799D03*
X608856D03*
X615549Y574857D03*
X612203D03*
X615549Y585757D03*
X612203D03*
X608856Y574857D03*
Y585757D03*
X615549Y555799D03*
Y566699D03*
X618892Y555800D03*
X618292Y574300D03*
X662640Y528330D03*
X646150Y540350D03*
Y543350D03*
Y546350D03*
X650900Y552500D03*
X657100D03*
X654150Y530200D03*
X651100Y532700D03*
X651150Y530200D03*
X657250Y534300D03*
Y531300D03*
X659750Y534300D03*
Y531300D03*
X654200Y532800D03*
X653700Y552500D03*
X660200D03*
X652140Y577011D03*
Y574511D03*
X660217Y576734D03*
X649700Y574400D03*
X662000Y589000D03*
X651750Y584150D03*
X653100Y587000D03*
X661500Y569800D03*
X658900D03*
X650050Y568623D03*
X647350D03*
X663100Y574200D03*
X644800Y563300D03*
X647800D03*
X650800D03*
X653800D03*
X649700Y577000D03*
X605510Y566699D03*
Y528899D03*
Y555799D03*
Y585757D03*
Y574857D03*
Y537057D03*
Y547957D03*
X608856Y612657D03*
X615549D03*
X612203D03*
X631741Y615759D03*
X655100Y614100D03*
X612203Y604499D03*
X608856D03*
X612203Y593599D03*
X608856D03*
X615549Y604499D03*
Y593599D03*
X618192Y593600D03*
X620033Y608878D03*
X655100Y611500D03*
X644500Y594400D03*
X648180Y590702D03*
X646760Y592992D03*
X660230Y598170D03*
X627705Y611973D03*
X629977Y613024D03*
X605510Y604499D03*
Y612657D03*
Y593599D03*
X718975Y-4451D03*
X713824Y-18333D03*
X665942Y4716D03*
X674300Y9847D03*
X671800D03*
X669300D03*
X673900Y23100D03*
X671400D03*
X668900D03*
X690000Y15300D03*
X683800Y24856D03*
X670430Y29253D03*
X689900Y20800D03*
X692500Y15300D03*
X666100Y10000D03*
X684126Y28137D03*
X681426D03*
X692400Y20800D03*
X679936Y18406D03*
X670400Y26100D03*
X716858Y-14448D03*
X710263Y-14500D03*
X723827Y-14658D03*
X710327Y-11968D03*
X712796Y-16011D03*
X716921Y-6048D03*
X701100Y8100D03*
X704450Y4950D03*
X710800Y7100D03*
X705250Y8600D03*
X717720Y23279D03*
X715114Y26395D03*
X704500Y26300D03*
X723715Y23462D03*
X714823Y23610D03*
X704150Y19650D03*
X708000Y26600D03*
X700500D03*
X701120Y19619D03*
X698470Y19669D03*
X714337Y7852D03*
Y5352D03*
Y2852D03*
X718555Y-16147D03*
X719400Y14300D03*
X711791Y23716D03*
X710107Y-19839D03*
X708330Y-17806D03*
X665396Y23000D03*
X680200Y13100D03*
X714300Y-1900D03*
X724837Y13852D03*
X666500Y48000D03*
X665100Y68600D03*
X668100D03*
X666700Y65600D03*
X684904Y39943D03*
X689500Y37900D03*
X675235Y36797D03*
X685000Y46650D03*
X685100Y43000D03*
X670227Y34277D03*
X690100Y93200D03*
X664471Y86061D03*
X694600Y85000D03*
X693000Y92500D03*
X678020Y69870D03*
X678300Y92630D03*
Y95130D03*
X675630Y94988D03*
X681300Y95130D03*
Y92630D03*
X684300D03*
X687400Y93900D03*
X673830Y83050D03*
X676430D03*
X676500Y80500D03*
X673900D03*
X674010Y77970D03*
X676610D03*
X692200Y83800D03*
X695000Y67000D03*
X699880Y66840D03*
X724200Y64730D03*
X722460Y69550D03*
X713680Y60910D03*
X700360Y72160D03*
X694910Y72220D03*
X713050Y63650D03*
X710440Y63710D03*
X704880Y66750D03*
X697747Y72184D03*
X723700Y67400D03*
X713620Y58270D03*
X715800Y59490D03*
Y57000D03*
X713590Y53260D03*
X713610Y55730D03*
X700640Y69500D03*
X703120Y69380D03*
X702380Y66840D03*
X697440Y66900D03*
X700904Y38439D03*
X723603Y46929D03*
X721141Y46900D03*
X716742Y41062D03*
X713300Y86000D03*
X707329Y88955D03*
X705972Y86660D03*
X716176Y46822D03*
X716700Y43800D03*
X711100Y38700D03*
X714023Y38653D03*
X713674Y46822D03*
X714023Y41053D03*
X716900Y38500D03*
X711100Y41100D03*
X714000Y43900D03*
X722312Y48999D03*
X718600Y46921D03*
X719850Y48970D03*
X699800Y89100D03*
X713830Y82730D03*
X715130Y79574D03*
X697200Y79500D03*
X697100Y90600D03*
X703845Y88830D03*
X716268Y88683D03*
X716894Y84047D03*
X713115Y88629D03*
X701500Y85500D03*
X698300Y85300D03*
X709560Y84648D03*
X670795Y89189D03*
X692000Y45000D03*
Y48500D03*
X697500D03*
Y45000D03*
X701525Y35610D03*
X720572Y88700D03*
X670600Y144900D03*
Y150000D03*
X670503Y115884D03*
X664700Y142800D03*
X675600Y144900D03*
Y150000D03*
X679900Y128200D03*
X682400Y127085D03*
X684900D03*
X673566Y116724D03*
X676494Y116940D03*
X668665Y118185D03*
X671249Y118744D03*
X677896Y119093D03*
X674896D03*
X693600Y103100D03*
X694459Y105382D03*
X691810Y105540D03*
X701953Y104902D03*
X715505Y155076D03*
X720700Y154750D03*
X725650Y155000D03*
X696100Y102700D03*
X696832Y104986D03*
X699400Y105060D03*
X704419Y104448D03*
X698600Y102600D03*
X691583Y200124D03*
X689033D03*
X686533D03*
Y196624D03*
X689033D03*
X691583D03*
X715550Y158880D03*
X705550D03*
X710550D03*
X709341Y190507D03*
X724888Y188930D03*
X709200Y198700D03*
X720369Y205199D03*
X714391Y215809D03*
X709182Y203948D03*
X709200Y201300D03*
X711800Y203100D03*
X706600Y201300D03*
X715100Y213344D03*
X715727Y218267D03*
X716480Y194700D03*
X709400Y195763D03*
X701956Y195294D03*
X705292Y195729D03*
X714137Y195682D03*
X711886Y194714D03*
X719686Y195421D03*
X722117Y195399D03*
X697568Y196197D03*
X707529Y193200D03*
X704907Y191638D03*
X701129Y192106D03*
X697746Y193205D03*
X716557Y198557D03*
X692513Y213800D03*
X692673Y206200D03*
X692500Y210100D03*
X690861Y211917D03*
Y215717D03*
X692400Y218100D03*
X690861Y204317D03*
Y208117D03*
X706500Y217400D03*
Y214900D03*
Y207800D03*
X706561Y211417D03*
Y204217D03*
X719315Y239104D03*
X669900Y224000D03*
X672500Y224100D03*
X678454Y278000D03*
X675380Y246340D03*
X678000Y246400D03*
X668100Y232200D03*
X667240Y246600D03*
X672530Y246300D03*
X677400Y232300D03*
X674300Y232200D03*
X675200Y224100D03*
X667600Y250200D03*
X688643Y225980D03*
X688388Y231280D03*
X678400Y224100D03*
X690380Y252240D03*
X690939Y266630D03*
X693530Y261240D03*
X690660Y264000D03*
X690704Y271324D03*
X690130Y277380D03*
X689960Y260500D03*
X671100Y232200D03*
X701800Y246480D03*
X669750Y246350D03*
X710572Y244773D03*
X719360Y241504D03*
X710627Y242061D03*
X702000Y243900D03*
X722050Y221150D03*
X707653Y226347D03*
X718300Y227400D03*
X701700Y226600D03*
X725725Y241560D03*
X710500Y224500D03*
X720450Y249950D03*
X710900Y231660D03*
X700000Y233700D03*
X704450Y226600D03*
X713800Y221544D03*
X709700Y275500D03*
X709600Y278100D03*
X704500Y252500D03*
X700800Y261300D03*
X715200Y258900D03*
X704090Y256080D03*
X710675Y263425D03*
X700900Y264100D03*
X697255Y267098D03*
X700400Y257200D03*
X694361Y223317D03*
Y220817D03*
X690861D03*
Y223317D03*
X672300Y269200D03*
X672200Y256800D03*
X706561Y219917D03*
X719900Y269300D03*
X725500Y279300D03*
X725300Y269400D03*
X719600Y279400D03*
X713700Y224144D03*
X717420Y249920D03*
X679300Y261700D03*
X677800Y254100D03*
X667700Y275600D03*
X709949Y272647D03*
X706800Y278100D03*
X710700Y260200D03*
X723400Y250000D03*
X713970Y308360D03*
X704175Y287275D03*
X704214Y290775D03*
X674469Y287375D03*
X686470Y282220D03*
X695000Y289500D03*
X670800Y292600D03*
X688100Y308600D03*
X680000Y281900D03*
X672150Y288350D03*
X695300Y338100D03*
X695400Y328000D03*
X686600Y335600D03*
X687400Y319833D03*
X687138Y317397D03*
X674700Y339200D03*
X687400Y328200D03*
X687300Y325200D03*
X684100Y338200D03*
X695400Y318000D03*
X706800Y281900D03*
X695800Y308000D03*
X696088Y297069D03*
X704500Y293800D03*
X707130Y310150D03*
X718200Y295000D03*
X713970Y310860D03*
X711900Y327700D03*
X712400Y324400D03*
X701100Y339000D03*
X698600Y338900D03*
X706300Y318400D03*
X683490Y282110D03*
X704404Y310875D03*
X697521Y320500D03*
X697120Y305349D03*
X670800Y298400D03*
X690048Y284053D03*
X665000Y284800D03*
X690048Y281053D03*
X678200Y307800D03*
X672700Y307700D03*
X667100D03*
X678100Y324800D03*
X672200Y329800D03*
X678100Y329600D03*
X666900Y329700D03*
X678200Y313700D03*
Y319300D03*
X688924Y288147D03*
X668000Y298400D03*
X704404Y315875D03*
X673922Y298078D03*
X686140Y298260D03*
X667900Y339000D03*
X710272Y281911D03*
X724000Y291700D03*
X705800Y301600D03*
X697521Y325500D03*
X697352Y335500D03*
Y330500D03*
X697120Y300349D03*
X679000Y348000D03*
X674194Y358467D03*
X683417Y364972D03*
X677563Y365496D03*
X695700Y357300D03*
X695644Y354644D03*
X695700Y346300D03*
X688600Y365100D03*
X671936Y367171D03*
X665936Y370171D03*
X684900Y348000D03*
X674600D03*
X671936Y370171D03*
X665936Y367171D03*
X668936Y370171D03*
Y367171D03*
X665936Y364171D03*
X668936D03*
X669093Y348120D03*
X671936Y373171D03*
X668936D03*
X670300Y375600D03*
X683100Y392200D03*
X713900Y347800D03*
X698560Y374430D03*
X713900Y342800D03*
Y352800D03*
Y350300D03*
Y345300D03*
X679523Y385808D03*
X678730Y362841D03*
X686619Y392600D03*
X691240Y390039D03*
X669194Y351206D03*
X674194D03*
X679194D03*
X684194D03*
X676900Y381800D03*
X679385Y388705D03*
X687427Y384926D03*
X680200Y432100D03*
X690040Y412030D03*
X685600Y432500D03*
X690600D03*
X680370Y427770D03*
X687400Y411200D03*
X690600Y437500D03*
X703876Y414949D03*
X705850Y417093D03*
X710600Y420267D03*
X710423Y417423D03*
X708346Y415859D03*
X708011Y419078D03*
X712980Y417900D03*
X713493Y420449D03*
X718546Y500283D03*
X723748Y499091D03*
X701255Y521538D03*
X676900Y489400D03*
X666500Y487600D03*
Y484600D03*
X669500D03*
Y481600D03*
X674300Y489500D03*
X689825Y491755D03*
X693604Y491803D03*
X664610Y512810D03*
X685050Y503970D03*
X682050D03*
X689825Y494255D03*
X693604Y494303D03*
X669300Y504000D03*
X677800Y485600D03*
X680300Y485700D03*
X676600Y501300D03*
X690500Y523300D03*
X675500Y521900D03*
X691000Y498200D03*
X688202Y497736D03*
X679049Y503746D03*
X671500Y501300D03*
X674000Y501200D03*
X704500Y512850D03*
X716267Y522020D03*
X703028Y495600D03*
X709028D03*
X706028D03*
X707511Y483439D03*
X720300Y485800D03*
X723792Y489148D03*
X721301Y488200D03*
X703028Y492600D03*
X706028D03*
X710137Y483583D03*
X708700Y499400D03*
X708500Y512500D03*
X700500Y512850D03*
X701200Y524250D03*
X712100Y512700D03*
X701500Y505500D03*
X710643Y505496D03*
X703800Y507100D03*
X716100Y525200D03*
X711339Y499478D03*
X713200Y505500D03*
X715900Y505650D03*
X715009Y512917D03*
X726040Y506080D03*
X721414Y508986D03*
X720565Y511338D03*
X721894Y501346D03*
X675080Y485570D03*
X696000Y496800D03*
X679700Y489400D03*
X686200Y511700D03*
X680000Y511800D03*
X711704Y525483D03*
X707850Y505700D03*
X686375Y527778D03*
X685200Y530500D03*
X684500Y532900D03*
X680910Y582000D03*
X693200Y575900D03*
X674200Y588900D03*
X690100Y575860D03*
X689193Y573493D03*
X693126Y581380D03*
X671599Y573493D03*
X671791Y588920D03*
X674099Y573493D03*
X669099D03*
X668891Y588900D03*
X696600Y581400D03*
X665700Y574200D03*
X713650Y540750D03*
X715650Y542250D03*
Y545250D03*
X713650Y546750D03*
X708000Y553250D03*
X720200Y551750D03*
X715650Y551250D03*
X716100Y527700D03*
X713600D03*
Y530200D03*
Y532700D03*
X716100D03*
Y530200D03*
X725000Y533700D03*
X696000Y553250D03*
X715650Y548250D03*
X713650Y549750D03*
X723200Y551750D03*
X699000Y553250D03*
X702000D03*
X705000D03*
X713650Y543750D03*
X723200Y554750D03*
X706500Y555750D03*
X703500D03*
X700500D03*
X720200Y554750D03*
X709500Y555750D03*
X712600Y571900D03*
X716300Y569400D03*
X707500Y587800D03*
X722200Y571300D03*
X702100Y568800D03*
X702000Y571400D03*
X725400Y580900D03*
X722500D03*
X691900Y531350D03*
Y534850D03*
X697500Y534750D03*
Y531250D03*
X680029Y577503D03*
X718200Y581000D03*
X713500Y618000D03*
X711500Y616274D03*
X665000Y598500D03*
X725173Y598171D03*
X724106Y609550D03*
X721106D03*
X708900Y589850D03*
X706100D03*
X712000Y597000D03*
Y599500D03*
X708800Y599300D03*
Y596700D03*
X712106Y604050D03*
X717612Y598554D03*
X716106Y609050D03*
X712106Y606650D03*
X722406Y598950D03*
X713132Y609306D03*
X755000Y17255D03*
X732600Y3600D03*
X755500Y8700D03*
X753600Y-4300D03*
X734500Y-5700D03*
X734916Y-1587D03*
X732316D03*
X732191Y-4087D03*
X735020Y-8858D03*
X726327Y-14658D03*
X728837Y-12763D03*
X728716Y-15465D03*
X731210Y-15134D03*
X736715Y33487D03*
X734201Y33510D03*
X726250Y23550D03*
X729500Y23500D03*
X729600Y17991D03*
X734256D03*
X754600Y300D03*
X751900Y400D03*
X731457Y8471D03*
X732335Y6000D03*
X786414Y-9650D03*
X766300Y-1800D03*
X765400Y-9800D03*
X779771Y9114D03*
X773228D03*
Y-1801D03*
X779921Y-1751D03*
X776188Y-7851D03*
X769881Y-9901D03*
X782567Y-7700D03*
X786388Y9098D03*
Y-1801D03*
X782567Y33700D03*
X779921Y27899D03*
X776188Y33700D03*
X773228Y27899D03*
X786414Y30750D03*
X786388Y33399D03*
X764100Y17100D03*
X760100Y17255D03*
X763500Y23940D03*
X786414Y28150D03*
X769881Y27899D03*
X782567Y14814D03*
Y30100D03*
X769881Y16839D03*
X776224Y14714D03*
X776188Y29949D03*
X786364Y16900D03*
X756714Y23130D03*
X753675Y23239D03*
X756176Y-4300D03*
X776274Y12114D03*
X773228Y-9901D03*
X776188Y-4100D03*
X773228Y17157D03*
X782567Y12114D03*
X779921Y-9901D03*
X782567Y-4100D03*
X779921Y17157D03*
X769881Y9157D03*
X786388Y11700D03*
Y-4401D03*
X786414Y-7050D03*
X786388Y14300D03*
X736631Y36122D03*
X736655Y38531D03*
X731887Y40916D03*
X734155Y38531D03*
X734131Y36122D03*
X731843Y43571D03*
X756100Y36200D03*
X755500Y46700D03*
X737800Y55800D03*
X731200Y68600D03*
X733600Y68546D03*
X733642Y66146D03*
X731242Y66200D03*
X731332Y63801D03*
X733732Y63747D03*
X751600Y41000D03*
X755500Y55200D03*
X752600Y86200D03*
X735700Y82700D03*
X752680Y83500D03*
X733740Y95230D03*
X730923Y75315D03*
X731910Y92790D03*
X751708Y73800D03*
X755500Y84361D03*
X733671Y75412D03*
X753100Y92111D03*
X779921Y65699D03*
X773228D03*
X786414Y68550D03*
X779921Y54957D03*
X782567Y49914D03*
X773228Y54957D03*
X776274Y49914D03*
X786388Y52100D03*
Y49500D03*
X764100Y55100D03*
X763500Y59700D03*
X765900Y35800D03*
X786388Y35999D03*
X786364Y54700D03*
X786388Y46898D03*
X773228Y46914D03*
X779771D03*
X776188Y67749D03*
X769881Y66000D03*
X782567Y67900D03*
Y52614D03*
X769881Y54839D03*
X779921Y35983D03*
X773228D03*
X776224Y52514D03*
X769881Y92500D03*
X773228Y84714D03*
X779771D03*
X776224Y90314D03*
X782567Y90414D03*
X779921Y73849D03*
X773228Y73799D03*
X782567Y71500D03*
X779921Y92757D03*
X782567Y87714D03*
X776188Y71500D03*
X773228Y92757D03*
X776274Y87714D03*
X786388Y89900D03*
Y71199D03*
Y87300D03*
X761650Y94550D03*
X769500Y84700D03*
X763400Y78300D03*
X766824Y85943D03*
X763930Y85100D03*
X786414Y65950D03*
X786388Y73799D03*
X786364Y92500D03*
X786388Y84698D03*
X730038Y88408D03*
X732599D03*
X735241Y88329D03*
X763350Y81220D03*
X732734Y82626D03*
X769881Y46957D03*
X746600Y103900D03*
X730600Y154984D03*
X746000Y150500D03*
X740718Y150957D03*
X741700Y102000D03*
X752900Y101000D03*
X744200Y102800D03*
X769100Y102900D03*
X766500D03*
X764000Y95750D03*
X756800Y99400D03*
Y102000D03*
X758400Y156200D03*
X747600Y161450D03*
X740650Y164800D03*
X735600Y164900D03*
X740650Y158800D03*
X727776Y188811D03*
X733564Y189288D03*
X742091Y188333D03*
X747469Y188368D03*
X755248D03*
X739641Y190634D03*
X752708Y188455D03*
X750167Y188490D03*
X744928Y188438D03*
X737319Y189766D03*
X739359Y188125D03*
X735626Y187965D03*
X731155Y189256D03*
X754726Y205037D03*
X752226D03*
X749726D03*
X754726Y207537D03*
X752226D03*
X749726D03*
X742937Y218574D03*
X737536Y192392D03*
X771232Y214033D03*
X777182Y212033D03*
X766368Y183636D03*
X765227Y186164D03*
X765007Y188583D03*
X762667Y186186D03*
X762533Y188626D03*
X763881Y184103D03*
X760084Y188508D03*
X760258Y186077D03*
X767692Y185654D03*
X767476Y188323D03*
X757654Y188464D03*
X758400Y159200D03*
X774582Y212033D03*
X770200Y208600D03*
X765116Y216512D03*
X779932Y212033D03*
X770300Y204930D03*
X769044Y191348D03*
X775171Y218616D03*
X787371Y215216D03*
Y217716D03*
X777700Y218600D03*
X765144Y213508D03*
X727969Y236770D03*
X736612Y237908D03*
X727997Y239195D03*
X736625Y240308D03*
X737837Y222364D03*
Y224964D03*
X740300Y228100D03*
X742897Y229573D03*
X731662Y247716D03*
X742937Y221174D03*
Y223774D03*
X740437Y224964D03*
Y222364D03*
X748700Y254000D03*
X751363Y254207D03*
X754758Y273356D03*
X749100Y279500D03*
X746303Y243122D03*
X746321Y240569D03*
X777000Y243500D03*
X766732Y225189D03*
X761580Y220160D03*
X760304Y235827D03*
X768560Y244055D03*
X765116Y248512D03*
X779932Y244033D03*
X766632Y222589D03*
X771650Y246451D03*
X765116Y280512D03*
X779400Y276200D03*
X766532Y254652D03*
X771650Y278451D03*
X766632Y257252D03*
X776700Y275500D03*
X748990Y267450D03*
X765007Y252363D03*
X769019Y276400D03*
X762616Y270113D03*
X761480Y242720D03*
X726328Y249979D03*
X731100Y269300D03*
Y279300D03*
X775200Y230500D03*
X775171Y227116D03*
Y234316D03*
X787371Y247216D03*
Y249716D03*
X775232Y221133D03*
X777700Y250600D03*
X775232Y223633D03*
X775171Y250616D03*
X775271Y262716D03*
X775171Y259116D03*
Y266316D03*
X775232Y253133D03*
Y255633D03*
X787371Y279216D03*
X748700Y257500D03*
X759700Y232000D03*
X739500Y247500D03*
X749126Y220843D03*
X742897Y226773D03*
X739400Y253400D03*
X730000Y254675D03*
X754263Y254207D03*
X754846Y276340D03*
X765144Y245508D03*
X749090Y270250D03*
X765144Y277508D03*
X774347Y339983D03*
X762760Y339500D03*
X736000Y303400D03*
X741250Y298856D03*
X727300Y302910D03*
X727474Y338363D03*
Y335363D03*
X732474D03*
Y338363D03*
X756114Y316209D03*
X741512Y315538D03*
X729974Y338363D03*
Y335363D03*
X767310Y286530D03*
X779100Y307900D03*
X771600Y310600D03*
X776270Y307100D03*
X765007Y284363D03*
X771278Y307918D03*
X762842Y302434D03*
X765116Y312512D03*
X767000Y318500D03*
X779932Y340033D03*
X777182D03*
X766732Y321189D03*
X765007Y316363D03*
X765730Y335064D03*
X775271Y294716D03*
X775171Y291116D03*
Y298316D03*
X777700Y282600D03*
X775232Y287633D03*
Y285133D03*
X775171Y282616D03*
X787371Y281716D03*
Y311216D03*
X775271Y326716D03*
X775171Y323116D03*
Y330316D03*
X777800Y314700D03*
X775171Y314616D03*
X787371Y313716D03*
X775232Y317133D03*
Y319633D03*
X749800Y282300D03*
X757956Y328095D03*
X729405Y290725D03*
X743600Y304100D03*
X737750Y298894D03*
X737912Y315500D03*
X764980Y287980D03*
X765144Y309508D03*
Y341508D03*
X727474Y344663D03*
Y367463D03*
X732474D03*
X729974D03*
X727474Y364863D03*
X732474D03*
X729974D03*
Y347663D03*
X727474D03*
X732474D03*
Y344663D03*
X732000Y380000D03*
X727574Y373463D03*
X732574D03*
X730074D03*
X732574Y376063D03*
X730074D03*
X729974Y344663D03*
X731100Y362300D03*
X772443Y371976D03*
X765116Y344512D03*
X779882Y372033D03*
X767477Y350708D03*
X771700Y342501D03*
X766732Y353189D03*
X777100Y372000D03*
X765007Y348363D03*
X760140Y362819D03*
X758952Y384100D03*
X763333Y400212D03*
X772300Y403520D03*
X764131Y376747D03*
X766643Y382724D03*
X771400Y374400D03*
X764957Y380363D03*
X775171Y346616D03*
Y362316D03*
X775271Y358716D03*
X775171Y355116D03*
X787371Y343216D03*
Y345716D03*
X775232Y349133D03*
X777600Y346600D03*
X775232Y351633D03*
X787321Y374916D03*
Y377316D03*
X775182Y383633D03*
Y381133D03*
X778000Y378700D03*
X775121Y378616D03*
Y394316D03*
X775221Y390716D03*
X775121Y387116D03*
X760500Y359800D03*
X767155Y385550D03*
X764159Y373743D03*
X746130Y430130D03*
X755487Y409903D03*
Y412403D03*
X748085Y412338D03*
X750585D03*
X753085D03*
Y409838D03*
X750585D03*
X748085D03*
X749640Y431797D03*
X739933Y447401D03*
X747950Y441600D03*
X748500Y438900D03*
X728940Y457806D03*
X746151Y433077D03*
X766200Y417005D03*
X775417Y435799D03*
X777979Y436516D03*
X760326Y414167D03*
Y411667D03*
X757826D03*
Y414167D03*
X762989Y411728D03*
X763069Y414441D03*
X768080Y418780D03*
X766394Y414397D03*
X763706Y514250D03*
X728373Y488356D03*
X731339Y489319D03*
X743483Y492937D03*
X752496Y515974D03*
X732522Y526808D03*
Y524308D03*
X750518Y522108D03*
X734922Y526808D03*
X756000Y525950D03*
X729000Y511500D03*
X731600Y511600D03*
X748524Y502174D03*
X743524D03*
X748524Y499674D03*
X750931Y499916D03*
X746024Y499674D03*
X743524D03*
X746024Y502174D03*
X786388Y515300D03*
Y512700D03*
X769500Y510100D03*
X763950Y508540D03*
X766535Y517900D03*
X763950Y506040D03*
Y511040D03*
X776224Y515714D03*
X779771Y510114D03*
X773228D03*
X769881Y517900D03*
X782567Y515814D03*
X786388Y510098D03*
X786364Y517900D03*
X779921Y518157D03*
X782567Y513114D03*
X773228Y518157D03*
X776274Y513114D03*
X738648Y492050D03*
X752900Y521121D03*
Y518621D03*
X763544Y522236D03*
X732442Y529300D03*
X734842D03*
X736300Y541500D03*
X756000Y537000D03*
X737400Y529400D03*
X734900Y531800D03*
X732400D03*
X726200Y551750D03*
X732098Y550000D03*
X729550D03*
X732098Y553000D03*
X729550D03*
X736000Y537700D03*
Y535200D03*
X733500Y537700D03*
Y535200D03*
X728000Y533750D03*
X754910Y556400D03*
X726200Y554750D03*
X727400Y571300D03*
X755000Y574800D03*
X752500Y585150D03*
X727106Y586550D03*
X732098Y556000D03*
X729550D03*
X755000Y566000D03*
X732600Y573950D03*
X786414Y531750D03*
X786388Y534399D03*
X782567Y550914D03*
X776274D03*
X786388Y553100D03*
Y550500D03*
X764400Y528600D03*
X769500Y536983D03*
X765100Y537110D03*
X773228Y536999D03*
X763677Y547783D03*
X776188Y530949D03*
X782567Y531100D03*
X769818Y529200D03*
X779921Y537049D03*
X782567Y553614D03*
X773228Y547914D03*
X779771D03*
X776224Y553514D03*
X786388Y536999D03*
X786414Y529150D03*
X786388Y547898D03*
X779921Y528899D03*
X776188Y534700D03*
X786414Y569550D03*
X786388Y572199D03*
X782567Y588714D03*
X776274D03*
X786388Y588300D03*
X763300Y566000D03*
X769500Y585700D03*
X764117Y575658D03*
X766535Y555700D03*
X763450Y585200D03*
X765900Y587300D03*
X786364Y555700D03*
X769881D03*
X773228Y574799D03*
X782567Y568900D03*
X769700Y566900D03*
X776188Y568749D03*
X779921Y574849D03*
X773228Y585714D03*
X779771D03*
X786388Y574799D03*
Y585698D03*
X786414Y566950D03*
X779921Y555957D03*
X782567Y572500D03*
X779921Y566699D03*
X773228Y555957D03*
X776188Y572500D03*
X773228Y566699D03*
X769500Y547900D03*
Y574700D03*
X782567Y534700D03*
X773228Y528899D03*
X733032Y604000D03*
X779921Y612649D03*
X773228Y612599D03*
X786388D03*
X769500Y612583D03*
X755000Y614500D03*
X728000Y623500D03*
X727000Y606600D03*
X739307Y598850D03*
X755800Y604600D03*
X726857Y610871D03*
X729616Y610863D03*
X753300Y593600D03*
X732500Y611000D03*
X782567Y610300D03*
X779921Y593757D03*
Y604499D03*
X776188Y610300D03*
X773228Y593757D03*
Y604499D03*
X786414Y607350D03*
X786388Y590900D03*
Y609999D03*
X764400Y604600D03*
X766535Y593500D03*
X766600Y590700D03*
X769700Y604900D03*
X776188Y606549D03*
X782567Y606700D03*
Y591414D03*
X776224Y591314D03*
X786414Y604750D03*
X786364Y593500D03*
X755900Y593650D03*
X803346Y-1751D03*
X810039Y-1801D03*
X791514Y-2050D03*
X791501Y-9864D03*
X812999Y-7851D03*
X806692D03*
X799999D03*
X816582Y9114D03*
X796653D03*
X791464Y9100D03*
X810039Y9114D03*
X803346D03*
X816732Y-1751D03*
X796653D03*
X799999Y29949D03*
X812999Y33700D03*
X810039Y27899D03*
X803346D03*
X796653D03*
X816732D03*
X791488Y30540D03*
Y33149D03*
X806692Y29949D03*
X812999D03*
X791501Y27936D03*
X791488Y17114D03*
X799999Y14814D03*
X813035Y14714D03*
X806692Y14814D03*
X828275Y9100D03*
X833464Y9114D03*
X840157D03*
X819378Y-7700D03*
X823199Y9098D03*
Y-1801D03*
X823225Y-9650D03*
X828312Y-9864D03*
X843503Y-7851D03*
X836810D03*
X846850Y-1801D03*
X828325Y-2050D03*
X833464Y-1751D03*
X840157D03*
X846850Y9114D03*
X833464Y27899D03*
X846850D03*
X819378Y33700D03*
X823225Y30750D03*
X828299Y30540D03*
X823199Y33399D03*
X828299Y33149D03*
X819378Y14814D03*
Y30100D03*
X843503Y14814D03*
X823175Y16900D03*
X823225Y28150D03*
X828312Y27936D03*
X836810Y29949D03*
X828299Y17114D03*
X836810Y14814D03*
X843503Y29949D03*
X840157Y27899D03*
X796653Y-9901D03*
X833464D03*
X840157D03*
X843503Y-3700D03*
X799999Y12114D03*
X836810D03*
X843503D03*
X840157Y17157D03*
X828299Y-4651D03*
Y11914D03*
X823199Y-4401D03*
Y11700D03*
X791488Y-4651D03*
Y11914D03*
X828299Y14514D03*
Y-7260D03*
X823199Y14300D03*
X823225Y-7050D03*
X791488Y-7260D03*
Y14514D03*
X819378Y12114D03*
X816732Y-9901D03*
Y17157D03*
X819378Y-4100D03*
X799999Y-3700D03*
X796653Y17157D03*
X803346Y-9901D03*
X806692Y12114D03*
Y-3700D03*
X803346Y17157D03*
X846850Y-9901D03*
Y17157D03*
X833464D03*
X836810Y-3700D03*
X810039Y-9901D03*
X813085Y12114D03*
X812999Y-4100D03*
X810039Y17157D03*
X791488Y54914D03*
X799999Y52614D03*
X796653Y46914D03*
X810039Y65699D03*
X803346D03*
X796653D03*
X816732D03*
X791488Y68340D03*
X810039Y54957D03*
X813085Y49914D03*
X806692Y34100D03*
X803346Y54957D03*
X806692Y49914D03*
X799999Y34100D03*
X796653Y54957D03*
X799999Y49914D03*
X816732Y54957D03*
X791488Y52314D03*
Y49714D03*
X791464Y46900D03*
X810039Y35999D03*
X803346Y36049D03*
X799999Y90414D03*
X791488Y92714D03*
X806692Y90414D03*
X812999Y71500D03*
X810039Y92757D03*
X813085Y87714D03*
X806692Y71900D03*
X803346Y92757D03*
X806692Y87714D03*
X799999Y71900D03*
X796653Y92757D03*
X799999Y87714D03*
X816732Y92757D03*
X791488Y70949D03*
Y87514D03*
Y90114D03*
X816582Y46914D03*
X816732Y36049D03*
X799999Y67749D03*
X812999D03*
X806692D03*
X791501Y65736D03*
X803346Y46914D03*
X806692Y52614D03*
X813035Y52514D03*
X810039Y46914D03*
X791514Y35750D03*
X796653Y36049D03*
X816582Y73849D03*
X791514Y73550D03*
X796653Y73849D03*
X810039Y73799D03*
X803346Y73849D03*
X816582Y84714D03*
X813035Y90314D03*
X803346Y84714D03*
X810039D03*
X796653D03*
X791464Y84700D03*
X846850Y65699D03*
X823225Y68550D03*
X828299Y68340D03*
X843503Y34100D03*
X833464Y54957D03*
X836810Y34100D03*
Y49914D03*
X846850Y54957D03*
X819378Y49914D03*
X823199Y52100D03*
X828299Y52314D03*
X823199Y49500D03*
X828299Y49714D03*
X819378Y67900D03*
Y52614D03*
X846850Y35999D03*
X833464Y36049D03*
X840157D03*
X823225Y65950D03*
X823175Y54700D03*
X823199Y46898D03*
Y35999D03*
X828299Y54914D03*
X828275Y46900D03*
X828325Y35750D03*
X833464Y46914D03*
X836810Y52614D03*
X840157Y46914D03*
X828312Y65736D03*
X836810Y67749D03*
X843503D03*
X846850Y46914D03*
X843503Y52614D03*
X840157Y65699D03*
X833464D03*
X823175Y92500D03*
X823199Y84698D03*
X846850Y73799D03*
X843503Y90414D03*
X846850Y84714D03*
X828325Y73550D03*
X840157Y73849D03*
X833464D03*
X828299Y92714D03*
X836810Y90414D03*
X840157Y84714D03*
X833464D03*
X828275Y84700D03*
X843503Y71900D03*
X840157Y92757D03*
X843503Y87714D03*
X836810Y71900D03*
X833464Y92757D03*
X836810Y87714D03*
X846850Y92757D03*
X819378Y71500D03*
Y87714D03*
X823199Y89900D03*
X828299Y70949D03*
Y87514D03*
X823199Y71199D03*
Y87300D03*
X828299Y90114D03*
X840157Y54957D03*
X843503Y49914D03*
X819378Y90364D03*
X823199Y73799D03*
X822400Y212400D03*
X799300Y195600D03*
Y199100D03*
X813700Y195600D03*
X790871Y215216D03*
Y217716D03*
X799620Y186547D03*
X798337Y181216D03*
X813700Y198900D03*
X804470Y186814D03*
X845100Y268200D03*
X847600D03*
X842600D03*
X847600Y243400D03*
X841400Y243300D03*
X847600Y238400D03*
X841400Y238300D03*
X847600Y240900D03*
X841400Y240800D03*
X789500Y231800D03*
X790900Y234000D03*
Y229700D03*
X790846Y225774D03*
X790882Y221723D03*
X790871Y247216D03*
Y249716D03*
X789471Y227742D03*
X789576Y223737D03*
X789554Y219723D03*
X790900Y253900D03*
X789432Y252000D03*
X790871Y266216D03*
X789432Y255800D03*
X790867Y257724D03*
X789432Y259800D03*
X789500Y263900D03*
X790885Y261711D03*
X790871Y279216D03*
X842600Y299900D03*
X845100D03*
X847600D03*
X845100Y331500D03*
X842600D03*
X847600D03*
X790871Y311216D03*
X789432Y284200D03*
Y288300D03*
Y292400D03*
X789400Y296200D03*
X790871Y298216D03*
X790937Y294270D03*
X790900Y290300D03*
Y286200D03*
X790871Y281716D03*
Y313716D03*
X789432Y319900D03*
Y323900D03*
X790900Y322000D03*
Y326000D03*
X790871Y330216D03*
X789500Y328000D03*
X789478Y315671D03*
X790800Y317700D03*
X805600Y403900D03*
X847600Y363000D03*
X845100D03*
X842600D03*
X847577Y381842D03*
X824000Y402863D03*
X840871Y391380D03*
X837272Y391420D03*
X827800Y402863D03*
X832300D03*
X789432Y348100D03*
Y352100D03*
X789597Y356105D03*
X789500Y360200D03*
X790900Y358200D03*
X790835Y354048D03*
X790867Y350024D03*
X790871Y345716D03*
Y343216D03*
Y362216D03*
X790821Y374916D03*
X790900Y389300D03*
X789500Y391300D03*
X790900Y393400D03*
Y381100D03*
X789582Y383200D03*
X790900Y385300D03*
X789500Y387300D03*
X790821Y377316D03*
X789282Y379200D03*
X797000Y404700D03*
X797200Y409830D03*
X805367Y407400D03*
X797780Y423484D03*
X800610Y415000D03*
X798500Y412600D03*
X799999Y513114D03*
X791488Y512914D03*
Y515514D03*
X816582Y510114D03*
X806692Y515814D03*
X813035Y515714D03*
X810039Y510114D03*
X791488Y518114D03*
X791464Y510100D03*
X799999Y515814D03*
X796653Y510114D03*
X803346D03*
Y518157D03*
X806692Y513114D03*
X796653Y518157D03*
X819378Y515764D03*
X843503Y515814D03*
X846850Y510114D03*
X823175Y517900D03*
X823199Y510098D03*
X828299Y518114D03*
X840157Y510114D03*
X833464D03*
X836810Y515814D03*
X846850Y518157D03*
X813085Y513114D03*
X810039Y518157D03*
X823199Y512700D03*
Y515300D03*
X819378Y513114D03*
X816732Y518157D03*
X828299Y515514D03*
Y512914D03*
X836810Y513114D03*
X833464Y518157D03*
X843503Y513114D03*
X840157Y518157D03*
X796653Y528899D03*
X791488Y534149D03*
Y531540D03*
X813085Y550914D03*
X806692D03*
X799999D03*
X791488Y550714D03*
Y553314D03*
X816582Y537049D03*
Y547914D03*
X810039Y536999D03*
X806692Y530949D03*
X812999D03*
X803346Y537049D03*
X796653D03*
X799999Y530949D03*
X791501Y528936D03*
X791514Y536750D03*
X799999Y553614D03*
X810039Y547914D03*
X796653D03*
X803346D03*
X791464Y547900D03*
X806692Y553614D03*
X813035Y553514D03*
X806692Y535100D03*
X803346Y528899D03*
X799999Y535100D03*
X816732Y555957D03*
Y566699D03*
X791488Y571949D03*
X813085Y588714D03*
X806692D03*
X799999D03*
X791488Y588514D03*
Y555914D03*
X810039Y585714D03*
X806692Y568749D03*
X810039Y574799D03*
X812999Y568749D03*
X803346Y585714D03*
X796653D03*
X791514Y574550D03*
X791464Y585700D03*
X799999Y568749D03*
X796653Y574849D03*
X803346D03*
X791501Y566736D03*
X816582Y585714D03*
Y574849D03*
X810039Y555957D03*
X812999Y572500D03*
X810039Y566699D03*
X803346Y555957D03*
X806692Y572900D03*
X803346Y566699D03*
X796653Y555957D03*
X799999Y572900D03*
X796653Y566699D03*
X846850Y528899D03*
X843503Y550914D03*
X836810D03*
X819378D03*
X823199Y553100D03*
X828299Y550714D03*
X823199Y550500D03*
X828299Y553314D03*
X819378Y553564D03*
Y531100D03*
X836810Y530949D03*
X833464Y537049D03*
X846850Y547914D03*
X833464D03*
X840157D03*
X828275Y547900D03*
X843503Y553614D03*
X836810D03*
X846850Y536999D03*
X843503Y530949D03*
X823199Y547898D03*
Y536999D03*
X823225Y529150D03*
X828325Y536750D03*
X840157Y537049D03*
X828312Y528936D03*
X840157Y555957D03*
X843503Y572900D03*
X840157Y566699D03*
X833464Y555957D03*
Y566699D03*
X846850Y555957D03*
Y566699D03*
X823225Y569550D03*
X828299Y571949D03*
X823199Y572199D03*
X828299Y569340D03*
X843503Y588714D03*
X836810D03*
X819378D03*
X828299Y588514D03*
X823199Y588300D03*
X819378Y568900D03*
X823175Y555700D03*
X828299Y555914D03*
X828275Y585700D03*
X823225Y566950D03*
X823199Y585698D03*
Y574799D03*
X828312Y566736D03*
X840157Y585714D03*
X833464D03*
X828325Y574550D03*
X840157Y574849D03*
X833464D03*
X836810Y568749D03*
X846850Y585714D03*
Y574799D03*
X843503Y568749D03*
X812999Y534700D03*
X823225Y531750D03*
X816732Y528899D03*
X819378Y534700D03*
X828299Y534149D03*
X836810Y535100D03*
X840157Y528899D03*
X843503Y535100D03*
X791488Y569340D03*
X836810Y572900D03*
X819378Y572500D03*
X810039Y528899D03*
X823199Y534399D03*
X828299Y531540D03*
X833464Y528899D03*
X846850Y612599D03*
X840157Y612649D03*
X833464D03*
X823199Y612599D03*
X810039D03*
X803346Y612649D03*
X796653D03*
X816582D03*
X812999Y610300D03*
X810039Y593757D03*
Y604499D03*
X806692Y610700D03*
X803346Y593757D03*
Y604499D03*
X799999Y610700D03*
X796653Y593757D03*
Y604499D03*
X816732Y593757D03*
Y604499D03*
X791488Y609749D03*
Y591114D03*
X791514Y612350D03*
X806692Y606549D03*
X812999D03*
X799999D03*
X791501Y604536D03*
X806692Y591414D03*
X813035Y591314D03*
X799999Y591414D03*
X791488Y593714D03*
X840157Y593757D03*
X843503Y610700D03*
X840157Y604499D03*
X833464Y593757D03*
X836810Y610700D03*
X833464Y604499D03*
X846850Y593757D03*
X819378Y610300D03*
X823199Y590900D03*
X828299Y609749D03*
X823199Y609999D03*
X828299Y591114D03*
Y607140D03*
X819378Y606700D03*
Y591364D03*
X823225Y604750D03*
X823175Y593500D03*
X843503Y591414D03*
X828312Y604536D03*
X843503Y606549D03*
X836810D03*
X828325Y612350D03*
X836810Y591414D03*
X828299Y593714D03*
X791488Y607140D03*
X846850Y604499D03*
X823225Y607350D03*
X870275Y9114D03*
X865086Y9100D03*
X860010Y9098D03*
X876968Y9114D03*
Y-1751D03*
X873621Y-7851D03*
X865123Y-9864D03*
X860036Y-9650D03*
X849810Y-7851D03*
X856189Y-7700D03*
X860010Y-1801D03*
X865136Y-2050D03*
X853543Y-1751D03*
X870275D03*
X853393Y9114D03*
X856189Y33700D03*
X853543Y27899D03*
X876968D03*
X849810Y33700D03*
X870275Y27899D03*
X860036Y30750D03*
X865110Y30540D03*
X860010Y33399D03*
X865110Y33149D03*
X860036Y28150D03*
X859986Y16900D03*
X865110Y17114D03*
X856189Y14814D03*
X849846Y14714D03*
X873621Y14814D03*
Y29949D03*
X865123Y27936D03*
X849810Y29949D03*
X856189Y30100D03*
X896847Y-9650D03*
X910432Y-7851D03*
X883661Y-1801D03*
X880314Y-7851D03*
X886621D03*
X907086Y-1751D03*
X890354D03*
X896821Y-1801D03*
X901947Y-2050D03*
X901934Y-9864D03*
X893000Y-7700D03*
X883661Y9114D03*
X907086D03*
X896821Y9098D03*
X901897Y9100D03*
X890204Y9114D03*
X886621Y33700D03*
X883661Y27899D03*
X907086D03*
X896847Y30750D03*
X901921Y33149D03*
X896821Y33399D03*
X901921Y30540D03*
X910432Y29949D03*
X896797Y16900D03*
X893000Y14814D03*
X901921Y17114D03*
X901934Y27936D03*
X893000Y30100D03*
X880314Y14814D03*
X886657Y14714D03*
X886621Y29949D03*
X880314D03*
X896847Y28150D03*
X910432Y14814D03*
X893000Y33700D03*
X890354Y27899D03*
X870275Y-9901D03*
X876968D03*
X880314Y-3700D03*
X907086Y-9901D03*
X873621Y12114D03*
X880314D03*
X876968Y17157D03*
X910432Y12114D03*
X901921Y11914D03*
Y-4651D03*
X865110Y11914D03*
Y-4651D03*
X896821Y-4401D03*
Y11700D03*
X860010D03*
Y-4401D03*
X901921Y-7260D03*
Y14514D03*
X865110Y-7260D03*
Y14514D03*
X896847Y-7050D03*
X896821Y14300D03*
X860036Y-7050D03*
X860010Y14300D03*
X907086Y17157D03*
X886707Y12114D03*
X883661Y-9901D03*
Y17157D03*
X886621Y-4100D03*
X893000Y12114D03*
X890354Y-9901D03*
X893000Y-4100D03*
X890354Y17157D03*
X873621Y-3700D03*
X870275Y17157D03*
X849896Y12114D03*
X849810Y-4100D03*
X853543Y-9901D03*
X856189Y12114D03*
Y-4100D03*
X853543Y17157D03*
X910432Y-3700D03*
X870275Y65699D03*
X860036Y68550D03*
X865110Y68340D03*
X853543Y54957D03*
X856189Y49914D03*
X876968Y54957D03*
X849896Y49914D03*
X873621Y34100D03*
X870275Y54957D03*
X873621Y49914D03*
X860010Y52100D03*
X865110Y52314D03*
X860010Y49500D03*
X865110Y49714D03*
X859986Y54700D03*
X870275Y36049D03*
X865136Y35750D03*
X865086Y46900D03*
X876968Y46914D03*
Y36049D03*
X873621Y67749D03*
Y52614D03*
X860010Y46898D03*
X860036Y65950D03*
X865123Y65736D03*
X849810Y67749D03*
X856189Y67900D03*
X853393Y46914D03*
X870275D03*
X865110Y54914D03*
X860010Y35999D03*
X856189Y52614D03*
X853543Y36049D03*
X849846Y52514D03*
X853543Y65699D03*
X876968D03*
Y84714D03*
Y73849D03*
X873621Y90414D03*
X870275Y73849D03*
X853543D03*
X860010Y73799D03*
X849846Y90314D03*
X856189Y90414D03*
X865110Y92714D03*
X870275Y84714D03*
X865086Y84700D03*
X853393Y84714D03*
X860010Y84698D03*
X859986Y92500D03*
X865136Y73550D03*
X856189Y71500D03*
X853543Y92757D03*
X856189Y87714D03*
X876968Y92757D03*
X849810Y71500D03*
X849896Y87714D03*
X873621Y71900D03*
X870275Y92761D03*
X873621Y87714D03*
X860010Y89900D03*
X865110Y70949D03*
Y87514D03*
X860010Y71199D03*
Y87300D03*
X865110Y90114D03*
X883661Y54957D03*
X886707Y49914D03*
X910432Y34100D03*
X907086Y54957D03*
X910432Y49914D03*
X896821Y52100D03*
X901921Y49714D03*
X896821Y49500D03*
X901921Y52314D03*
X910432Y67749D03*
X893000Y67900D03*
X901934Y65736D03*
X896847Y65950D03*
X910432Y52614D03*
X890204Y46914D03*
X896821Y35999D03*
X901921Y54914D03*
X896797Y54700D03*
X883661Y35999D03*
X886621Y67749D03*
X880314D03*
X883661Y46914D03*
X880314Y52614D03*
X886657Y52514D03*
X901947Y35750D03*
X901897Y46900D03*
X896821Y46898D03*
X893000Y52614D03*
X890354Y36049D03*
X907086D03*
X883661Y73799D03*
X910432Y90414D03*
X907086Y84714D03*
X901897Y84700D03*
X880314Y71900D03*
Y87714D03*
X893000Y71500D03*
X890354Y92757D03*
X893000Y87714D03*
X886621Y71500D03*
X883661Y92757D03*
X886707Y87714D03*
X910432Y71900D03*
X907086Y92757D03*
X910432Y87714D03*
X896821Y89900D03*
X901921Y70949D03*
Y87514D03*
X896821Y71199D03*
Y87300D03*
X901921Y90114D03*
X907086Y46914D03*
X890354Y65699D03*
X883661D03*
X907086D03*
X896847Y68550D03*
X901921Y68340D03*
X880314Y34100D03*
Y49914D03*
X890354Y54957D03*
X893000Y49914D03*
X896821Y84698D03*
X893000Y90414D03*
X890204Y84714D03*
X896797Y92500D03*
X901921Y92714D03*
X890354Y73849D03*
X896821Y73799D03*
X901947Y73550D03*
X907086Y73849D03*
X883661Y84714D03*
X886657Y90314D03*
X880314Y90414D03*
X886657Y109884D03*
X907086Y104284D03*
X901934Y105051D03*
X896847Y105265D03*
X890354Y112327D03*
X893000Y106934D03*
X883661Y112327D03*
X886707Y107284D03*
X907086Y112327D03*
X910432Y107284D03*
X896821Y110514D03*
X901921Y107655D03*
X896847Y107865D03*
X901947Y110264D03*
X890204Y104284D03*
X893000Y109534D03*
X896821Y113114D03*
X901947Y112865D03*
X910432Y109984D03*
X883661Y104284D03*
X882008Y321100D03*
X851430Y367468D03*
X849896Y513114D03*
X870275Y518161D03*
X873621Y513114D03*
X860010Y515300D03*
X865110Y512914D03*
X860010Y512700D03*
X865110Y515514D03*
X873621Y515814D03*
X876968Y510114D03*
X870275D03*
X859986Y517900D03*
X865086Y510100D03*
X860010Y510098D03*
X865110Y518114D03*
X853393Y510114D03*
X856189Y515814D03*
X849846Y515714D03*
X853543Y518157D03*
X856189Y513114D03*
X876968Y518157D03*
X910432Y513114D03*
X896821Y515300D03*
X901921Y512914D03*
X896821Y512700D03*
X901921Y515514D03*
X907000Y495800D03*
X882900Y495900D03*
X893000Y493094D03*
X886500Y493400D03*
X910432Y491044D03*
X901921Y490514D03*
X896785D03*
X901921Y498514D03*
X896785D03*
X889100Y498500D03*
X901897Y510100D03*
X893000Y515814D03*
X890204Y510114D03*
X896821Y510098D03*
X901921Y518114D03*
X896797Y517900D03*
X880314Y515814D03*
X886657Y515714D03*
X883661Y510114D03*
X910432Y515814D03*
X907086Y510114D03*
X880314Y513114D03*
X890354Y518157D03*
X893000Y513114D03*
X883661Y518157D03*
X907086D03*
X886500Y490800D03*
X882900Y498500D03*
X896836Y493209D03*
X901921Y493214D03*
X910432Y493744D03*
X901921Y495814D03*
X896836Y495909D03*
X907086Y498487D03*
X893000Y495694D03*
X889200Y495900D03*
X886707Y513114D03*
X849810Y534700D03*
X873621Y535100D03*
X860036Y531750D03*
X865110Y534149D03*
Y531540D03*
X856189Y550914D03*
X849896D03*
X873621D03*
X860010Y553100D03*
X865110Y550714D03*
X860010Y550500D03*
X865110Y553314D03*
X860010Y536999D03*
X865123Y528936D03*
X873621Y530949D03*
Y553614D03*
X876968Y537049D03*
Y547914D03*
X860010Y547898D03*
X870275Y547914D03*
X853393D03*
X865086Y547900D03*
X856189Y553614D03*
X849846Y553514D03*
X870275Y537049D03*
X853543D03*
X856189Y531100D03*
X849810Y530949D03*
X865136Y536750D03*
X860036Y529150D03*
X856189Y534700D03*
X853543Y528899D03*
X876968D03*
X849810Y568749D03*
X865086Y585700D03*
X860010Y585698D03*
X865136Y574550D03*
X853543Y555957D03*
X856189Y572500D03*
X853543Y566699D03*
X876968Y555957D03*
Y566699D03*
X870275Y555961D03*
X873621Y572900D03*
X870275Y566699D03*
X860036Y569550D03*
X865110Y571949D03*
Y569340D03*
X856189Y588714D03*
X849896D03*
X873621D03*
X865110Y588514D03*
X860010Y588300D03*
X859986Y555700D03*
X865110Y555914D03*
X860010Y574799D03*
X853393Y585714D03*
X870275D03*
X873621Y568749D03*
X876968Y574849D03*
Y585714D03*
X860036Y566950D03*
X865123Y566736D03*
X870275Y574849D03*
X853543D03*
X856189Y568900D03*
X907086Y528899D03*
X896847Y531750D03*
X896821Y534399D03*
X901921Y531540D03*
X880314Y550914D03*
X890354Y537049D03*
X893000Y531100D03*
X896821Y536999D03*
X901934Y528936D03*
X901947Y536750D03*
X910432Y530949D03*
X907086Y537049D03*
X886621Y530949D03*
X883661Y536999D03*
X880314Y530949D03*
Y553614D03*
X886657Y553514D03*
X883661Y547914D03*
X893000Y553614D03*
X910432D03*
X890204Y547914D03*
X896821Y547898D03*
X901897Y547900D03*
X907086Y547914D03*
X880314Y535100D03*
X893000Y534700D03*
X890354Y528899D03*
X886621Y534700D03*
X880314Y568749D03*
X886621D03*
X883661Y574799D03*
Y585714D03*
X880314Y572900D03*
Y588714D03*
X893000D03*
X886707D03*
X896821Y588300D03*
X901921Y555914D03*
X896797Y555700D03*
X901934Y566736D03*
X896847Y566950D03*
X901897Y585700D03*
X890354Y574849D03*
X896821Y574799D03*
X893000Y568900D03*
X901947Y574550D03*
X896821Y585698D03*
X890204Y585714D03*
X910432Y568749D03*
X907086Y574849D03*
Y585714D03*
X901921Y588514D03*
X910432Y588714D03*
X886707Y550914D03*
X883661Y566699D03*
Y555957D03*
X901921Y553314D03*
X896821Y550500D03*
X901921Y550714D03*
X896821Y553100D03*
X910432Y550914D03*
X893000D03*
X901921Y571949D03*
X896847Y569550D03*
X907086Y566699D03*
X910432Y572900D03*
X907086Y555957D03*
X890354Y566699D03*
X893000Y572500D03*
X890354Y555957D03*
X883661Y528899D03*
X870275D03*
X860010Y534399D03*
X849810Y572500D03*
X860010Y572199D03*
X910432Y535100D03*
X901921Y534149D03*
X886621Y572500D03*
X901921Y569340D03*
X896821Y572199D03*
X890354Y612649D03*
X896821Y612599D03*
X883661D03*
X907086Y612649D03*
X870275D03*
X876968D03*
X860010Y612599D03*
X853543Y612649D03*
Y593757D03*
X856189Y610300D03*
X853543Y604499D03*
X876968Y593757D03*
Y604499D03*
X849810Y610300D03*
X870275Y593761D03*
X873621Y610700D03*
X870275Y604499D03*
X860010Y590900D03*
X860036Y607350D03*
X865110Y609749D03*
X860010Y609999D03*
X865110Y591114D03*
X859986Y593500D03*
X865110Y593714D03*
X856189Y591414D03*
X849846Y591314D03*
X860036Y604750D03*
X865123Y604536D03*
X856189Y606700D03*
X849810Y606549D03*
X865136Y612350D03*
X873621Y606549D03*
Y591414D03*
X886657Y591314D03*
X896847Y604750D03*
X901934Y604536D03*
X880314Y610700D03*
X893000Y610300D03*
X890354Y593757D03*
Y604499D03*
X886621Y610300D03*
X883661Y593757D03*
X896847Y607350D03*
X896821Y590900D03*
Y609999D03*
X901921Y591114D03*
X901947Y612350D03*
X896797Y593500D03*
X901921Y593714D03*
X893000Y591414D03*
X910432D03*
Y606549D03*
X893000Y606700D03*
X880314Y606549D03*
X886621D03*
X880314Y591414D03*
X901921Y609749D03*
X907086Y604499D03*
Y593757D03*
X910432Y610700D03*
X865110Y607140D03*
X883661Y604499D03*
X901921Y607140D03*
X923432Y-7851D03*
X929811Y-7700D03*
X933658Y-9650D03*
X917125Y-7851D03*
X913779Y-1751D03*
X933632Y-1801D03*
X927165Y-1751D03*
X920472Y-1801D03*
X927015Y9114D03*
X933632Y9098D03*
X913779Y9114D03*
X920472D03*
X933658Y-7050D03*
X933632Y-4401D03*
X929811Y-4100D03*
X927165Y-9901D03*
X923432Y-4100D03*
X920472Y-9901D03*
X933658Y30750D03*
X933632Y33399D03*
X929811Y33700D03*
X927165Y27899D03*
X923432Y33700D03*
X920472Y27899D03*
X933632Y14300D03*
Y11700D03*
X927165Y17157D03*
X929811Y12114D03*
X920472Y17157D03*
X923518Y12114D03*
X923432Y29949D03*
X917125D03*
Y14814D03*
X929811D03*
X933608Y16900D03*
X923468Y14714D03*
X933658Y28150D03*
X929811Y30100D03*
X913779Y27899D03*
X938745Y-9864D03*
X938758Y-2050D03*
X938708Y9100D03*
X947243Y-7851D03*
X950590Y-1751D03*
X957283Y-1843D03*
X953936Y-7851D03*
X943897Y-1751D03*
Y9114D03*
X950590D03*
X957765Y-7180D03*
X938732Y-7260D03*
Y-4651D03*
X953936Y-3700D03*
X950590Y-9901D03*
X947243Y-3700D03*
X943897Y-9901D03*
X960629Y-9786D03*
X963976Y-1843D03*
X970669Y-1743D03*
X967322Y-9786D03*
X963976Y9114D03*
X970669D03*
X967322Y-4536D03*
X938732Y33149D03*
Y30540D03*
X950590Y27899D03*
X943897D03*
X938732Y14514D03*
Y11914D03*
X950590Y17157D03*
X953936Y12114D03*
X943897Y17157D03*
X947243Y12114D03*
X967322Y28014D03*
X960629Y17057D03*
Y28014D03*
X967322Y17057D03*
X938745Y27936D03*
X938732Y17114D03*
X957283Y9300D03*
X953936Y14814D03*
Y29949D03*
X957600Y13200D03*
X957700Y32100D03*
X970800Y13200D03*
X970942Y32100D03*
X947243Y29949D03*
Y14814D03*
X913779Y-9901D03*
X917125Y-3700D03*
Y12114D03*
X913779Y17157D03*
X960629Y-4536D03*
X963976Y-7108D03*
X970669D03*
X933632Y52100D03*
Y49500D03*
X927165Y54957D03*
X929811Y49914D03*
X920472Y54957D03*
X923518Y49914D03*
X933658Y65950D03*
X923432Y67749D03*
X929811Y67900D03*
X917125Y67749D03*
X920472Y35999D03*
X917125Y52614D03*
X913779Y46914D03*
Y36049D03*
X927015Y73849D03*
X913779D03*
X920472Y73799D03*
X933632D03*
X913779Y84714D03*
X920472D03*
X933608Y92500D03*
X917125Y71900D03*
X913779Y92757D03*
X917125Y87714D03*
X933632Y89900D03*
Y71199D03*
Y87300D03*
X929811Y71500D03*
X927165Y92757D03*
X920472Y46914D03*
X933632Y35999D03*
X927165Y36049D03*
X927015Y46914D03*
X933608Y54700D03*
X933632Y46898D03*
X929811Y52614D03*
X913779Y65699D03*
X933658Y68550D03*
X927165Y65699D03*
X920472D03*
X913779Y54957D03*
X917125Y34100D03*
Y49914D03*
X929811Y87714D03*
X923432Y71500D03*
X920472Y92757D03*
X923518Y87714D03*
X933632Y84698D03*
X927015Y84714D03*
X923468Y90314D03*
X929811Y90414D03*
X917125D03*
X953936Y52614D03*
X957558Y50729D03*
X938732Y68340D03*
X950590Y65699D03*
X943897D03*
X938732Y49714D03*
Y52314D03*
X953936Y34100D03*
X950590Y54957D03*
X953936Y49914D03*
X947243Y34100D03*
X943897Y54957D03*
X947243Y49914D03*
X967322Y65814D03*
X960629D03*
X970669Y35957D03*
Y46914D03*
X967322Y54857D03*
X963976Y35957D03*
Y46914D03*
X960629Y54857D03*
X938758Y35750D03*
X938708Y46900D03*
X938732Y54914D03*
X938745Y65736D03*
X950590Y36049D03*
X953936Y67749D03*
X950590Y46914D03*
X970800Y50860D03*
X947243Y67749D03*
X943897Y36049D03*
Y46914D03*
X947243Y52614D03*
X957283Y35957D03*
X947243Y87714D03*
X963976Y73757D03*
X960629Y89964D03*
X963976Y87392D03*
X967322Y89964D03*
X970669Y87392D03*
Y73757D03*
X967322Y84714D03*
X938708Y84700D03*
X938732Y92714D03*
X938758Y73550D03*
X957600Y70400D03*
X970942Y69900D03*
X943897Y84714D03*
X947243Y90414D03*
X943897Y73849D03*
X950590D03*
X953886Y90414D03*
X950590Y84714D03*
X957774Y87394D03*
X957200Y73800D03*
X957283Y92657D03*
X938732Y70949D03*
Y87514D03*
Y90114D03*
X953936Y71900D03*
X950590Y92757D03*
X953936Y87714D03*
X947243Y71900D03*
X943897Y92757D03*
X960629Y84714D03*
X963976Y92657D03*
X970669Y92757D03*
X933658Y105265D03*
X913779Y112327D03*
X917125Y107284D03*
X933632Y110514D03*
X933658Y107865D03*
X927165Y112327D03*
X929811Y106934D03*
X920472Y112327D03*
X923518Y107284D03*
X929811Y109534D03*
X933632Y113114D03*
X923468Y109884D03*
X917125Y109984D03*
X920472Y104284D03*
X913779D03*
X927015D03*
X938732Y107655D03*
X938758Y110264D03*
X950590Y109700D03*
X953786Y107684D03*
X944497Y110927D03*
X947243Y105084D03*
X963245Y105725D03*
X938758Y112865D03*
X938745Y105051D03*
X947250Y107700D03*
X950600Y112300D03*
X953800Y105000D03*
X930987Y209109D03*
X937747Y201309D03*
Y209109D03*
X927607Y199360D03*
X924227Y201309D03*
Y209109D03*
Y205210D03*
X930987Y216909D03*
X934367Y203260D03*
Y211060D03*
X958026Y216909D03*
X944507D03*
X951267Y213009D03*
Y216909D03*
X944507Y197409D03*
Y205210D03*
Y209109D03*
X937747Y213009D03*
Y205210D03*
X917467Y209109D03*
X920847Y203260D03*
X927607D03*
Y207159D03*
X934367D03*
Y199360D03*
X930987Y201309D03*
X934367Y214960D03*
X930987Y213009D03*
X920847Y211060D03*
X927607Y214960D03*
Y211060D03*
X937747Y216909D03*
X924227D03*
Y213009D03*
X920847Y207159D03*
X927607Y218860D03*
X934367D03*
X930987Y205210D03*
X968166Y218860D03*
X951256Y194841D03*
X958026Y201309D03*
X967036Y193507D03*
X947887Y203260D03*
Y207159D03*
X944507Y213009D03*
Y201309D03*
X947887Y199360D03*
X941127D03*
Y207159D03*
X947887Y211060D03*
Y218860D03*
X941127D03*
Y214960D03*
X947887D03*
X954647D03*
X962526Y205210D03*
X961406Y214960D03*
Y211060D03*
Y218860D03*
X951267Y209109D03*
X958026Y213009D03*
X954647Y211060D03*
Y218860D03*
X941127Y203260D03*
Y211060D03*
X964786Y213009D03*
Y216909D03*
Y209109D03*
X930987Y248109D03*
X937747Y244209D03*
X927607Y246160D03*
X934367Y242260D03*
X930987Y228610D03*
X937747D03*
X927607Y222760D03*
X913700Y242260D03*
X920847D03*
Y250060D03*
X927607Y226660D03*
X917467Y248109D03*
X934367Y222760D03*
X927607Y238360D03*
X934367Y250060D03*
Y238360D03*
X917467Y271509D03*
X927607Y273460D03*
X924227Y271509D03*
X913787Y257860D03*
X920847Y261760D03*
Y253960D03*
X930987Y255909D03*
X934367Y269560D03*
X937747Y267609D03*
X927607Y261760D03*
X937747Y259809D03*
X934367Y261760D03*
X930987Y263709D03*
X947887Y222760D03*
X954647D03*
X951267Y220809D03*
X971546Y240309D03*
Y244209D03*
X961406Y242260D03*
X964786Y244209D03*
X961406Y246160D03*
X964786Y248109D03*
X958026D03*
X968166Y250060D03*
X971546Y279310D03*
X944507Y271509D03*
X964786Y263709D03*
Y275409D03*
X961406Y265660D03*
X971546Y271509D03*
X958026D03*
X968166Y265660D03*
Y273460D03*
X944507Y267609D03*
X947887Y269560D03*
X951267Y271509D03*
X947887Y273460D03*
X941127D03*
X944507Y232509D03*
X971546Y228610D03*
X968166Y222760D03*
X951267Y232509D03*
Y252009D03*
Y244209D03*
X947887Y257860D03*
X968166Y230559D03*
X964786Y228610D03*
X944507Y259809D03*
X954647Y234460D03*
X961406Y226660D03*
X944507Y240309D03*
X954647Y253960D03*
Y238360D03*
Y261760D03*
X951267Y263709D03*
X947887Y250060D03*
X944507Y252009D03*
X964786Y236409D03*
X961406Y234460D03*
X954647Y257860D03*
X968166Y234460D03*
X971546Y252009D03*
X937747Y240309D03*
X930987Y244209D03*
X934367Y226660D03*
X924227Y236409D03*
X920847Y238360D03*
X913787Y226660D03*
X913700Y222710D03*
X913787Y238360D03*
X924227Y232509D03*
X927607Y230559D03*
Y234460D03*
X930987Y232509D03*
X934367Y234460D03*
X924227Y228610D03*
X930987Y220809D03*
X924227Y224709D03*
X937747Y232509D03*
Y236409D03*
X924227Y240309D03*
X917467D03*
X930987D03*
X924227Y248109D03*
Y244209D03*
X917467D03*
X913787Y250060D03*
X934367Y246160D03*
X927607Y250060D03*
X924227Y220809D03*
X937747Y224709D03*
X934367Y230559D03*
X913787Y246160D03*
X920847D03*
X937747Y220809D03*
X930987Y224709D03*
Y236409D03*
X937747Y248109D03*
X927607Y242260D03*
X937747Y279310D03*
X917000Y276000D03*
X920847Y277360D03*
X924227Y279310D03*
X913787Y273460D03*
Y253960D03*
X927607D03*
X934367D03*
X937747Y252009D03*
X930987D03*
X924227D03*
X917467D03*
Y259809D03*
X924227D03*
X930987D03*
X920847Y265660D03*
X930987Y275409D03*
X937747D03*
Y271509D03*
Y255909D03*
X934367Y277360D03*
X930987Y271509D03*
X934367Y273460D03*
X927607Y269560D03*
X917467Y263709D03*
X913787Y265660D03*
X924227Y267609D03*
X934367Y265660D03*
X924227Y263709D03*
Y275409D03*
X927607Y277360D03*
X920847Y273460D03*
Y269560D03*
X924227Y255909D03*
X920847Y257860D03*
X913787Y261760D03*
X917467Y255909D03*
X930987Y267609D03*
X937747Y263709D03*
X927607Y257860D03*
X934367D03*
X927607Y265660D03*
X916967Y279310D03*
X930987D03*
X951267Y248109D03*
X958026Y244209D03*
X968166Y242260D03*
X944507Y228610D03*
Y224709D03*
Y244209D03*
Y248109D03*
X941127Y242260D03*
Y250060D03*
Y246160D03*
X947887D03*
X941127Y222760D03*
X947887Y226660D03*
Y234460D03*
X941127Y238360D03*
Y234460D03*
Y230559D03*
Y226660D03*
X971546Y248109D03*
X968166Y246160D03*
X958026Y220809D03*
X944507D03*
X951267Y224709D03*
Y240309D03*
X958026D03*
X964786D03*
X954647Y246160D03*
Y250060D03*
X958026Y228610D03*
Y236409D03*
X961406Y238360D03*
X951267Y228610D03*
X954647Y226660D03*
X958026Y224709D03*
Y232509D03*
X954647Y230559D03*
X961406Y222760D03*
X968166Y226660D03*
X971546Y236409D03*
X968166Y238360D03*
X971546Y220809D03*
X964786Y232509D03*
Y220809D03*
X944507Y279310D03*
X947887Y253960D03*
X941127D03*
X958026Y252009D03*
X968166Y277360D03*
X951267Y275409D03*
X961406Y277360D03*
X958026Y263709D03*
X968166Y269560D03*
X961406Y261760D03*
X958026Y255909D03*
X951267Y259809D03*
X958026D03*
X954647Y277360D03*
Y265660D03*
X951267Y267609D03*
X954647Y273460D03*
X958026Y275409D03*
X954647Y269560D03*
X961406D03*
X971546Y275409D03*
Y263709D03*
X941127Y277360D03*
Y265660D03*
X944507Y275409D03*
Y263709D03*
X941127Y269560D03*
Y257860D03*
Y261760D03*
X947887Y277360D03*
Y265660D03*
X971546Y259809D03*
Y255909D03*
X964786Y279310D03*
Y267609D03*
Y271509D03*
X961406Y273460D03*
X971546Y267609D03*
X958026D03*
Y279310D03*
X951267D03*
X947887Y230559D03*
X971546Y224709D03*
X944507Y236409D03*
X954647Y242260D03*
X947887Y261760D03*
X951267Y236409D03*
X947887Y238360D03*
X951267Y255909D03*
X971546Y232509D03*
X947887Y242260D03*
X944507Y255909D03*
X964786Y224709D03*
X961406Y230559D03*
X913787Y335860D03*
X920847Y331960D03*
Y339760D03*
X930987Y330009D03*
Y341709D03*
X937747Y330009D03*
X927607Y335860D03*
X934367D03*
Y320260D03*
X927607Y324160D03*
X947887Y335860D03*
X954647D03*
X944507Y341709D03*
X951267D03*
X968166Y331960D03*
X964786Y326110D03*
X947887Y320260D03*
X941127D03*
X944507Y330009D03*
X961406Y331960D03*
X971546Y326110D03*
Y341709D03*
X944507Y326110D03*
X937747Y287109D03*
X920500Y304660D03*
Y300760D03*
X930987Y302709D03*
X924227D03*
X920500Y311960D03*
X927607Y304660D03*
X924227Y306609D03*
X930987D03*
Y310509D03*
X934367Y304660D03*
X924227Y310509D03*
X920500Y308560D03*
Y289060D03*
X934367Y296860D03*
X930987Y294909D03*
X920500Y296860D03*
Y292959D03*
X927607Y296860D03*
X924227Y298809D03*
X930987D03*
X924227Y283209D03*
X927607Y281260D03*
X920500Y285500D03*
X924227Y287109D03*
X920847Y281260D03*
X930987Y287109D03*
X934367Y289060D03*
Y285160D03*
Y300760D03*
X927607D03*
Y308560D03*
X934367D03*
X927607Y285160D03*
Y292959D03*
X934367D03*
Y281260D03*
X930987Y283209D03*
X924227Y291009D03*
X930987D03*
X927607Y289060D03*
X937747Y302709D03*
Y306609D03*
Y310509D03*
Y283209D03*
Y291009D03*
Y294909D03*
Y298809D03*
X920847Y335860D03*
X913787Y331960D03*
X917467Y337809D03*
X937747Y333909D03*
X927607Y339760D03*
X934367Y328060D03*
Y339760D03*
X927607Y331960D03*
X930987Y333909D03*
X937747Y337809D03*
Y314409D03*
X924227D03*
X930987D03*
X934367Y312460D03*
X927607D03*
X920847Y324160D03*
X924227Y318309D03*
X920547Y316160D03*
X917167Y318309D03*
Y322209D03*
X917467Y326110D03*
X920847Y320260D03*
X937747Y318309D03*
Y341709D03*
Y326110D03*
X917467Y333909D03*
Y341709D03*
X913787Y339760D03*
X924227Y333909D03*
Y337809D03*
Y341709D03*
X913787Y328060D03*
X924227Y330009D03*
X920847Y328060D03*
X917467Y330009D03*
X930987Y326110D03*
X934367Y331960D03*
X927607Y328060D03*
X934367Y324160D03*
X924227Y322209D03*
X927607Y320260D03*
X930987Y318309D03*
X934367Y316360D03*
X927607D03*
X930987Y337809D03*
X924227Y326110D03*
X971546Y294909D03*
X944507Y283209D03*
X961406Y292959D03*
Y285160D03*
X954647Y292959D03*
Y285160D03*
X968166Y292959D03*
Y300760D03*
X971546Y310509D03*
X964786D03*
X954647Y308560D03*
X961406D03*
X954647Y300760D03*
X961406D03*
X964786Y283209D03*
X971546D03*
X947887Y308560D03*
X941127D03*
Y300760D03*
X947887D03*
X941127Y285160D03*
Y292959D03*
X947887D03*
Y285160D03*
X968166Y281260D03*
X964786Y291009D03*
X954647Y281260D03*
X958026Y283209D03*
X951267Y287109D03*
X958026D03*
X951267Y283209D03*
X961406Y281260D03*
Y296860D03*
X964786Y298809D03*
Y302709D03*
X971546D03*
X961406Y304660D03*
X958026Y302709D03*
X951267D03*
X968166Y308560D03*
X964786Y306609D03*
X968166Y304660D03*
X971546Y306609D03*
X951267Y310509D03*
X954647Y304660D03*
X958026Y306609D03*
Y310509D03*
X951267Y306609D03*
X944507Y302709D03*
Y306609D03*
Y310509D03*
X941127Y304660D03*
X947887D03*
X944507Y294909D03*
Y287109D03*
X971546Y298809D03*
X968166Y285160D03*
X964786Y287109D03*
X944507Y291009D03*
X941127Y281260D03*
Y289060D03*
Y296860D03*
X944507Y298809D03*
X947887Y289060D03*
Y296860D03*
Y281260D03*
X968166Y296860D03*
X964786Y294909D03*
X971546Y291009D03*
Y287109D03*
X968166Y289060D03*
X961406D03*
X958026Y298809D03*
X951267D03*
Y291009D03*
X958026D03*
X954647Y289060D03*
Y296860D03*
X958026Y294909D03*
X951267D03*
X958026Y333909D03*
Y337809D03*
Y341709D03*
Y318309D03*
X951267D03*
X954647Y316360D03*
X961406D03*
Y324160D03*
X971546Y337809D03*
X964786Y330009D03*
X971546D03*
X951267D03*
X958026D03*
X954647Y339760D03*
X951267Y333909D03*
X944507Y337809D03*
X968166Y312460D03*
X964786Y314409D03*
X951267Y337809D03*
X954647Y331960D03*
Y328060D03*
X971546Y322209D03*
X968166Y320260D03*
X964786Y322209D03*
X968166Y335860D03*
X947887Y339760D03*
X944507Y314409D03*
X951267D03*
X958026D03*
X961406Y312460D03*
X954647D03*
X941127D03*
X947887D03*
X971546Y314409D03*
Y318309D03*
X964786D03*
X951267Y322209D03*
X954647Y324160D03*
X961406Y320260D03*
X954647D03*
X958026Y322209D03*
X951267Y326110D03*
X968166Y316360D03*
X958026Y326110D03*
X947887Y316360D03*
X941127D03*
X944507Y322209D03*
Y318309D03*
X947887Y331960D03*
Y328060D03*
X941127Y331960D03*
Y328060D03*
Y339760D03*
Y335860D03*
X944507Y333909D03*
X968166Y328060D03*
Y324160D03*
X964786Y333909D03*
X961406Y328060D03*
X971546Y333909D03*
X934367Y367060D03*
X913787Y351460D03*
X920847D03*
X927607Y370959D03*
X917467Y345609D03*
X934367Y347560D03*
X927607Y359260D03*
X934367Y355360D03*
X927607Y351460D03*
X937747Y372909D03*
X927607Y378760D03*
X934367D03*
Y386560D03*
X930987Y392410D03*
X937747Y396309D03*
X930987Y400209D03*
X917467Y392410D03*
X924227Y396309D03*
X971546Y357309D03*
X951267Y365109D03*
Y353409D03*
X944507Y365109D03*
X961406Y367060D03*
X964786Y361209D03*
X947887Y347560D03*
X954647Y359260D03*
X971546Y345609D03*
X944507Y357309D03*
X971546Y365109D03*
X958026Y349509D03*
X947887Y382660D03*
X958026Y376809D03*
X944507D03*
X954647Y382660D03*
X951267Y372909D03*
X944507Y392410D03*
X941127Y386560D03*
X971546Y372909D03*
X964786D03*
X944507Y400209D03*
X964786Y384609D03*
Y380709D03*
X930987Y369010D03*
X937747D03*
X913787Y347560D03*
X920847Y343660D03*
X934367Y359260D03*
X930987Y361209D03*
X937747Y349509D03*
X927607Y355360D03*
X937747Y353409D03*
X930987Y349509D03*
X937747Y357309D03*
X930987Y353409D03*
X937747Y365109D03*
Y345609D03*
Y361209D03*
X924227Y365109D03*
X930987D03*
X927607Y367060D03*
X934367Y370959D03*
Y363160D03*
X927607D03*
X924227Y369010D03*
X913787Y343660D03*
X934367D03*
X927607D03*
Y347560D03*
X934367Y351460D03*
X930987Y357309D03*
Y345609D03*
X917467Y353409D03*
Y349509D03*
X913787Y355360D03*
X924227Y349509D03*
Y345609D03*
Y353409D03*
Y361209D03*
Y357309D03*
X920847Y355360D03*
X917167Y361209D03*
Y369010D03*
X920847Y347560D03*
X934367Y382660D03*
X930987Y384609D03*
Y376809D03*
X934367Y390460D03*
X927607Y386560D03*
Y390460D03*
X930987Y396309D03*
X934367Y398260D03*
X927607Y394359D03*
X917467Y388509D03*
X924227Y392410D03*
X920847Y390460D03*
X930987Y380709D03*
X927607Y374860D03*
X934367D03*
X937747Y376809D03*
X930987Y372909D03*
X934367Y394359D03*
X930987Y388509D03*
X937747D03*
Y384609D03*
Y392410D03*
X924227Y400209D03*
X920847Y394359D03*
Y398260D03*
X927607D03*
X924227Y372909D03*
X937747Y400209D03*
X917100Y380709D03*
X937747D03*
X924227D03*
X920847Y382660D03*
X924227Y376809D03*
X927607Y382660D03*
X968166Y370959D03*
X958026Y361209D03*
X954647Y347560D03*
X961406Y359260D03*
X958026Y357309D03*
X951267D03*
X941127Y355360D03*
Y347560D03*
Y351460D03*
X958026Y345609D03*
X951267Y349509D03*
X954647Y351460D03*
X958026Y353409D03*
X968166Y355360D03*
Y351460D03*
X971546Y353409D03*
X947887Y367060D03*
X954647Y355360D03*
X944507Y361209D03*
X968166Y363160D03*
X961406D03*
X971546Y369010D03*
X944507Y345609D03*
X951267D03*
X947887Y355360D03*
X951267Y361209D03*
X968166Y367060D03*
X964786Y357309D03*
X971546Y361209D03*
X968166Y359260D03*
X958026Y365109D03*
X964786D03*
X954647Y370959D03*
Y367060D03*
X958026Y369010D03*
X951267D03*
X961406Y370959D03*
X954647Y363160D03*
X947887Y359260D03*
X964786Y369010D03*
X954647Y343660D03*
X971546Y349509D03*
X947887Y363160D03*
X941127D03*
X947887Y370959D03*
X941127D03*
Y367060D03*
X944507Y369010D03*
X947887Y343660D03*
X941127Y359260D03*
X944507Y349509D03*
Y353409D03*
X941127Y343660D03*
X947887Y351460D03*
X964786Y349509D03*
Y353409D03*
X961406Y355360D03*
Y347560D03*
Y351460D03*
X958026Y380709D03*
X954647Y374860D03*
X951267Y376809D03*
Y384609D03*
Y380709D03*
X944507Y388509D03*
X941127Y394359D03*
X968166Y374860D03*
X958026Y372909D03*
X941127Y374860D03*
X961406D03*
X944507Y372909D03*
X941127Y382660D03*
Y378760D03*
X947887D03*
X944507Y384609D03*
X947887Y390460D03*
Y386560D03*
X941127Y390460D03*
X947887Y398260D03*
X941127D03*
X944507Y396309D03*
X947887Y394359D03*
X964786Y376809D03*
X971546D03*
X968166Y378760D03*
Y386560D03*
X964786Y392410D03*
X968166Y390460D03*
Y394359D03*
X964786Y388509D03*
X961406Y378760D03*
X954647D03*
X958026Y384609D03*
X961406Y382660D03*
X951267Y388509D03*
X958026D03*
X954647Y394359D03*
X961406Y386560D03*
X952216Y402421D03*
X970416Y401941D03*
X971546Y380709D03*
X968166Y382660D03*
X947887Y374860D03*
X944507Y380709D03*
X933632Y515300D03*
Y512700D03*
X927165Y518157D03*
X929811Y513114D03*
X920472Y518157D03*
X923518Y513114D03*
X920700Y495944D03*
X913800Y495800D03*
X927165Y495944D03*
X929811Y515814D03*
X933632Y510098D03*
X923600Y491144D03*
X917192Y491219D03*
X933632Y490644D03*
X929811D03*
X933632Y498644D03*
X933608Y517900D03*
X913779Y510114D03*
X917125Y515814D03*
X923468Y515714D03*
X920472Y510114D03*
X927015D03*
X913779Y518157D03*
X917125Y513114D03*
X938732Y490644D03*
X950700Y490700D03*
X943897Y490444D03*
X970669Y512792D03*
X967322Y515364D03*
X963976Y512792D03*
X960629Y515364D03*
X967322Y510114D03*
X938708Y510100D03*
X938732Y518114D03*
Y498644D03*
X954000Y497300D03*
X953886Y515814D03*
X950590Y510114D03*
X943897D03*
X947243Y515814D03*
X947443Y497644D03*
X957774Y512794D03*
X957283Y518057D03*
X938732Y512914D03*
Y515514D03*
X943897Y518157D03*
X947243Y513114D03*
X961309Y499136D03*
X947443Y494944D03*
X944000Y493100D03*
X923600Y493744D03*
X929811Y493244D03*
X933647Y493344D03*
X938732D03*
X917192Y493919D03*
X920700Y498644D03*
X927165D03*
X938732Y495944D03*
X933647D03*
X913779Y498487D03*
X954000Y494700D03*
X950700Y493300D03*
X960629Y510114D03*
X963976Y518057D03*
X970669Y518157D03*
X953936Y513114D03*
X950590Y518157D03*
X933658Y531750D03*
X929811Y534700D03*
X927165Y528899D03*
X923432Y534700D03*
X920472Y528899D03*
X933632Y536999D03*
X929811Y531100D03*
X933658Y529150D03*
X913779Y537049D03*
X917125Y530949D03*
X927015Y537049D03*
X923432Y530949D03*
X920472Y536999D03*
X923468Y553514D03*
X917125Y553614D03*
X913779Y547914D03*
X927015D03*
X920472D03*
X933632Y547898D03*
X929811Y553614D03*
X917125Y535100D03*
X913779Y528899D03*
X933608Y555700D03*
X933632Y585698D03*
X933658Y566950D03*
X929811Y568900D03*
X933632Y574799D03*
X920472D03*
X927015Y585714D03*
X920472D03*
X913779Y574849D03*
X917125Y568749D03*
X913779Y585714D03*
X923432Y568749D03*
X927015Y574849D03*
X960629Y529014D03*
X963976Y536957D03*
X970669D03*
X967322Y529014D03*
X963976Y547914D03*
X970669D03*
X938745Y528936D03*
X938758Y536750D03*
X938708Y547900D03*
X957600Y533100D03*
X970942D03*
X957701Y552000D03*
X970731D03*
X950590Y537049D03*
X957283Y536957D03*
X953936Y530949D03*
X957283Y548200D03*
X953886Y553614D03*
X950590Y547914D03*
X947243Y530949D03*
X943897Y537049D03*
Y547914D03*
X947243Y553614D03*
X938732Y534149D03*
Y531540D03*
X947243Y535100D03*
X953936Y588714D03*
X967322Y555857D03*
X960629D03*
X970669Y585714D03*
Y574757D03*
X960629Y566814D03*
X963976Y585714D03*
Y574757D03*
X967322Y566814D03*
X938732Y555914D03*
X938745Y566736D03*
X938758Y574550D03*
X938708Y585700D03*
X957600Y570900D03*
X970942D03*
X950590Y574849D03*
Y585714D03*
X957283Y574757D03*
X957456Y588334D03*
X953936Y568749D03*
X943897Y574849D03*
X947243Y568749D03*
X943897Y585714D03*
X938732Y588514D03*
X933632Y588300D03*
X929811Y588714D03*
X923518D03*
X947243D03*
Y550914D03*
X923518D03*
X929811D03*
X938732Y553314D03*
X933632Y550500D03*
X938732Y550714D03*
X933632Y553100D03*
X917125Y550914D03*
X943897Y566699D03*
X947243Y572900D03*
X943897Y555957D03*
X920472Y566699D03*
X923432Y572500D03*
X920472Y555957D03*
X927165Y566699D03*
X929811Y572500D03*
X927165Y555957D03*
X938732Y571949D03*
X933658Y569550D03*
X913779Y555957D03*
X953936Y550914D03*
Y572900D03*
X950590Y555957D03*
X917125Y588714D03*
X950590Y528899D03*
X953936Y535100D03*
X933632Y534399D03*
X943897Y528899D03*
X938732Y569340D03*
X933632Y572199D03*
X913779Y566699D03*
X917125Y572900D03*
X950590Y566699D03*
X933632Y612599D03*
X923432Y606549D03*
X917125D03*
X933658Y604750D03*
X917125Y610700D03*
X913779Y593757D03*
X929811Y610300D03*
X927165Y593757D03*
X923468Y591314D03*
X917125Y591414D03*
X933608Y593500D03*
X929811Y591414D03*
X927015Y612449D03*
X920472Y612399D03*
X913779Y612449D03*
X929811Y606700D03*
X950590Y604499D03*
X967322Y593657D03*
X963976Y612457D03*
X970669D03*
X960629Y604614D03*
X967322D03*
X960629Y593657D03*
X967322Y609864D03*
X938758Y612350D03*
X938745Y604536D03*
X938732Y593714D03*
X957500Y591000D03*
X970731Y589800D03*
X953936Y606549D03*
X957283Y611600D03*
X950590Y612249D03*
X953886Y591414D03*
X947243Y606549D03*
X943897Y612249D03*
X947243Y591414D03*
X957765Y607220D03*
X938732Y609749D03*
Y607140D03*
Y591114D03*
X953936Y610700D03*
X950590Y593757D03*
X933632Y590900D03*
Y609999D03*
X927165Y604499D03*
X923432Y610300D03*
X920472Y593757D03*
Y604499D03*
X947243Y610700D03*
X943897Y593757D03*
Y604499D03*
X963976Y607292D03*
X970669D03*
X913779Y604499D03*
X933658Y607350D03*
X960629Y609864D03*
X1025670Y6640D03*
X1023740Y18150D03*
X980708Y-4536D03*
X987401Y-9901D03*
X997441Y-7108D03*
X990748Y-1743D03*
X977362Y-7108D03*
X980708Y9114D03*
X990748Y9122D03*
X977362Y28014D03*
X987401D03*
Y17057D03*
X977362D03*
X997441Y28022D03*
Y17057D03*
X983900Y13200D03*
Y32100D03*
X1028400Y6500D03*
X1030407Y-8938D03*
X1000787Y-4536D03*
Y9122D03*
X1017519Y-1858D03*
Y-9786D03*
X1007480Y-1858D03*
X1007280Y9114D03*
X1017519D03*
X1007480Y-9786D03*
X1020866Y-1858D03*
X1027202Y-11005D03*
X1028639Y-6615D03*
X1008200Y30736D03*
X1014173Y28014D03*
X1010826D03*
X1007480Y17014D03*
Y28014D03*
X1017519D03*
Y17042D03*
X1025291Y20734D03*
X1007100Y11714D03*
X1008227Y33342D03*
X1030400Y26150D03*
X1030450Y23150D03*
X1007100Y14314D03*
X1026700Y1700D03*
X984055Y-7108D03*
X990748D03*
X987401Y-4536D03*
X994094Y-9786D03*
Y-4536D03*
X997441Y-1743D03*
X1000787Y-9901D03*
X1004133Y-1742D03*
X1004134Y-7108D03*
X980708Y-9786D03*
X984055Y-1743D03*
X1010826Y9114D03*
Y-1858D03*
X1012270Y17014D03*
X1010826Y-9786D03*
X1014173Y9114D03*
Y-1858D03*
X1014919Y17042D03*
X1014173Y-9786D03*
X974015Y-4536D03*
Y-9901D03*
X977362Y-1743D03*
X1020650Y46900D03*
X987401Y65814D03*
X977362D03*
X987401Y54857D03*
X977362D03*
X990748Y46922D03*
Y35957D03*
X980708D03*
Y46914D03*
X997441Y65822D03*
Y54857D03*
X983900Y51000D03*
X997441Y92757D03*
X990748Y73757D03*
Y87392D03*
X977362Y92757D03*
X987401Y89964D03*
X980708Y84714D03*
Y73757D03*
X983900Y69900D03*
X1007370Y52333D03*
Y49659D03*
X1014173Y54842D03*
Y35942D03*
X1013873Y46914D03*
X1010826Y54842D03*
Y35942D03*
X1011126Y46914D03*
X1000787Y35957D03*
Y46922D03*
X1017519Y54842D03*
X1007480Y46914D03*
X1008226Y54842D03*
X1008217Y35942D03*
X1007480Y65736D03*
X1016600Y65950D03*
X1017519Y35942D03*
Y46914D03*
X1030300Y63200D03*
X1014350Y73000D03*
X1017919Y92500D03*
X1017519Y87500D03*
X1000787Y84599D03*
Y73757D03*
X1007480Y87500D03*
X1007573Y92500D03*
X1008099Y73479D03*
X1017350Y73450D03*
X1024945Y86377D03*
Y83877D03*
X1007380Y68335D03*
X1030400Y56500D03*
X1031600Y42900D03*
X1007380Y70935D03*
X1023900Y74100D03*
Y77200D03*
X984055Y92757D03*
X990748D03*
X987401Y84599D03*
X994094Y89964D03*
Y84714D03*
X997441Y87392D03*
X1000787Y89964D03*
X1004023Y87392D03*
Y92757D03*
X980708Y89964D03*
X984055Y87392D03*
X974015Y84599D03*
Y89964D03*
X977362Y87392D03*
X1012043Y87500D03*
X1012400Y92500D03*
X1014842Y87500D03*
X1015215Y92500D03*
X976200Y105600D03*
X974100Y103500D03*
X976700Y103021D03*
X991826Y213009D03*
X988446Y214960D03*
X991826Y216909D03*
X988446Y207158D03*
Y203258D03*
X995206Y211060D03*
X998586Y213009D03*
X1025625Y216909D03*
X1015485Y218860D03*
X1022245D03*
X1032385Y213009D03*
X1029005Y207159D03*
X1012105Y213009D03*
X1008725Y218860D03*
X1005345Y216909D03*
X1025625Y213009D03*
X991826Y209109D03*
X995206Y207159D03*
X1022245D03*
X1005345Y213009D03*
X1029005Y218860D03*
X1001965D03*
X1018865Y213009D03*
X995206Y218860D03*
X983936Y199108D03*
X973808Y201308D03*
X998586Y209109D03*
Y216909D03*
X995206Y203260D03*
X988446Y218860D03*
X995206Y214960D03*
X981686Y218860D03*
X974926Y211060D03*
X985066Y216909D03*
X988446Y211058D03*
X979426Y214958D03*
X1012105Y216909D03*
X1008725Y211060D03*
X1001965Y214960D03*
X1027875Y193507D03*
X1032385Y201309D03*
X1015485Y203260D03*
Y214960D03*
X1022245D03*
X1012105Y205210D03*
X1025625Y205211D03*
X1029005Y214960D03*
X1007595Y193507D03*
X1005345Y205210D03*
X1008725Y214960D03*
X1005345Y209109D03*
X1001965Y211060D03*
X1025625Y209109D03*
X1012105D03*
X1032385D03*
X998586Y205210D03*
X991826D03*
X1022245Y211060D03*
X1018865Y216909D03*
X1032385D03*
X978306Y236409D03*
Y240309D03*
Y244209D03*
X974926Y246160D03*
X985066Y240309D03*
X981686Y246160D03*
X991826Y224709D03*
X988446Y222760D03*
X998586Y228610D03*
X985066Y220809D03*
X981686Y222760D03*
X978306Y224709D03*
X981686Y226660D03*
X985066Y228610D03*
X978306D03*
X981686Y230559D03*
X985066Y232509D03*
X995206Y250060D03*
X998586Y252009D03*
X995206Y253960D03*
X998586Y255909D03*
X995206Y257860D03*
X998586Y259809D03*
X995206Y261760D03*
X988446Y269560D03*
X985066Y271509D03*
X978306D03*
X988446Y273460D03*
X981686D03*
X985066Y275409D03*
X978306D03*
X988446Y277360D03*
X981686D03*
X974926D03*
X985066Y279310D03*
X978306D03*
X1025625Y224709D03*
X1022245Y222760D03*
X1018865Y224709D03*
X1012105D03*
X1032385D03*
X1029005Y222760D03*
X1005345Y224709D03*
X1001965Y230559D03*
X1012105Y248109D03*
X1008725Y250060D03*
X1001965D03*
X1032385Y240309D03*
X1029005Y242260D03*
X1032385Y244209D03*
X1025625D03*
X1029005Y246160D03*
X1022245D03*
X1015485D03*
X1018865Y248109D03*
X1015485Y250060D03*
X1005345Y252009D03*
X1008725Y253960D03*
X1001965D03*
X1005345Y255909D03*
X1001965Y257860D03*
X1012105Y252009D03*
X985066Y263709D03*
X988446Y257860D03*
X1022245Y242260D03*
X1018865Y228610D03*
X1012105Y236409D03*
X1018865D03*
X1015485Y230559D03*
X1022245D03*
X991826Y236409D03*
Y228610D03*
X995206Y242260D03*
X1015485D03*
X1029005Y230559D03*
X998586Y236409D03*
Y224709D03*
X1008725Y246160D03*
X1001965Y242260D03*
X1005345Y236409D03*
X1008725Y230559D03*
Y242260D03*
X1001965Y246160D03*
X1025625Y236409D03*
X981686Y257860D03*
Y265660D03*
Y253960D03*
X974926Y261760D03*
Y257860D03*
X978306Y263709D03*
X1032385Y236409D03*
X995206Y222760D03*
X1022245Y234460D03*
X991826Y240309D03*
X995206Y234460D03*
X1008725D03*
X1032385Y228610D03*
X995206Y238360D03*
X988446Y234460D03*
X998586Y248109D03*
Y220809D03*
X985066Y248109D03*
X981686Y250060D03*
X974926D03*
X988446Y246160D03*
Y250060D03*
Y230560D03*
X978306Y248109D03*
X974926Y238360D03*
X985066Y244209D03*
X981686Y238360D03*
X995206Y230559D03*
X981686Y242260D03*
X974926D03*
X988446D03*
X998586Y244209D03*
Y232509D03*
X991826Y244209D03*
Y232509D03*
X995206Y226660D03*
X991826Y248109D03*
X988446Y238360D03*
X985066Y236409D03*
X981686Y234460D03*
X974926Y226660D03*
X991826Y220809D03*
X974926Y230559D03*
Y234460D03*
Y222760D03*
X985066Y224709D03*
X978306Y232509D03*
Y220809D03*
X974926Y253960D03*
X988446D03*
X978306Y252009D03*
X985066D03*
X974926Y265660D03*
X991826Y259809D03*
X985066D03*
X981686Y269560D03*
X995206D03*
X985066Y267609D03*
X991826Y263709D03*
X988446Y265660D03*
X998586Y263709D03*
X991826Y271509D03*
X995206Y273460D03*
X991826Y279310D03*
Y275409D03*
X974926Y269560D03*
X978306Y267609D03*
Y259809D03*
X991826Y255909D03*
X995206Y265660D03*
X991826Y252009D03*
Y267609D03*
X974926Y273460D03*
X995206Y277360D03*
X998586Y267609D03*
Y271509D03*
Y275409D03*
Y279310D03*
X1029005Y238360D03*
X1015485Y222760D03*
X1008725D03*
X1032385Y232509D03*
X1018865Y244209D03*
X1012105D03*
X1018865Y232509D03*
X1015485Y226660D03*
X1022245D03*
X1012105Y232509D03*
X1025625D03*
X1029005Y226660D03*
X1005345Y244209D03*
X1008725Y226660D03*
X1005345Y232509D03*
X1001965Y226660D03*
X1005345Y248109D03*
X1008725Y238360D03*
X1001965D03*
X1005345Y220809D03*
X1029005Y250060D03*
X1032385Y248109D03*
X1025625D03*
X1022245Y250060D03*
X1025625Y220809D03*
X1012105D03*
X1015485Y238360D03*
X1022245D03*
X1018865Y220809D03*
X1032385D03*
X1001965Y261760D03*
X1012105Y255909D03*
X1022245Y253960D03*
X1025625Y252009D03*
X1017735Y264300D03*
X1014355Y266300D03*
X1021115Y262300D03*
X1024495Y260300D03*
X1027875Y258400D03*
X1031255Y256400D03*
X1005345Y263709D03*
X1001965Y265660D03*
X1009256Y269777D03*
X1008725Y261760D03*
X1006665Y277360D03*
X1006700Y270700D03*
X1006665Y273460D03*
X1011100Y268100D03*
X1015485Y257860D03*
X1018865Y255909D03*
X1012105Y259809D03*
X1015485Y253960D03*
X1018865Y252009D03*
X1005345Y259809D03*
X1008725Y257860D03*
X988446Y261760D03*
X1012105Y228610D03*
X1015485Y234460D03*
X1001965D03*
X998586Y240309D03*
X1001965Y222760D03*
X1025625Y228610D03*
X1005345Y240309D03*
Y228610D03*
X1012105Y240309D03*
X1029005Y234460D03*
X1025625Y240309D03*
X995206Y246160D03*
X1018865Y240309D03*
X981686Y261760D03*
X985066Y255909D03*
X978306D03*
X1004215Y277360D03*
Y273460D03*
Y269560D03*
X1007595Y267609D03*
X1010975Y265660D03*
X1014355Y263709D03*
X1017735Y261760D03*
X1021115Y259809D03*
X1024495Y257860D03*
X1027875Y255909D03*
X1031255Y253960D03*
X998586Y337809D03*
X991826D03*
X978306D03*
X985066Y333909D03*
X974926Y331960D03*
X1001965Y339760D03*
X1005345Y341709D03*
X998586D03*
X995206Y296860D03*
X985066Y294909D03*
X981686Y281260D03*
Y292959D03*
Y300760D03*
X988446D03*
X978306Y310509D03*
X991826D03*
X985066D03*
X974926Y300760D03*
X988446Y292959D03*
X991826Y283209D03*
X988446Y281260D03*
X985066Y283209D03*
X978306D03*
X974926Y292959D03*
Y281260D03*
X985066Y287109D03*
X988446Y285160D03*
X991826Y287109D03*
X995206Y281260D03*
X978306Y298809D03*
Y287109D03*
X981686Y285160D03*
X978306Y294909D03*
X981686Y296860D03*
Y289060D03*
X978306Y291009D03*
X998586Y302709D03*
Y306609D03*
Y310509D03*
Y287109D03*
Y294909D03*
Y291009D03*
Y298809D03*
Y283209D03*
X985066Y302709D03*
X978306D03*
X988446Y304660D03*
Y308560D03*
X985066Y306609D03*
X995206Y304660D03*
Y308560D03*
X991826Y306609D03*
X978306D03*
X981686Y308560D03*
Y304660D03*
X974926D03*
Y308560D03*
X995206Y300760D03*
X991826Y302709D03*
X974926Y285160D03*
Y296860D03*
Y289060D03*
X995206Y292959D03*
X988446Y296860D03*
X991826Y294909D03*
X995206Y289060D03*
X988446D03*
X991826Y291009D03*
X985066D03*
X995206Y285160D03*
X985066Y298809D03*
X991826D03*
Y333909D03*
X995206Y335860D03*
Y339760D03*
Y328060D03*
X991826Y326110D03*
X981686Y339760D03*
X978306Y333909D03*
Y330009D03*
Y326110D03*
X981686Y331960D03*
X985066Y330009D03*
X974926Y324160D03*
X988446Y339760D03*
X981686Y335860D03*
X978306Y341709D03*
X974926Y312460D03*
X981686D03*
X988446D03*
X991826Y314409D03*
Y330009D03*
X995206Y331960D03*
X988446D03*
X995206Y324160D03*
X988446Y316360D03*
X991826Y318309D03*
X995206Y320260D03*
X991826Y322209D03*
X998586Y333909D03*
X985066Y337809D03*
Y341709D03*
X974926Y328060D03*
X998586Y314409D03*
X995206Y312460D03*
X998586Y318309D03*
Y322209D03*
Y326110D03*
Y330009D03*
X995206Y316360D03*
X985066Y314409D03*
X978306D03*
Y318309D03*
Y322209D03*
X981686Y320260D03*
X974926Y316360D03*
Y320260D03*
X985066Y326110D03*
X981686Y328060D03*
X988446D03*
Y324160D03*
X985066Y318309D03*
Y322209D03*
X988446Y320260D03*
X981686Y324160D03*
X974926Y339760D03*
Y335860D03*
X981686Y316360D03*
X1006665Y300760D03*
Y304660D03*
Y308560D03*
Y285160D03*
Y296860D03*
Y289060D03*
Y281260D03*
Y292959D03*
X1008725Y335860D03*
X1005345Y333909D03*
X1001965Y331960D03*
X1007595Y327609D03*
X1021115Y335409D03*
X1018865Y341709D03*
X1017735Y333460D03*
X1015485Y339760D03*
X1024495Y337360D03*
X1012105Y337809D03*
X1016399Y324304D03*
X1022393Y326580D03*
X1024893D03*
X1017393D03*
X1028393Y329580D03*
X1019893Y326580D03*
X1027393D03*
X1017957Y312421D03*
X1025438Y312381D03*
X1022915Y312372D03*
X1020404Y312408D03*
X1028039Y312414D03*
X1025755Y328951D03*
X1008725Y339760D03*
X1005345Y337809D03*
X1001965Y335860D03*
X1012105Y341709D03*
X1006665Y312460D03*
X1014355Y331509D03*
X1010975Y329560D03*
X1027875Y339309D03*
X1031255Y341260D03*
X1006665Y324160D03*
Y316360D03*
Y320260D03*
X991826Y341709D03*
X988446Y335860D03*
X1027875Y341709D03*
X1024495Y339760D03*
X1021115Y337809D03*
X1017735Y335860D03*
X1014355Y333909D03*
X1010975Y331960D03*
X1007595Y330009D03*
X1004215Y328060D03*
Y324160D03*
Y320260D03*
Y316360D03*
Y312460D03*
Y308560D03*
Y304660D03*
Y300760D03*
Y296860D03*
Y292959D03*
Y289060D03*
Y285160D03*
Y281260D03*
X978306Y361209D03*
X974926Y351460D03*
X981686D03*
X995206Y367060D03*
X988446Y370959D03*
X981686Y343660D03*
X991826Y349509D03*
X995206Y347560D03*
X981686Y370959D03*
X978306Y369010D03*
X985066D03*
Y365109D03*
X988446Y363160D03*
X995206Y378760D03*
X998586Y372909D03*
X988446Y378760D03*
X998586Y384609D03*
X985066Y376809D03*
X981686Y374860D03*
X995206D03*
X991826Y384609D03*
X991500Y396301D03*
X1032385Y357309D03*
X1022245Y351460D03*
X1029005D03*
X1001965Y347560D03*
X1012105Y345609D03*
X1015485Y347560D03*
X1008725D03*
X1001965Y367060D03*
X1015485Y355360D03*
X1008725Y367060D03*
X1022245Y390460D03*
X1000800Y402800D03*
X1025625Y372909D03*
X1018865Y384609D03*
Y372909D03*
X1012105D03*
X1022245Y378760D03*
X1032385Y384609D03*
X1001965Y378760D03*
X1032385Y372909D03*
X1029005Y378760D03*
X1012105Y384609D03*
X1008725Y378760D03*
X1005345Y372909D03*
Y384609D03*
X1025625D03*
X988446Y343660D03*
X1015485Y378760D03*
Y367060D03*
X1022245D03*
X1012105Y361209D03*
X1018865D03*
X991826D03*
X998586D03*
X1029005Y367060D03*
X995206Y355360D03*
X1001965D03*
X1005345Y361209D03*
X1008725Y355360D03*
X1025625Y361209D03*
X1032385D03*
X985066Y357309D03*
X998586Y345609D03*
X981686Y367060D03*
X978306Y372909D03*
X1029005Y355360D03*
X1015485Y351460D03*
X1012105Y349509D03*
X1025625D03*
X1001965Y343660D03*
X1018865Y369010D03*
X995206Y363160D03*
X1032385Y369010D03*
X995206Y343660D03*
X985066Y361209D03*
X974926Y355360D03*
Y347560D03*
X978306Y353409D03*
Y349509D03*
Y357309D03*
X974926Y359260D03*
X981686D03*
X998586Y369010D03*
Y357309D03*
X981686Y347560D03*
X978306Y345609D03*
X981686Y355360D03*
X985066Y349509D03*
X998586D03*
X978306Y365109D03*
X981686Y363160D03*
X974926D03*
Y367060D03*
Y370959D03*
X988446Y367060D03*
X998586Y365109D03*
Y353409D03*
X991826Y365109D03*
X995206Y370959D03*
X991826Y353409D03*
X974926Y343660D03*
X995206Y359260D03*
X988446D03*
Y347560D03*
X991826Y345609D03*
X988446Y351460D03*
Y355360D03*
X998586Y388509D03*
X991826Y380709D03*
X998586D03*
X991826Y372909D03*
X988446Y374860D03*
X998586Y392410D03*
X988446Y382660D03*
X995206D03*
X985066Y372909D03*
X974926Y374860D03*
X985066Y384609D03*
X998586Y376809D03*
X991826Y388509D03*
X995206Y390460D03*
X974926Y386560D03*
X991826Y376809D03*
X974066Y399911D03*
X978306Y376809D03*
X974926Y378760D03*
X981686D03*
X985066Y380709D03*
X995206Y386560D03*
X1022245Y343660D03*
X1005345Y365109D03*
X1008725Y370959D03*
X1001965D03*
X1005345Y353409D03*
X1018865Y365109D03*
X1012105D03*
X1025625D03*
X1022245Y370959D03*
X1015485D03*
X1018865Y353409D03*
X1012105D03*
X1025625D03*
X1029005Y370959D03*
X1032385Y365109D03*
X1005345Y345609D03*
X1018865Y349509D03*
X1032385Y353409D03*
X1008725Y343660D03*
X1001965Y359260D03*
X1005345Y349509D03*
X1008725Y359260D03*
X1015485D03*
X1018865Y345609D03*
X1022245Y347560D03*
X1015485Y343660D03*
X1025625Y345609D03*
X1022245Y359260D03*
X1029005Y347560D03*
Y359260D03*
X1032385Y349509D03*
X1018865Y357309D03*
X1001965Y363160D03*
X1022245Y355360D03*
X1012105Y357309D03*
X1008725Y351460D03*
X1032385Y388509D03*
Y376809D03*
X1022245Y386560D03*
X1007595Y402800D03*
X1012105Y380709D03*
X1022245Y374860D03*
X1015485D03*
X1025625Y380709D03*
X1029005Y386560D03*
X1018865Y380709D03*
X1001965Y374860D03*
X1029005D03*
X1008725Y386560D03*
X1005345Y380709D03*
X1008725Y374860D03*
Y382660D03*
X1001965D03*
X1005345Y392410D03*
X1029005Y390460D03*
X1025625Y392410D03*
X1022245Y382660D03*
X1015485D03*
X1012105Y392410D03*
X1018865D03*
X1029005Y382660D03*
X1027875Y402800D03*
X1005345Y376809D03*
Y388509D03*
X1001965Y386560D03*
X1025625Y376809D03*
Y388509D03*
X1018865Y376809D03*
X1012105D03*
X1018865Y388509D03*
X1012105D03*
X985066Y345609D03*
X1025625Y357309D03*
X1032385Y380709D03*
X1025625Y369010D03*
X1015485Y363160D03*
X1022245D03*
X1012105Y369010D03*
X991826D03*
Y357309D03*
X995206Y351460D03*
X1005345Y357309D03*
Y369010D03*
X1008725Y363160D03*
X1029005D03*
X1001965Y351460D03*
X985066Y353409D03*
X1031255Y343660D03*
X987401Y515364D03*
X990748Y512792D03*
X997441Y518157D03*
X973795Y499793D03*
X977362Y512792D03*
X974015Y509999D03*
X984055Y512792D03*
X980708Y515364D03*
X984055Y518157D03*
X976421Y499768D03*
X980708Y510114D03*
X977362Y518157D03*
X1034200Y506956D03*
X1000490Y509999D03*
X1016473Y515152D03*
Y510114D03*
X1008650Y515200D03*
X1008526Y510114D03*
X1024800Y516356D03*
Y518856D03*
X976530Y497170D03*
X974015Y515364D03*
X990748Y518157D03*
X994094Y515364D03*
X997441Y512792D03*
X1000787Y515364D03*
X1003915Y512792D03*
X1004134Y518157D03*
X1011126Y510114D03*
X1013873Y515152D03*
X987401Y509999D03*
X994094Y510114D03*
X1011250Y515200D03*
X1013873Y510114D03*
X1026500Y581000D03*
X1019800Y555800D03*
X990748Y536957D03*
X977362Y529014D03*
X980708Y536957D03*
X987401Y529014D03*
X990748Y547922D03*
X980708Y547914D03*
X997441Y529022D03*
X983900Y533100D03*
Y552000D03*
X977362Y555857D03*
X987401D03*
X997441D03*
X977362Y566814D03*
X990748Y574757D03*
Y585722D03*
X980708Y585714D03*
Y574757D03*
X997441Y566822D03*
X987401Y566814D03*
X983900Y570900D03*
X1007147Y550511D03*
Y553111D03*
X1007207Y534137D03*
X1013500Y529200D03*
X1026500Y538500D03*
Y541000D03*
X1007207Y531537D03*
X1026500Y546400D03*
X1013873Y547914D03*
X1000787Y536957D03*
Y547922D03*
X1017300Y536200D03*
X1017519Y529057D03*
X1017300Y547914D03*
X1007518Y536727D03*
X1007480Y528942D03*
X1007280Y547914D03*
X1026400Y543700D03*
X1016800Y566814D03*
X1019277Y585714D03*
X1016800Y574742D03*
X1006406Y588366D03*
X1007332Y572010D03*
X1016473Y585714D03*
X1026500Y577500D03*
X1007332Y569410D03*
X1014173Y566814D03*
Y555842D03*
Y574742D03*
X1010928Y555842D03*
X1000787Y585722D03*
Y574757D03*
X1016819Y555842D03*
X1007518D03*
Y566814D03*
X1007480Y574742D03*
X1006633Y585714D03*
X1011126Y547914D03*
Y585714D03*
X1013873D03*
X1010826Y566814D03*
Y574742D03*
X1020800Y612600D03*
X1029777Y613581D03*
X980708Y604614D03*
X997441Y612357D03*
X977362Y593657D03*
X987401D03*
X997441D03*
Y607292D03*
X977362D03*
X990748Y612457D03*
X980708Y609864D03*
X987401Y604499D03*
X983900Y589800D03*
X977362Y612457D03*
X1016778Y611759D03*
X1017519Y604614D03*
Y593642D03*
X1007480Y612242D03*
X1020700Y604600D03*
X1020300Y593700D03*
X1023200Y610700D03*
X1022950Y593650D03*
X1025450D03*
X1006406Y590966D03*
X1004133Y612358D03*
X1000787Y609864D03*
X1007480Y604614D03*
X1006634Y593642D03*
X990748Y607292D03*
X987401Y609864D03*
X994094D03*
X1000787Y604499D03*
X1004134Y607292D03*
X984055Y612457D03*
X1011572Y593642D03*
X1010826Y604614D03*
X1014173Y612242D03*
X1014919Y593642D03*
X974015Y609864D03*
Y604499D03*
X984055Y607292D03*
X994094Y604614D03*
X1010826Y612242D03*
X1014173Y604614D03*
X1044290Y11792D03*
X1043800Y-9700D03*
X1047637Y-4536D03*
X1057676Y-1743D03*
X1047637Y9107D03*
X1057677D03*
X1050983Y-7108D03*
X1047637Y28007D03*
X1057677D03*
X1050984Y17042D03*
X1045525Y15357D03*
X1057792Y13200D03*
Y32100D03*
X1071062Y-1817D03*
X1061023Y-9786D03*
X1067716Y-4536D03*
Y-9901D03*
X1081102Y-4536D03*
X1074409D03*
X1084448Y-7108D03*
X1077755D03*
X1091141Y-1843D03*
X1067716Y9107D03*
X1091141D03*
X1074409D03*
X1081102D03*
X1061023Y-4536D03*
X1081102Y28007D03*
X1074409D03*
X1061024Y17057D03*
X1067716Y28007D03*
Y17042D03*
X1091141D03*
X1084450Y17057D03*
X1077757D03*
X1091141Y28007D03*
X1083116Y13200D03*
Y32100D03*
X1070976Y13200D03*
Y32100D03*
X1071062Y-7108D03*
X1094488Y-4536D03*
Y-9786D03*
X1081102Y-9901D03*
X1064369Y-7108D03*
X1087795Y-4536D03*
X1050983Y-1743D03*
X1054330Y-9901D03*
X1044291Y-2200D03*
X1087795Y-9786D03*
X1074409D03*
X1084448Y-1743D03*
X1057676Y-7108D03*
X1064369Y-1743D03*
X1077755D03*
X1054330Y-4536D03*
X1047637Y-9901D03*
X1044100Y54700D03*
X1044290Y49592D03*
X1050984Y54842D03*
X1047637Y35942D03*
Y46907D03*
X1057677Y35942D03*
Y46907D03*
X1044290Y68964D03*
X1057676Y87392D03*
X1050983Y92757D03*
X1047637Y84599D03*
X1035000Y81200D03*
X1057677Y73742D03*
X1047637D03*
X1057792Y51000D03*
Y69900D03*
X1061024Y54857D03*
X1067716Y54842D03*
Y35942D03*
Y46907D03*
Y65807D03*
X1091141Y54842D03*
Y35942D03*
X1084450Y54857D03*
X1081102Y35942D03*
X1074409D03*
X1077757Y54857D03*
X1081102Y46907D03*
X1074409D03*
X1091141D03*
Y65807D03*
X1083116Y51000D03*
X1070976D03*
X1083116Y69900D03*
X1070976D03*
X1067716Y89964D03*
Y84599D03*
X1081102D03*
X1091141Y87392D03*
Y92657D03*
X1077755Y92757D03*
X1074409Y84714D03*
X1084448Y92757D03*
X1061023Y89964D03*
X1067716Y73742D03*
X1074409D03*
X1081102D03*
X1091141D03*
X1061023Y84714D03*
X1057677Y65807D03*
X1047637D03*
X1044290Y87392D03*
X1057676Y92757D03*
X1071062D03*
X1064369Y87392D03*
X1054330Y84599D03*
X1047637Y89964D03*
X1064369Y92757D03*
X1050983Y87392D03*
X1054330Y89964D03*
X1074409Y65807D03*
X1081102D03*
Y89964D03*
X1087795Y84714D03*
Y89964D03*
X1074409D03*
X1084448Y87392D03*
X1077755D03*
X1094488Y84714D03*
Y89964D03*
X1050983Y105800D03*
X1057734Y105750D03*
X1035900Y98800D03*
X1077304Y105800D03*
X1071111D03*
X1064428D03*
X1071120Y103116D03*
X1057734D03*
X1064427D03*
X1050983D03*
X1077304Y103100D03*
X1049284Y218860D03*
X1057314Y216909D03*
X1035765Y218860D03*
X1049284Y211060D03*
X1089101Y218147D03*
X1065242Y216196D03*
X1039145Y213009D03*
X1042524Y211060D03*
X1049284Y207159D03*
X1045904Y216909D03*
X1042524Y218860D03*
X1045904Y213009D03*
X1057314Y209109D03*
X1045904D03*
X1035765Y211060D03*
X1039145Y216909D03*
X1035765Y214960D03*
X1042524D03*
X1042506Y195041D03*
X1045904Y197359D03*
X1054000Y199100D03*
X1035765Y207159D03*
X1042524Y203260D03*
X1049284Y214960D03*
Y203260D03*
X1039145Y209109D03*
X1068822Y218147D03*
X1072202Y216196D03*
X1065242Y208397D03*
X1068822Y214247D03*
X1065242Y212296D03*
Y204496D03*
X1071072Y199583D03*
X1095861Y218147D03*
X1089101Y214247D03*
Y210346D03*
X1092481Y216196D03*
X1095861Y206446D03*
X1091351Y199841D03*
X1075582Y206446D03*
Y218147D03*
X1082341D03*
X1078962Y216196D03*
X1078961Y212296D03*
X1082341Y214247D03*
X1085721Y212296D03*
Y216196D03*
X1084591Y198931D03*
X1054914Y216909D03*
Y213009D03*
Y209109D03*
Y205210D03*
X1045904Y244209D03*
Y240309D03*
X1035765Y222760D03*
X1039145Y224709D03*
X1042524Y222760D03*
X1045904Y224709D03*
X1049284Y242260D03*
X1039145Y240309D03*
X1042524Y242260D03*
X1035765D03*
X1039145Y244209D03*
X1042524Y246160D03*
X1035765D03*
X1092481Y220096D03*
Y227896D03*
X1089101Y229847D03*
X1075582Y222047D03*
X1065242Y227896D03*
Y231797D03*
X1072202Y220096D03*
Y227896D03*
X1068822Y225947D03*
Y222047D03*
X1095861Y241547D03*
X1092481Y235696D03*
Y239596D03*
X1072202Y247396D03*
X1065242Y243496D03*
X1085721Y220096D03*
X1095861Y225947D03*
X1082341D03*
X1095700Y265900D03*
X1078962Y231797D03*
X1082341Y241547D03*
X1085721Y235696D03*
X1075582Y241547D03*
X1045904Y236409D03*
X1035765Y230559D03*
X1072202Y235696D03*
X1057314Y228610D03*
X1042524Y230559D03*
X1049284D03*
X1057314Y236409D03*
X1045904Y228610D03*
X1078962Y235696D03*
Y243496D03*
X1042524Y234460D03*
X1035765D03*
X1049284D03*
X1039145Y236409D03*
X1045904Y220809D03*
X1057314D03*
X1049284Y222760D03*
X1042524Y226660D03*
X1039145Y232509D03*
X1035765Y226660D03*
X1057314Y240309D03*
X1049284Y226660D03*
X1045904Y232509D03*
X1057314D03*
Y244209D03*
X1049284Y246160D03*
X1035765Y238360D03*
Y250060D03*
X1057314Y248109D03*
X1039145D03*
X1042524Y250060D03*
X1049284D03*
X1045904Y248109D03*
X1042524Y238360D03*
X1039145Y220809D03*
X1038015Y256500D03*
X1041395Y254259D03*
X1048154D03*
X1051534Y256500D03*
X1044774Y256400D03*
X1054914Y254500D03*
X1034635Y254259D03*
X1050002Y264899D03*
X1047002D03*
X1043502D03*
X1040502D03*
X1089101Y222047D03*
Y225947D03*
X1065242Y220096D03*
X1075582Y225947D03*
X1095861Y229847D03*
X1068822Y233746D03*
X1065242Y235696D03*
Y223996D03*
X1068822Y237647D03*
Y249347D03*
X1065242Y247396D03*
X1068822Y241547D03*
X1072202Y243496D03*
Y251296D03*
X1092481Y223996D03*
Y231797D03*
X1089101Y233746D03*
X1068822Y229847D03*
X1095861Y233746D03*
X1092481Y247396D03*
X1089101Y245447D03*
X1085721Y247396D03*
X1089101Y249347D03*
X1092481Y251296D03*
X1095861Y249347D03*
X1089101Y237647D03*
X1095861D03*
Y245447D03*
X1078962Y251296D03*
X1082341Y245447D03*
Y249347D03*
X1078962Y247396D03*
X1092481Y243496D03*
X1075582Y245447D03*
X1085721Y251296D03*
X1075582Y249347D03*
X1085721Y243496D03*
X1089101Y241547D03*
X1085721Y223996D03*
X1075582Y229847D03*
X1082341D03*
X1078962Y227896D03*
Y220096D03*
Y223996D03*
X1085721Y231797D03*
X1082341Y237647D03*
X1075582D03*
X1072202Y231797D03*
Y223996D03*
X1065242Y239596D03*
X1068822Y245447D03*
X1085721Y227896D03*
X1095861Y222047D03*
X1082341D03*
X1079859Y265000D03*
X1089101Y253247D03*
X1092481Y255196D03*
X1095861Y257147D03*
X1089100Y264500D03*
X1092300Y267200D03*
X1095700Y268790D03*
X1089000Y267000D03*
X1067692Y254000D03*
X1071072Y255728D03*
X1087971Y257800D03*
X1091351Y259600D03*
X1094731Y261500D03*
X1084591Y255497D03*
X1081212Y257600D03*
X1095861Y253247D03*
X1092100Y264500D03*
X1078962Y239596D03*
X1082341Y233746D03*
X1085721Y239596D03*
X1075582Y233746D03*
X1039145Y228610D03*
X1049284Y238360D03*
X1072202Y239596D03*
X1057314Y224709D03*
X1054914Y232509D03*
Y228610D03*
Y224709D03*
Y220809D03*
X1038015Y253960D03*
X1044774D03*
X1051534D03*
X1054914Y252009D03*
Y248109D03*
Y244209D03*
Y240309D03*
Y236409D03*
X1047756Y338341D03*
X1044256D03*
X1050756D03*
X1053702Y338404D03*
X1095702Y309904D03*
X1071102Y292904D03*
X1068102D03*
X1063902D03*
X1075302Y309904D03*
X1082502D03*
X1092756Y309841D03*
X1089702Y309904D03*
X1085502D03*
X1078302D03*
X1071102D03*
X1068102D03*
X1063902D03*
X1060902D03*
Y292904D03*
X1085502D03*
X1082502D03*
X1078302D03*
X1075302D03*
X1089702D03*
X1092702D03*
X1049284Y355360D03*
X1052664Y361209D03*
X1035765Y367060D03*
X1045904Y384609D03*
X1039145D03*
X1049284Y390460D03*
X1052664Y396309D03*
X1049284Y386560D03*
X1048154Y402900D03*
X1052500Y400400D03*
X1049284Y378760D03*
X1039145Y372909D03*
X1042524Y378760D03*
X1035765D03*
X1045904Y372909D03*
X1083462Y356596D03*
X1086841Y370247D03*
X1073322Y358547D03*
X1083462Y364396D03*
X1093601Y354647D03*
X1090221Y360496D03*
X1080082Y358547D03*
X1093601Y381947D03*
X1090221Y387796D03*
X1073322Y393647D03*
X1083462Y383896D03*
X1073322Y378047D03*
X1080082Y389747D03*
X1060694Y394359D03*
Y386560D03*
Y382660D03*
Y378760D03*
X1086841Y378047D03*
X1090221Y376096D03*
X1093601Y374146D03*
X1061055Y363160D03*
X1060963Y370959D03*
X1064371Y367060D03*
X1076702Y364396D03*
X1073322Y370247D03*
X1080082Y374146D03*
X1045904Y361209D03*
X1052664Y372909D03*
X1042524Y367060D03*
X1049284D03*
X1039145Y361209D03*
X1076702Y383896D03*
X1093601Y370247D03*
X1076435Y343595D03*
X1052664Y357309D03*
X1049284Y370959D03*
X1035765D03*
X1042524D03*
X1045904Y365109D03*
X1039145D03*
X1052664D03*
X1035765Y355360D03*
X1042524Y359260D03*
X1049284Y351460D03*
X1045904Y353409D03*
X1035765Y351460D03*
Y359260D03*
X1039145Y353409D03*
X1042524Y351460D03*
X1054914Y347000D03*
X1042524Y355360D03*
X1045904Y357309D03*
X1039145D03*
X1045904Y369010D03*
X1049284Y359260D03*
X1034635Y343209D03*
X1038015Y345160D03*
X1041395Y347109D03*
X1048154D03*
X1044774Y345160D03*
X1051534D03*
X1039145Y388509D03*
X1045904D03*
X1052664D03*
X1039145Y376809D03*
X1045904D03*
X1042524Y386560D03*
X1045904Y380709D03*
X1035765Y374860D03*
Y386560D03*
X1052664Y380709D03*
X1049284Y374860D03*
X1042524D03*
X1039145Y380709D03*
X1052664Y392410D03*
X1040265Y394359D03*
X1049284Y382660D03*
X1035765D03*
X1042524D03*
Y390460D03*
X1056176Y402471D03*
X1041395Y402800D03*
X1052664Y376809D03*
X1060694Y351460D03*
X1086841Y358547D03*
X1094731Y346546D03*
X1086841Y354647D03*
X1090221Y352696D03*
X1091351Y348497D03*
X1073322Y354647D03*
X1076702Y356596D03*
X1080082Y354647D03*
X1083462Y368296D03*
X1076702Y372197D03*
Y368296D03*
X1073322Y362447D03*
X1086841D03*
X1090221Y372197D03*
Y364396D03*
X1093601Y366347D03*
X1090221Y368296D03*
X1076702Y360496D03*
X1083462D03*
Y352696D03*
X1076702D03*
X1093601Y358547D03*
X1086841Y366347D03*
X1073322D03*
X1083462Y372197D03*
X1093601Y362447D03*
X1090221Y356596D03*
X1080082Y366347D03*
Y362447D03*
X1071072Y348497D03*
X1087971Y346546D03*
X1074452D03*
X1081212D03*
X1077832Y348497D03*
X1084591D03*
X1090221Y379996D03*
X1073323Y401449D03*
X1078962Y399496D03*
X1093601Y401447D03*
Y389747D03*
X1090221Y383896D03*
X1073322Y389747D03*
X1083462Y387796D03*
X1073322Y381947D03*
X1080082D03*
X1076702Y391696D03*
Y387796D03*
X1060694Y390460D03*
Y374860D03*
X1073322Y374146D03*
X1086841D03*
X1073323Y397548D03*
X1073322Y385847D03*
X1080082Y393647D03*
X1083462Y391696D03*
X1080082Y385847D03*
X1083462Y376096D03*
X1080082Y378047D03*
X1083462Y379996D03*
X1076702Y376096D03*
X1090221Y395595D03*
X1086841Y389747D03*
X1093601Y393647D03*
X1090221Y391696D03*
X1093601Y385847D03*
X1086841D03*
X1093601Y397546D03*
Y378047D03*
X1086841Y381947D03*
X1080082Y370247D03*
X1052664Y353409D03*
X1060694Y355360D03*
X1061039Y359351D03*
X1039145Y369010D03*
X1042524Y363160D03*
X1035765D03*
X1052664Y369010D03*
X1049284Y363160D03*
X1076702Y379996D03*
X1058294Y394359D03*
Y390460D03*
Y386560D03*
Y382660D03*
Y378760D03*
Y374860D03*
Y370959D03*
Y367060D03*
Y363160D03*
Y359260D03*
Y355360D03*
Y351460D03*
X1054914Y349509D03*
X1038015Y347560D03*
X1044774D03*
X1051534D03*
X1034635Y345609D03*
X1093601Y405347D03*
X1077832Y407800D03*
X1035750Y503006D03*
X1050983Y512792D03*
X1054330Y509999D03*
X1044290Y512792D03*
X1047637Y509999D03*
X1057676Y512792D03*
X1035000Y521556D03*
X1050983Y518157D03*
X1067716Y509999D03*
X1074409Y510114D03*
X1061023Y515364D03*
X1091141Y518057D03*
X1077755Y518157D03*
X1081102Y509999D03*
X1084448Y518157D03*
X1082800Y497650D03*
X1091141Y512792D03*
X1067716Y515364D03*
X1061023Y510114D03*
X1087795D03*
X1077755Y512792D03*
X1071062Y518157D03*
X1084448Y512792D03*
X1057676Y518157D03*
X1064369Y512792D03*
X1047637Y515364D03*
X1064369Y518157D03*
X1054330Y515364D03*
X1087795D03*
X1074409D03*
X1094488Y510114D03*
Y515364D03*
X1081102D03*
X1084800Y499400D03*
X1057792Y552000D03*
Y533100D03*
X1044203Y537058D03*
X1044290Y550592D03*
X1057677Y547907D03*
Y536942D03*
X1047637Y547907D03*
Y536942D03*
X1044195Y529026D03*
X1057677Y574742D03*
Y585707D03*
X1047637Y574742D03*
Y585707D03*
X1044290Y569492D03*
X1057792Y570900D03*
X1047637Y566807D03*
X1057677D03*
X1050984Y555842D03*
X1074409Y547907D03*
X1081102D03*
X1091141D03*
Y529007D03*
Y536942D03*
X1074409D03*
X1081102D03*
X1067716D03*
Y529007D03*
X1070976Y552000D03*
Y533100D03*
X1084003Y532904D03*
X1083116Y552000D03*
X1074409Y566807D03*
X1061024Y555857D03*
X1077757D03*
X1084450D03*
X1091141Y555842D03*
X1067716D03*
X1081102Y574742D03*
Y585707D03*
X1074409D03*
X1091141Y574742D03*
Y585707D03*
X1067716Y574742D03*
Y585599D03*
Y566807D03*
X1091141D03*
X1074409Y574742D03*
X1070976Y570900D03*
X1083116D03*
X1057677Y529007D03*
X1047637D03*
X1044290Y588392D03*
X1081102Y566807D03*
X1071062Y612560D03*
X1064369Y612657D03*
X1084448D03*
X1091141Y612557D03*
X1050984Y612658D03*
X1057676Y612657D03*
X1046500Y623500D03*
X1050984Y593642D03*
X1047637Y609864D03*
X1044290Y607292D03*
X1057792Y589800D03*
X1054330Y609864D03*
X1087795D03*
X1071062Y607292D03*
X1061024Y593657D03*
X1061023Y604614D03*
X1077757Y593657D03*
X1084450D03*
X1067716Y593642D03*
Y609864D03*
Y604499D03*
X1081102Y609864D03*
X1091141Y593642D03*
Y607292D03*
X1084448D03*
X1077755D03*
X1061023Y609864D03*
X1070242Y589800D03*
X1083108D03*
X1077755Y612657D03*
X1044291Y612658D03*
X1057676Y607292D03*
X1047637Y604499D03*
X1094488Y604614D03*
X1081102Y604499D03*
X1054330D03*
X1050983Y607292D03*
X1074409Y609864D03*
Y593642D03*
X1087795Y604614D03*
X1074409D03*
X1094488Y609864D03*
X1064369Y607292D03*
X1119453Y-9864D03*
X1097352Y-7180D03*
X1104141Y-7851D03*
X1110520Y-7700D03*
X1114340Y-1801D03*
X1107874Y-1751D03*
X1101181Y-1801D03*
X1107724Y9114D03*
X1101181D03*
X1114340Y9098D03*
X1114400Y28100D03*
X1110520Y14814D03*
X1104177Y14714D03*
X1098500Y17000D03*
X1114300Y16900D03*
X1110520Y33700D03*
X1107874Y27899D03*
X1104141Y33700D03*
X1101181Y27899D03*
X1114366Y30750D03*
X1119440Y33149D03*
X1114340Y33399D03*
X1119440Y30540D03*
X1097834Y11100D03*
X1119400Y9300D03*
X1119453Y27936D03*
X1119440Y17114D03*
X1097900Y13700D03*
Y31900D03*
X1110520Y30100D03*
X1097834Y28100D03*
X1104141Y29949D03*
X1156300Y-2000D03*
X1151152Y-1801D03*
X1131299Y9114D03*
X1124606D03*
X1151152Y9098D03*
X1137992Y9114D03*
X1144535D03*
X1147331Y-4100D03*
X1144685Y-9901D03*
X1140952Y-4100D03*
X1137992Y-9901D03*
X1151178Y-7050D03*
X1156252Y-7260D03*
X1151152Y-4401D03*
X1156252Y-4651D03*
X1124606Y27899D03*
X1147331Y33700D03*
X1144685Y27899D03*
X1140952Y33700D03*
X1137992Y27899D03*
X1151177Y30750D03*
X1156251Y33149D03*
X1127952Y-7851D03*
X1124606Y-1751D03*
X1131299D03*
X1134645Y-7851D03*
X1156265Y-9864D03*
X1151200Y-9700D03*
X1147331Y-7700D03*
X1140952Y-7851D03*
X1137992Y-1801D03*
X1144685Y-1751D03*
X1151151Y33399D03*
X1156251Y30540D03*
X1144685Y17157D03*
X1147331Y12114D03*
X1137992Y17157D03*
X1141038Y12114D03*
X1151152Y14300D03*
X1156252Y14514D03*
X1151152Y11700D03*
X1156252Y11914D03*
X1156212Y9300D03*
X1127952Y14814D03*
X1151211Y28100D03*
X1156252Y17114D03*
X1151112Y16900D03*
X1147331Y30100D03*
Y14814D03*
X1134645Y29949D03*
X1140952D03*
X1140988Y14714D03*
X1134645Y14814D03*
X1156265Y27936D03*
X1127952Y29949D03*
X1131299Y27899D03*
X1119440Y-4651D03*
X1114340Y-4401D03*
X1119440Y-7260D03*
X1114366Y-7050D03*
X1124606Y-9901D03*
X1127952Y-3700D03*
X1131299Y-9901D03*
X1107874D03*
X1110520Y-4100D03*
X1134645Y-3700D03*
X1119440Y11914D03*
X1114340Y11700D03*
X1119440Y14514D03*
X1114340Y14300D03*
X1127952Y12114D03*
X1124606Y17157D03*
X1131299D03*
X1110520Y12114D03*
X1107874Y17157D03*
X1134645Y12114D03*
X1101181Y17157D03*
X1104227Y12114D03*
X1101181Y-9901D03*
X1104141Y-4100D03*
X1114340Y35999D03*
X1098235Y68090D03*
X1110520Y67900D03*
X1104141Y67749D03*
X1114366Y65950D03*
X1107874Y65699D03*
X1101181D03*
X1114366Y68550D03*
X1119440Y68340D03*
X1107874Y54957D03*
X1110520Y49914D03*
X1101181Y54957D03*
X1104227Y49564D03*
X1114340Y52100D03*
X1119440Y49714D03*
X1114340Y49500D03*
X1119440Y52314D03*
Y54914D03*
X1119400Y47100D03*
Y35800D03*
X1098100Y51000D03*
X1119453Y65736D03*
X1107874Y36049D03*
X1098022Y35761D03*
X1101181Y35999D03*
X1107724Y46914D03*
X1110520Y52614D03*
X1098581Y54883D03*
X1104177Y52514D03*
X1101181Y46900D03*
X1098125Y46975D03*
X1114300Y54700D03*
X1114340Y46898D03*
X1098259Y70896D03*
X1101181Y84714D03*
X1098218Y85296D03*
X1114340Y73799D03*
X1107874Y73849D03*
X1101181Y73799D03*
X1098207Y73589D03*
X1110520Y90314D03*
X1114340Y84698D03*
X1114316Y92500D03*
X1107724Y84714D03*
X1119440Y92714D03*
X1119416Y84700D03*
X1119466Y73550D03*
X1098300Y89900D03*
X1104177Y90314D03*
X1110520Y71500D03*
X1107874Y92757D03*
X1110520Y87714D03*
X1104227D03*
X1114340Y89900D03*
X1119440Y70949D03*
Y87514D03*
X1114340Y71199D03*
Y87300D03*
X1119440Y90114D03*
X1127952Y34100D03*
X1124606Y54957D03*
X1127952Y49914D03*
X1144685Y54957D03*
X1147331Y49914D03*
X1137992Y54957D03*
X1141038Y49914D03*
X1151151Y52100D03*
X1156251Y49714D03*
X1151151Y49500D03*
X1156251Y52314D03*
X1127952Y67749D03*
X1156211Y35800D03*
X1156200Y47000D03*
X1151152Y35999D03*
Y46898D03*
X1151100Y54700D03*
X1147331Y52614D03*
X1134645D03*
X1137992Y46914D03*
Y35999D03*
X1144535Y46914D03*
X1144685Y36049D03*
X1156252Y54914D03*
X1134645Y67749D03*
X1140952D03*
X1156265Y65736D03*
X1151178Y65950D03*
X1147331Y67900D03*
X1131299Y46914D03*
X1124606D03*
X1127952Y52614D03*
X1131299Y36049D03*
X1124606D03*
X1131299Y65699D03*
X1124606D03*
X1144685D03*
X1137992D03*
X1151178Y68550D03*
X1156252Y68340D03*
X1131299Y54957D03*
X1134645Y34100D03*
Y49914D03*
X1131299Y73849D03*
X1124606D03*
X1127952Y90414D03*
X1131299Y84714D03*
X1124606D03*
X1147331Y90414D03*
X1137992Y73799D03*
X1144535Y84714D03*
X1140988Y90314D03*
X1137992Y84714D03*
X1134645Y90414D03*
Y71900D03*
X1131299Y92757D03*
X1134645Y87714D03*
X1127952Y71900D03*
X1124606Y92757D03*
X1127952Y87714D03*
X1147331Y71500D03*
X1144685Y92757D03*
X1147331Y87714D03*
X1140952Y71500D03*
X1137992Y92757D03*
X1141038Y87714D03*
X1151152Y89900D03*
X1156252Y70949D03*
Y87514D03*
X1151152Y71199D03*
Y87300D03*
X1156252Y90114D03*
X1144685Y73849D03*
X1156252Y92714D03*
X1151128Y92500D03*
X1151152Y84698D03*
X1156228Y84700D03*
X1156278Y73550D03*
X1151152Y73799D03*
X1101181Y92757D03*
X1104141Y71500D03*
X1138242Y104314D03*
X1144685D03*
X1144535Y112357D03*
X1147331Y106964D03*
X1138242Y112357D03*
X1141038Y106964D03*
X1151152Y110514D03*
X1156252Y107655D03*
X1151178Y107865D03*
X1156278Y110264D03*
Y112865D03*
X1151152Y113114D03*
X1141038Y109564D03*
X1147331D03*
X1156265Y105051D03*
X1151178Y105265D03*
X1109381Y218147D03*
X1116141Y206446D03*
X1133040Y216196D03*
X1129660Y218147D03*
X1133040Y212296D03*
X1129660Y210346D03*
X1136420D03*
X1144300Y212296D03*
X1147680Y214247D03*
X1144300Y216196D03*
X1147680Y218147D03*
X1154440D03*
X1099241Y216196D03*
Y212296D03*
X1109381Y214247D03*
X1116141Y218147D03*
X1106001Y212296D03*
X1102621Y218147D03*
Y214247D03*
X1119521Y216196D03*
X1119520Y212296D03*
X1104871Y198050D03*
X1106001Y216196D03*
X1112761D03*
X1129660Y206447D03*
X1126280Y216196D03*
Y212296D03*
X1125300Y199900D03*
X1122900Y214247D03*
Y218147D03*
X1129660Y214247D03*
X1147950Y209900D03*
X1136420Y218147D03*
Y214247D03*
X1151060Y212296D03*
X1157820D03*
Y216196D03*
X1151060D03*
X1154440Y214247D03*
X1106001Y220096D03*
X1116141Y225947D03*
X1102621Y222047D03*
Y225947D03*
X1112761Y220096D03*
Y227896D03*
X1109381Y229847D03*
X1116141Y241547D03*
X1112761Y235696D03*
X1119521Y243496D03*
Y235696D03*
X1106001D03*
X1102621Y241547D03*
X1099241Y231797D03*
Y243496D03*
Y235696D03*
X1107600Y271900D03*
X1114340Y280560D03*
X1151060Y251296D03*
X1126280Y220096D03*
X1133040Y231797D03*
X1122900Y222047D03*
Y225947D03*
X1133040Y220096D03*
X1129660Y229847D03*
X1126280Y235696D03*
X1122900Y241547D03*
X1157820Y243496D03*
X1133040Y239596D03*
X1136420Y261047D03*
X1133040Y262996D03*
X1151060Y255196D03*
X1147680Y261047D03*
X1144300Y259096D03*
X1151060Y262996D03*
X1147680Y253247D03*
Y257147D03*
X1134160Y272747D03*
X1109381Y264947D03*
X1129660Y249347D03*
X1109381D03*
X1126280Y247396D03*
X1102621Y249347D03*
X1116141D03*
X1129660Y257147D03*
X1122900Y253247D03*
X1133040Y247396D03*
Y255196D03*
X1136420Y253247D03*
X1140920Y280547D03*
X1157820Y274696D03*
X1154440Y268847D03*
X1140920Y272747D03*
X1154440Y280547D03*
Y276647D03*
X1147680D03*
X1140920D03*
X1154440Y272747D03*
X1147680D03*
X1151060Y270796D03*
X1144300Y220096D03*
X1154440Y237647D03*
X1147680Y241547D03*
X1157820Y227896D03*
X1147680Y229847D03*
X1109381Y257147D03*
X1112761Y255196D03*
X1102621Y253247D03*
X1106001Y255196D03*
X1144300Y274696D03*
X1106001Y227896D03*
X1116141Y222047D03*
X1109381D03*
Y225947D03*
X1116141Y233746D03*
X1112761Y239596D03*
X1119521Y231797D03*
X1099241Y227896D03*
Y220096D03*
X1102621Y229847D03*
X1099241Y223996D03*
X1109381Y233746D03*
X1112761Y231797D03*
Y223996D03*
X1116141Y237647D03*
X1109381D03*
X1106001Y223996D03*
X1102621Y237647D03*
X1119521Y239596D03*
X1106001D03*
X1102621Y233746D03*
X1099241Y239596D03*
X1102621Y245447D03*
X1112761Y251296D03*
X1116141Y245447D03*
X1106001Y243496D03*
X1112761D03*
X1109381Y241547D03*
X1106001Y251296D03*
X1099241D03*
Y247396D03*
X1119521Y223996D03*
Y220096D03*
Y227896D03*
Y247396D03*
Y251296D03*
X1106001Y231797D03*
X1116141Y229847D03*
X1096756Y278941D03*
X1099186Y278938D03*
X1102336Y274819D03*
X1107561Y269038D03*
X1116141Y264947D03*
X1111631Y271300D03*
X1106001Y262996D03*
Y259096D03*
X1099241Y255196D03*
Y259096D03*
X1119521Y270796D03*
X1118391Y274997D03*
X1119521Y255196D03*
X1102621Y261047D03*
Y257147D03*
X1109381Y261047D03*
X1116141Y257147D03*
X1112761Y259096D03*
X1110648Y276899D03*
X1100200Y273300D03*
X1101491Y265400D03*
X1104871Y267300D03*
X1098111Y263400D03*
X1116141Y268847D03*
X1112761Y262996D03*
X1116141Y261047D03*
X1119521Y278596D03*
X1129660Y237647D03*
X1126280Y223996D03*
Y231797D03*
X1122900Y229847D03*
X1126280Y227896D03*
X1133040D03*
X1129660Y225947D03*
Y222047D03*
X1126280Y239596D03*
X1122900Y233746D03*
X1144300Y223996D03*
X1154440Y225947D03*
X1147680Y245447D03*
X1122900Y237647D03*
X1129660Y233746D03*
Y241547D03*
X1126280Y251296D03*
Y243496D03*
X1122900Y245447D03*
X1144300Y243496D03*
X1147680Y249347D03*
X1151060Y247396D03*
X1154440Y245447D03*
X1144300Y247396D03*
Y251296D03*
X1136420Y245447D03*
X1154440Y241547D03*
X1136420D03*
X1157820Y239596D03*
X1147680Y222047D03*
X1144300Y235696D03*
X1136420Y229847D03*
Y233746D03*
Y222047D03*
Y225947D03*
Y237647D03*
X1133040Y223996D03*
Y235696D03*
Y243496D03*
Y251296D03*
X1147680Y225947D03*
X1151060Y223996D03*
X1147680Y233746D03*
X1154440Y229847D03*
X1157820Y220096D03*
Y223996D03*
Y231797D03*
X1147680Y280547D03*
X1137540Y266896D03*
X1147680Y268847D03*
X1137540Y270796D03*
X1140920Y268847D03*
Y264947D03*
X1144300Y262996D03*
X1126280Y266896D03*
X1129660Y264947D03*
X1122900D03*
Y268847D03*
X1154440Y253247D03*
X1130780Y278596D03*
X1129660Y261047D03*
X1130780Y274696D03*
X1126280Y259096D03*
X1122900Y257147D03*
X1157820Y278596D03*
Y270796D03*
X1151060Y266896D03*
Y274696D03*
X1137540D03*
X1151060Y259096D03*
X1144300Y255196D03*
X1133040Y259096D03*
X1134160Y268847D03*
X1136420Y257147D03*
X1144300Y278596D03*
Y270796D03*
X1137540Y278596D03*
X1126280Y262996D03*
X1154440Y261047D03*
X1127400Y280547D03*
Y276646D03*
X1134160Y280547D03*
X1157820Y266896D03*
X1151060Y278596D03*
X1154440Y264947D03*
X1119521Y266896D03*
Y262996D03*
X1134160Y276646D03*
X1157820Y247396D03*
X1154440Y249347D03*
X1151060Y220096D03*
X1154440Y233746D03*
X1144300Y227896D03*
X1151060Y235696D03*
X1144300Y239596D03*
X1151060Y243496D03*
Y239596D03*
X1144300Y266896D03*
X1108125Y276799D03*
X1157820Y251296D03*
X1154440Y257147D03*
X1122900Y261047D03*
X1119521Y259096D03*
X1147680Y264947D03*
X1154440Y222047D03*
X1147680Y237647D03*
X1144300Y231797D03*
X1129660Y245447D03*
X1109381D03*
X1122900Y249347D03*
X1112761Y247396D03*
X1106001D03*
X1129660Y253247D03*
X1109381D03*
X1126280Y255196D03*
X1116141Y253247D03*
X1136420Y249347D03*
X1157820Y235696D03*
X1151060Y227896D03*
Y231797D03*
X1116096Y295809D03*
X1099391Y337001D03*
X1105800Y336830D03*
X1114839Y320075D03*
X1157820Y309797D03*
X1134160Y303947D03*
X1130780Y321496D03*
X1137540Y313696D03*
X1130780Y325396D03*
X1140920Y315647D03*
X1134160Y319547D03*
X1130780Y317596D03*
Y333196D03*
X1134160Y331247D03*
X1115230Y289252D03*
X1144300Y290296D03*
X1147680Y292247D03*
X1154440D03*
X1157820Y282496D03*
X1154440Y288347D03*
Y284447D03*
X1144300Y282496D03*
X1157820Y286396D03*
X1137540D03*
X1140920Y288347D03*
Y284447D03*
X1147680D03*
Y288347D03*
X1151060Y286396D03*
X1137540Y301996D03*
X1151060Y337096D03*
X1120641Y339047D03*
X1154440Y311747D03*
X1157820Y305896D03*
X1154440Y303947D03*
X1157820Y301996D03*
X1154440Y300047D03*
X1119521Y282496D03*
Y301996D03*
X1101256Y308841D03*
X1103756Y307841D03*
Y310341D03*
X1119521Y286396D03*
Y305896D03*
X1113900Y297800D03*
X1113132Y291702D03*
X1098756Y309841D03*
X1119521Y298096D03*
Y294196D03*
Y290296D03*
Y309797D03*
X1113500Y323400D03*
X1119521Y313696D03*
Y317596D03*
X1109200Y325100D03*
X1108251Y338746D03*
X1117261Y340996D03*
X1104871Y340697D03*
X1119521Y321496D03*
X1102300Y336700D03*
X1118391Y332897D03*
X1105900Y334000D03*
X1134160Y307847D03*
X1151060Y294196D03*
X1147680Y300047D03*
Y296147D03*
X1140920Y307847D03*
Y311747D03*
X1151060Y301996D03*
X1144300Y305896D03*
X1147680Y311747D03*
X1130780Y290296D03*
X1127400Y288347D03*
X1130780Y309797D03*
Y301996D03*
X1127400Y303947D03*
Y307847D03*
X1157820Y290296D03*
X1151060Y298096D03*
Y290296D03*
Y282496D03*
X1144300Y286396D03*
Y294196D03*
X1157820D03*
X1140920Y300047D03*
X1134160Y292247D03*
Y300047D03*
X1140920Y292247D03*
X1137540Y282496D03*
X1144300Y309797D03*
X1137540D03*
X1147680Y303947D03*
X1154440Y307847D03*
X1157820Y298096D03*
X1127400Y284447D03*
Y300047D03*
X1130780Y294196D03*
X1127400Y296147D03*
Y292247D03*
X1130780Y298096D03*
Y305896D03*
X1137540Y290296D03*
X1134160Y296147D03*
Y288347D03*
X1147680Y307847D03*
X1151060Y309797D03*
Y305896D03*
X1144300Y301996D03*
Y298096D03*
X1137540D03*
X1140920Y303947D03*
X1137540Y305896D03*
X1140920Y296147D03*
X1137540Y294196D03*
X1127400Y311747D03*
X1154440Y296147D03*
X1130780Y313696D03*
X1157820D03*
X1134160Y335147D03*
Y339047D03*
X1140920Y319547D03*
X1124021Y340996D03*
Y337096D03*
X1127400Y327347D03*
X1157820Y337096D03*
Y333196D03*
X1134160Y323446D03*
X1151060Y340996D03*
Y333196D03*
X1154440Y319547D03*
X1157820Y317596D03*
X1137540D03*
X1157820Y329296D03*
X1147680Y327347D03*
X1154440Y335147D03*
X1144300Y340996D03*
Y337096D03*
X1140920Y339047D03*
Y331247D03*
X1154440Y323446D03*
Y315647D03*
X1147680Y319547D03*
X1157820Y325396D03*
X1154440Y339047D03*
Y331247D03*
X1144300Y317596D03*
X1137540Y321496D03*
X1134160Y327347D03*
X1137540Y325396D03*
X1127400Y319547D03*
Y315647D03*
X1124021Y325396D03*
X1127400Y323446D03*
X1124021Y329296D03*
Y333196D03*
X1154440Y327347D03*
X1147680Y339047D03*
X1157820Y321496D03*
X1130780Y329296D03*
X1140920Y323446D03*
X1144300Y313696D03*
X1151060D03*
X1144300Y325396D03*
Y321496D03*
X1151060Y329296D03*
X1147680Y335147D03*
Y331247D03*
X1140920Y335147D03*
X1144300Y333196D03*
X1151060Y325396D03*
Y321496D03*
X1147680Y323446D03*
X1137540Y329296D03*
X1144300D03*
X1140920Y327347D03*
X1130780Y340996D03*
Y337096D03*
X1127400Y331247D03*
Y335147D03*
Y339047D03*
X1147680Y315647D03*
X1151060Y317596D03*
X1137540Y337096D03*
Y340996D03*
Y333196D03*
X1130780Y282496D03*
Y286396D03*
X1134160Y311747D03*
Y315647D03*
X1116999Y286826D03*
X1134160Y284447D03*
X1113881Y370247D03*
X1100361D03*
X1103741Y360496D03*
X1100361Y354647D03*
Y362447D03*
X1113881Y354647D03*
X1110501Y356596D03*
Y360496D03*
X1096981Y356596D03*
X1117261D03*
X1096981Y364396D03*
X1117261D03*
X1107121Y366347D03*
X1103741Y387796D03*
X1100361Y381947D03*
X1113881Y389747D03*
X1110501Y383896D03*
X1117261Y379996D03*
X1096981Y391696D03*
X1117261Y383896D03*
Y387796D03*
X1103741Y376096D03*
X1110501D03*
X1124021Y368296D03*
X1130780Y364396D03*
X1124021Y360496D03*
X1120641Y354647D03*
Y362447D03*
X1140920Y354647D03*
X1137540Y356596D03*
X1124021Y383896D03*
X1120641Y389747D03*
X1144300Y399496D03*
X1130780Y383896D03*
Y387796D03*
X1140920Y393647D03*
X1137540Y379996D03*
Y383896D03*
Y387796D03*
X1134160Y374146D03*
X1120641D03*
X1127400D03*
X1157820Y383896D03*
X1156699Y401447D03*
X1127400Y370247D03*
X1147680D03*
X1157820Y364396D03*
X1110501Y344896D03*
X1107121Y350747D03*
X1113881Y342947D03*
X1154440Y370246D03*
X1151060Y372196D03*
X1157820D03*
X1140920Y342947D03*
Y401447D03*
X1154440Y374146D03*
X1147680D03*
X1124021Y344896D03*
X1127400Y350747D03*
X1120641Y346847D03*
X1151060Y376096D03*
X1157820Y368296D03*
X1144300Y379996D03*
Y387796D03*
X1157820Y376096D03*
X1144300Y383896D03*
X1147680Y381947D03*
Y378047D03*
X1100361Y350747D03*
X1113881D03*
Y358547D03*
X1117261Y348796D03*
X1100361Y358547D03*
X1103741Y348796D03*
Y352696D03*
X1110501D03*
X1107121Y346847D03*
Y354647D03*
Y358547D03*
Y362447D03*
X1103741Y372197D03*
X1110501Y364396D03*
X1103741D03*
X1113881Y366347D03*
X1117261Y372197D03*
Y368296D03*
X1110501Y372197D03*
X1096981Y368296D03*
Y372197D03*
X1100361Y366347D03*
X1103741Y368296D03*
X1110501D03*
X1103741Y356596D03*
X1113881Y362447D03*
X1107121Y370247D03*
X1096981Y352696D03*
X1117261D03*
X1096981Y360496D03*
X1117261D03*
X1101491Y342646D03*
X1098111Y344597D03*
X1113881Y346847D03*
Y401447D03*
X1103741Y383896D03*
X1113881Y381947D03*
X1110501Y387796D03*
X1096981Y383896D03*
X1117261Y391696D03*
X1096981Y379996D03*
Y387796D03*
X1113881Y374146D03*
X1100361D03*
X1107121Y378047D03*
Y374146D03*
X1110501Y391696D03*
Y395595D03*
X1107121Y389747D03*
X1100361Y385847D03*
X1107121D03*
X1100361Y393647D03*
X1103741Y391696D03*
X1100361Y397547D03*
X1113881Y385847D03*
Y397546D03*
Y393647D03*
X1103741Y379996D03*
X1113881Y378047D03*
X1117261Y376096D03*
X1110501Y379996D03*
X1107121Y381947D03*
X1096981Y376096D03*
X1100361Y378047D03*
X1151060Y368296D03*
X1147680Y366347D03*
X1120641Y350747D03*
Y358547D03*
Y366347D03*
X1127400Y362447D03*
X1124021Y348796D03*
Y352696D03*
X1127400Y354647D03*
Y358547D03*
X1134160D03*
X1130780Y360496D03*
X1127400Y342947D03*
X1134160Y346847D03*
Y362447D03*
Y366347D03*
Y370247D03*
X1147680Y342947D03*
X1151060Y356596D03*
Y360496D03*
X1144300D03*
X1137540D03*
X1144300Y356596D03*
X1140920Y358547D03*
X1147680Y346847D03*
Y350747D03*
X1151060Y352696D03*
Y348796D03*
X1147680Y358547D03*
X1157820Y360496D03*
X1154440Y358547D03*
Y342947D03*
Y354647D03*
X1157820Y352696D03*
X1147680Y354647D03*
X1144300Y348796D03*
X1140920Y346847D03*
Y350747D03*
X1144300Y344896D03*
X1151060D03*
X1154440Y346847D03*
X1140920Y362447D03*
X1154440Y366347D03*
X1144300Y372197D03*
X1137540D03*
Y368296D03*
X1140920Y366347D03*
Y370247D03*
X1151060Y364396D03*
X1144300D03*
X1137540D03*
X1147680Y362447D03*
X1130780Y352696D03*
Y344896D03*
X1124021Y372197D03*
X1130780D03*
X1124021Y364396D03*
X1120641Y370247D03*
X1130780Y368296D03*
X1127400Y366347D03*
X1124021Y356596D03*
X1157820D03*
X1144300Y352696D03*
X1154440Y350747D03*
Y362447D03*
X1144300Y368296D03*
X1120641Y342947D03*
X1137540Y352696D03*
X1130780Y356596D03*
X1134160Y342947D03*
Y354647D03*
Y350747D03*
X1137540Y348796D03*
Y344896D03*
Y403396D03*
Y399496D03*
X1124021Y391696D03*
X1130780Y395596D03*
X1127400Y385847D03*
Y389747D03*
X1130780Y391696D03*
X1124021Y379996D03*
X1127400Y381947D03*
X1130780Y379996D03*
X1137540Y395597D03*
X1140920Y397546D03*
X1137540Y376096D03*
X1157820Y387796D03*
X1140920Y378047D03*
Y381947D03*
X1147680Y393647D03*
X1124021Y387796D03*
X1120641Y381947D03*
X1134160Y389747D03*
X1144300Y395597D03*
X1137540Y391696D03*
X1124021Y376096D03*
X1130780D03*
X1127400Y378047D03*
X1157820Y379996D03*
X1147680Y389747D03*
X1144300Y376096D03*
X1151060Y383896D03*
X1120641Y385847D03*
Y393647D03*
Y378047D03*
Y401447D03*
X1140920Y374146D03*
X1151060Y395597D03*
Y391696D03*
X1147680Y385847D03*
Y397546D03*
X1151060Y379996D03*
X1154440Y378047D03*
Y381947D03*
X1140920Y389747D03*
X1134160Y393647D03*
Y385847D03*
Y378047D03*
X1140920Y385847D03*
X1144300Y391696D03*
X1130780Y348796D03*
X1127400Y346847D03*
X1154440Y397546D03*
Y385847D03*
X1157820Y391696D03*
X1154440Y389747D03*
X1157820Y395597D03*
X1151060Y387796D03*
X1154440Y393647D03*
X1134160Y381947D03*
X1100361Y389747D03*
X1117261Y407296D03*
X1113881Y405347D03*
X1096699Y407782D03*
X1134160Y405347D03*
X1119440Y518114D03*
X1114316Y517900D03*
X1114340Y510098D03*
X1110520Y515714D03*
X1097343Y512794D03*
X1104177Y515714D03*
X1101181Y510114D03*
X1098300Y515300D03*
X1107724Y510114D03*
X1110520Y513114D03*
X1104227D03*
X1119440Y515514D03*
X1151152Y515300D03*
X1156252Y512914D03*
X1151152Y512700D03*
X1156252Y515514D03*
Y496167D03*
X1137992Y495887D03*
X1144385D03*
X1140988Y493744D03*
X1156252Y490867D03*
X1147331Y493494D03*
X1151168Y490867D03*
X1147331Y490894D03*
X1141038Y491144D03*
X1156252Y493567D03*
X1127952Y515814D03*
X1124606Y510114D03*
X1131299D03*
X1156252Y518114D03*
X1147331Y515814D03*
X1151128Y517900D03*
X1156252Y498867D03*
X1151168D03*
X1151152Y510098D03*
X1134645Y515814D03*
X1137992Y510114D03*
X1140988Y515714D03*
X1144535Y510114D03*
X1156228Y510100D03*
X1127952Y513114D03*
X1144685Y518157D03*
X1147331Y513114D03*
X1137992Y518157D03*
X1141038Y513114D03*
X1114340Y512700D03*
X1119440Y512914D03*
X1114340Y515300D03*
X1124606Y518157D03*
X1101181D03*
X1131299D03*
X1107874D03*
X1151168Y493467D03*
X1134645Y513114D03*
X1151168Y496167D03*
X1137992Y498487D03*
X1144385D03*
X1119440Y550714D03*
Y553314D03*
X1104141Y530949D03*
X1098040Y536723D03*
X1098160Y533809D03*
X1119416Y547900D03*
X1119466Y536750D03*
X1119453Y528936D03*
X1098300Y553100D03*
X1114340Y547898D03*
X1107724Y547914D03*
X1101181D03*
X1110520Y553514D03*
X1104177D03*
X1098118Y549843D03*
X1098018Y531156D03*
X1114366Y529150D03*
X1114340Y536999D03*
X1110520Y531100D03*
X1107874Y537049D03*
X1101181Y536999D03*
X1107874Y528899D03*
X1101181D03*
X1110520Y550914D03*
X1104227D03*
X1119440Y571949D03*
X1104227Y588714D03*
X1114340Y588300D03*
X1097343Y588394D03*
X1119440Y555914D03*
X1114316Y555700D03*
X1119416Y585700D03*
X1119466Y574550D03*
X1119453Y566736D03*
X1104141Y568749D03*
X1097899Y574773D03*
X1101181Y585714D03*
X1097834Y569200D03*
X1107724Y585714D03*
X1107874Y574849D03*
X1110520Y568900D03*
X1101181Y574799D03*
X1114340D03*
Y585698D03*
X1114366Y566950D03*
X1107874Y555957D03*
X1110520Y572500D03*
X1107874Y566699D03*
X1101181Y555957D03*
X1104141Y572500D03*
X1101181Y566699D03*
X1156252Y534149D03*
X1151152Y534399D03*
X1156252Y531540D03*
X1134645Y550914D03*
X1127952D03*
X1147331D03*
X1141038D03*
X1156252Y550714D03*
Y553314D03*
X1140988Y553514D03*
X1151152Y547898D03*
X1156228Y547900D03*
X1137992Y547914D03*
X1144535D03*
X1127952Y553614D03*
X1131299Y547914D03*
X1124606D03*
X1131299Y537049D03*
X1124606D03*
X1127952Y530949D03*
X1151178Y529150D03*
X1151152Y536999D03*
X1147331Y531100D03*
X1156278Y536750D03*
X1156265Y528936D03*
X1134645Y530949D03*
X1140952D03*
X1137992Y536999D03*
X1144685Y537049D03*
X1147331Y553614D03*
X1134645D03*
X1147331Y534700D03*
X1144685Y528899D03*
X1140952Y534700D03*
X1137992Y528899D03*
X1156252Y569340D03*
X1134645Y588714D03*
X1127952D03*
X1147331D03*
X1141038D03*
X1156252Y588514D03*
X1151152Y588300D03*
X1156252Y555914D03*
X1151128Y555700D03*
X1156265Y566736D03*
X1151178Y566950D03*
X1134645Y568749D03*
X1137992Y585714D03*
X1144535D03*
X1140952Y568749D03*
X1137992Y574799D03*
X1144685Y574849D03*
X1151152Y585698D03*
Y574799D03*
X1147331Y568900D03*
X1156228Y585700D03*
X1156278Y574550D03*
X1131299Y585714D03*
X1124606D03*
X1131299Y574849D03*
X1127952Y568749D03*
X1124606Y574849D03*
X1131299Y555957D03*
X1134645Y572900D03*
X1131299Y566699D03*
X1124606Y555957D03*
X1127952Y572900D03*
X1124606Y566699D03*
X1144685D03*
X1110520Y588714D03*
X1119440Y588514D03*
Y534149D03*
X1114366Y531750D03*
X1127952Y535100D03*
X1104141Y534700D03*
X1131299Y528899D03*
X1110520Y534700D03*
X1151152Y550500D03*
Y553100D03*
X1151178Y569550D03*
X1137992Y555957D03*
X1147331Y572500D03*
X1144685Y555957D03*
X1114340Y553100D03*
Y550500D03*
X1114366Y569550D03*
X1119440Y531540D03*
Y569340D03*
X1151178Y531750D03*
X1124606Y528899D03*
X1137992Y566699D03*
X1156252Y571949D03*
X1114340Y534399D03*
X1134645Y535100D03*
X1151152Y572199D03*
X1140952Y572500D03*
X1114340Y572199D03*
X1137992Y612599D03*
X1144685Y612649D03*
X1151152Y612599D03*
X1124606Y612649D03*
X1131299D03*
X1097374Y612659D03*
X1114340Y612599D03*
X1107874Y612649D03*
X1101181Y612599D03*
Y593757D03*
X1104141Y610300D03*
X1101181Y604499D03*
X1114340Y590900D03*
Y609999D03*
X1097352Y607220D03*
X1110520Y606700D03*
X1119453Y604536D03*
X1119466Y612350D03*
X1119440Y593714D03*
X1104177Y591314D03*
X1110520D03*
X1114316Y593500D03*
X1098300Y590900D03*
X1114366Y604750D03*
X1104141Y606549D03*
X1134645Y610700D03*
X1131299Y593757D03*
Y604499D03*
X1124606Y593757D03*
X1127952Y610700D03*
X1124606Y604499D03*
X1147700Y611200D03*
X1144685Y593757D03*
Y604499D03*
X1137992Y593757D03*
X1141332Y611668D03*
X1137992Y604499D03*
X1151178Y607350D03*
X1151152Y590900D03*
Y609999D03*
X1156252Y607140D03*
Y591114D03*
X1156265Y604536D03*
X1147331Y606700D03*
X1134645Y606549D03*
X1140952D03*
X1156278Y612350D03*
X1134645Y591414D03*
X1140988Y591314D03*
X1151128Y593500D03*
X1147331Y591414D03*
X1156252Y593714D03*
X1151178Y604750D03*
X1127952Y606549D03*
Y591414D03*
X1107874Y604499D03*
X1119440Y609749D03*
Y591114D03*
Y607140D03*
X1107874Y593757D03*
X1110520Y610300D03*
X1114366Y607350D03*
X1156252Y609749D03*
X1161417Y9114D03*
X1168110D03*
X1174803D03*
X1171456Y-3700D03*
X1168110Y-9901D03*
X1164763Y-3700D03*
X1161417Y-9901D03*
X1168110Y27899D03*
X1161417D03*
X1177763Y33700D03*
X1174803Y27899D03*
X1171456Y-7851D03*
X1164763D03*
X1177763D03*
X1168110Y-1751D03*
X1161417D03*
X1174803Y-1801D03*
X1168110Y17157D03*
X1171456Y12114D03*
X1161417Y17157D03*
X1164763Y12114D03*
X1171456Y14814D03*
X1164763Y29949D03*
X1171456D03*
X1164763Y14814D03*
X1177799Y14714D03*
X1177763Y29949D03*
X1181496Y-1751D03*
X1181346Y9114D03*
X1187963Y9098D03*
X1204921Y9114D03*
X1198228D03*
X1188011Y-9700D03*
X1193076Y-9864D03*
X1184142Y-7700D03*
X1193111Y-2000D03*
X1187963Y-1801D03*
X1201574Y-7851D03*
X1204921Y-1751D03*
X1198228D03*
X1218307D03*
X1211614Y-1801D03*
X1214574Y-7851D03*
X1208267D03*
X1218157Y9114D03*
X1211614D03*
X1204921Y27899D03*
X1198228D03*
X1218307D03*
X1214574Y33700D03*
X1211614Y27899D03*
X1187989Y30750D03*
X1193063Y33149D03*
X1187963Y33399D03*
X1193063Y30540D03*
X1193023Y9300D03*
X1184142Y30100D03*
Y14814D03*
X1188023Y28100D03*
X1187923Y16900D03*
X1193063Y17114D03*
X1193076Y27936D03*
X1201574Y14814D03*
Y29949D03*
X1208267Y14814D03*
Y29949D03*
X1214600Y14714D03*
X1214574Y29949D03*
X1184142Y33700D03*
X1181496Y27899D03*
X1184142Y12114D03*
X1204921Y17157D03*
X1198228D03*
X1201574Y12114D03*
X1187963Y14300D03*
X1193063Y14514D03*
X1187963Y11700D03*
X1193063Y11914D03*
X1184142Y-4100D03*
X1204921Y-9901D03*
X1201574Y-3700D03*
X1198228Y-9901D03*
X1187989Y-7050D03*
X1193063Y-7260D03*
X1187963Y-4401D03*
X1193063Y-4651D03*
X1208267Y-3700D03*
X1218307Y-9901D03*
X1214574Y-4100D03*
X1211614Y-9901D03*
X1208267Y12114D03*
X1218307Y17157D03*
X1211614D03*
X1214660Y12114D03*
X1174803Y-9901D03*
X1177763Y-4100D03*
X1181496Y-9901D03*
X1177849Y12114D03*
X1174803Y17157D03*
X1181496D03*
X1171456Y34100D03*
X1168110Y54957D03*
X1171456Y49914D03*
X1161417Y54957D03*
X1164763Y34100D03*
Y49914D03*
X1174803Y54957D03*
X1177849Y49914D03*
X1161417Y36049D03*
X1164763Y52614D03*
X1168110Y36049D03*
Y46914D03*
X1161417D03*
X1174803D03*
X1171456Y52614D03*
X1174803Y35999D03*
X1177763Y67749D03*
X1171456D03*
X1164763D03*
X1168110Y65699D03*
X1161417D03*
X1174803D03*
X1177799Y90314D03*
X1174803Y84714D03*
X1168110D03*
Y73849D03*
X1161417D03*
X1174803Y73799D03*
X1171456Y71900D03*
X1168110Y92757D03*
X1171456Y87714D03*
X1164763Y71900D03*
X1161417Y92757D03*
X1164763Y87714D03*
X1177763Y71500D03*
X1174803Y92757D03*
X1177849Y87714D03*
X1161417Y84714D03*
X1164763Y90414D03*
X1171456D03*
X1204921Y54957D03*
X1208267Y34100D03*
Y49914D03*
X1198228Y54957D03*
X1201574Y34100D03*
Y49914D03*
X1218307Y54957D03*
X1211614D03*
X1214660Y49914D03*
X1187963Y52100D03*
X1193063Y49714D03*
X1187963Y49500D03*
X1193063Y52314D03*
X1181346Y46914D03*
X1181496Y36049D03*
X1184142Y52614D03*
X1193012Y47000D03*
X1187963Y46898D03*
Y35999D03*
X1187912Y54700D03*
X1187989Y65950D03*
X1193076Y65736D03*
X1193063Y54914D03*
X1193023Y35800D03*
X1204921Y36049D03*
X1198228D03*
Y46914D03*
X1204921D03*
X1201574Y52614D03*
X1184142Y67900D03*
X1201574Y67749D03*
X1218307Y36049D03*
X1211614Y35999D03*
X1214960Y52864D03*
X1211614Y46914D03*
X1218157D03*
X1208267Y52614D03*
X1211614Y73799D03*
X1218307Y73849D03*
X1208267Y90414D03*
X1218157Y84714D03*
X1211614D03*
X1181496Y92757D03*
X1184142Y71500D03*
Y87714D03*
X1208267Y71900D03*
X1204921Y92757D03*
X1208267Y87714D03*
X1201574Y71900D03*
X1198228Y92757D03*
X1201574Y87714D03*
X1218307Y92757D03*
X1214574Y71500D03*
X1211614Y92757D03*
X1214874Y87374D03*
X1187963Y89900D03*
X1193063Y70949D03*
Y87514D03*
X1187963Y71199D03*
Y87300D03*
X1214574Y67749D03*
X1208267D03*
X1181496Y65699D03*
X1204921D03*
X1198228D03*
X1218307D03*
X1211614D03*
X1187989Y68550D03*
X1193063Y68340D03*
X1181496Y54957D03*
X1184142Y49914D03*
X1193063Y90114D03*
X1181346Y84714D03*
X1181496Y73849D03*
X1184142Y90414D03*
X1193039Y84700D03*
X1193063Y92714D03*
X1187939Y92500D03*
X1187963Y84698D03*
Y73799D03*
X1193089Y73550D03*
X1198228Y73849D03*
X1204921D03*
X1198228Y84714D03*
X1204921D03*
X1201574Y90414D03*
X1177799Y109914D03*
X1161632Y104314D03*
X1167925Y112357D03*
X1170721Y106964D03*
X1161632Y112357D03*
X1164428Y106964D03*
X1174742Y112357D03*
X1177849Y107314D03*
X1170721Y109564D03*
X1164428D03*
X1168075Y104314D03*
X1174742D03*
X1208267Y110014D03*
X1181496Y112357D03*
X1184142Y106964D03*
X1204921Y112357D03*
X1208267Y107314D03*
X1198228Y112357D03*
X1201574Y107314D03*
X1187963Y110514D03*
X1193063Y107655D03*
X1187989Y107865D03*
X1193089Y110264D03*
X1181346Y104314D03*
X1187963Y113114D03*
X1193089Y112865D03*
X1184142Y109564D03*
X1193076Y105051D03*
X1187989Y105265D03*
X1201574Y110014D03*
X1198228Y104314D03*
X1204921D03*
X1208519Y218147D03*
X1210070Y195300D03*
X1191619Y212296D03*
X1167960Y214247D03*
X1164580Y208397D03*
X1181479Y214247D03*
X1194999Y218147D03*
X1174719Y214247D03*
X1161200D03*
Y206446D03*
X1167960Y206447D03*
Y218147D03*
X1171339Y216196D03*
X1178099Y204496D03*
X1174719Y202547D03*
X1171339Y208397D03*
X1174719Y218147D03*
Y206447D03*
X1178099Y208397D03*
Y216196D03*
X1161200Y210346D03*
Y218147D03*
X1209033Y183907D03*
X1210000Y192500D03*
X1181479Y206447D03*
X1188239Y210346D03*
Y206447D03*
X1201759Y218147D03*
X1205759Y206682D03*
X1197492Y201356D03*
X1198379Y212296D03*
X1194999Y210346D03*
X1184859Y204496D03*
X1188239Y214247D03*
X1181479Y218147D03*
X1191619Y208397D03*
X1188239Y202247D03*
X1181479Y202547D03*
X1218868Y214869D03*
X1218000Y218100D03*
X1198379Y216196D03*
X1188239Y218147D03*
X1184859Y212296D03*
X1181479Y210346D03*
X1184859Y216196D03*
X1174719Y210346D03*
X1164580Y212296D03*
X1184859Y208397D03*
X1178099Y212296D03*
X1194999Y214247D03*
X1191619Y216196D03*
X1171339Y212296D03*
X1167960Y210346D03*
X1164580Y216196D03*
X1178099Y223996D03*
X1174719Y241547D03*
X1178099Y239596D03*
X1174719Y245447D03*
X1178099Y251296D03*
X1171339Y270796D03*
X1178099Y266896D03*
Y262996D03*
X1191619Y223996D03*
X1181479Y253247D03*
X1164580Y243496D03*
Y274696D03*
X1167960Y280547D03*
X1171339Y262996D03*
X1174719Y264947D03*
X1171339Y278596D03*
X1161200Y276646D03*
Y280547D03*
X1167960Y268847D03*
X1188239D03*
X1205139Y278596D03*
X1184859Y227896D03*
X1198379Y223996D03*
X1188239Y245447D03*
X1194999Y229847D03*
X1178099Y231797D03*
X1171339Y227896D03*
X1174719Y222047D03*
X1208519Y253247D03*
X1205139Y262996D03*
X1181479Y280547D03*
X1191619Y235696D03*
X1164580Y231797D03*
X1205139Y270796D03*
X1198379Y274696D03*
X1201759Y253247D03*
X1194999Y261047D03*
X1188239Y253247D03*
X1181479Y245447D03*
X1212199Y227896D03*
X1184859Y220096D03*
X1205139Y223996D03*
X1161200Y237647D03*
X1205139Y243496D03*
Y235696D03*
Y255196D03*
X1208519Y229847D03*
X1164580Y235696D03*
X1167960Y229847D03*
X1164580Y223996D03*
Y227896D03*
Y239596D03*
X1171339Y251296D03*
X1167960Y222047D03*
X1164580Y220096D03*
X1167960Y233746D03*
X1161200Y222047D03*
X1167960Y249347D03*
Y241547D03*
Y245447D03*
Y237647D03*
X1171339Y239596D03*
Y243496D03*
X1174719Y249347D03*
X1178099Y247396D03*
X1161200Y241547D03*
X1164580Y247396D03*
X1161200Y249347D03*
X1171339Y247396D03*
X1178099Y243496D03*
X1171339Y235696D03*
Y220096D03*
Y231797D03*
X1178099Y227896D03*
Y235696D03*
Y220096D03*
X1174719Y237647D03*
X1167960Y257147D03*
Y253247D03*
X1174719D03*
X1164580Y270796D03*
X1171339Y274696D03*
X1174719Y280547D03*
X1171339Y266896D03*
X1164580Y278596D03*
X1159578Y265117D03*
X1171339Y259096D03*
X1178099Y274696D03*
X1161200Y268847D03*
X1164580Y255196D03*
X1161200Y272747D03*
X1159410Y259720D03*
X1178099Y270796D03*
Y278596D03*
X1162300Y264947D03*
X1178099Y255196D03*
X1161200Y253247D03*
X1174719Y268847D03*
Y276646D03*
X1167960D03*
Y264947D03*
X1181479Y222047D03*
X1188239D03*
X1191619Y239596D03*
X1188239Y225947D03*
X1184859Y235696D03*
X1188239Y237647D03*
X1184859Y247396D03*
X1188239Y249347D03*
X1201759Y229847D03*
Y225947D03*
Y233746D03*
X1198379Y235696D03*
Y243496D03*
X1201759Y241547D03*
Y249347D03*
X1198379Y239596D03*
X1194999Y225947D03*
Y222047D03*
Y233746D03*
X1184859Y239596D03*
Y251296D03*
X1212199D03*
Y243496D03*
X1208519Y233746D03*
X1215700Y223600D03*
X1181479Y249347D03*
Y237647D03*
Y241547D03*
X1184859Y223996D03*
X1201759Y237647D03*
X1198379Y227896D03*
X1205139Y231797D03*
X1201759Y245447D03*
X1194999Y237647D03*
X1198379Y251296D03*
X1194999Y264947D03*
Y268847D03*
Y272747D03*
Y280547D03*
X1188239Y257147D03*
X1208519Y272747D03*
X1208819Y280547D03*
X1181479Y264947D03*
X1184859Y255196D03*
X1191619Y270796D03*
X1198379Y262996D03*
X1194999Y276646D03*
X1198379Y270796D03*
X1181479Y257147D03*
Y261047D03*
Y268847D03*
Y276646D03*
X1212199Y274696D03*
X1217200Y270500D03*
X1213808Y264800D03*
X1208519Y264947D03*
X1184859Y259096D03*
X1191619Y274696D03*
X1205139D03*
X1198379Y278596D03*
X1201759Y261047D03*
X1198379Y255196D03*
X1201759Y257147D03*
X1174719Y272747D03*
X1164580Y251296D03*
X1167960Y261047D03*
X1159390Y262460D03*
X1161200Y225947D03*
X1181479D03*
Y233746D03*
Y229847D03*
X1184859Y270796D03*
X1191619Y278596D03*
X1205139Y259096D03*
X1216234Y268055D03*
X1212199Y223996D03*
Y231797D03*
X1205139Y239596D03*
X1208519Y237647D03*
X1205139Y220096D03*
X1191619D03*
X1184859Y243496D03*
X1194999Y241547D03*
Y245447D03*
Y253247D03*
X1191619Y251296D03*
Y231797D03*
X1188239Y233746D03*
Y229847D03*
X1174719Y225947D03*
X1171339Y223996D03*
X1161200Y229847D03*
X1201759Y222047D03*
X1198379Y220096D03*
X1174719Y233746D03*
X1167960Y225947D03*
X1174719Y229847D03*
X1188239Y264947D03*
Y272747D03*
X1208519Y241547D03*
X1205139Y251296D03*
X1208519Y257147D03*
X1201759Y264947D03*
X1191619Y255196D03*
X1198379Y259096D03*
X1191619Y262996D03*
X1188239Y261047D03*
X1191619Y266896D03*
X1184859Y274696D03*
X1205139Y266896D03*
X1208519Y268847D03*
X1201759D03*
Y276646D03*
X1184859Y231797D03*
X1208519Y225947D03*
X1191619Y227896D03*
X1174719Y257147D03*
X1178099Y259096D03*
X1161200Y245447D03*
X1174719Y261047D03*
X1167960Y272747D03*
X1171339Y255196D03*
X1181479Y272747D03*
X1201759D03*
Y280547D03*
X1208519Y249347D03*
X1194999Y257147D03*
X1198379Y247396D03*
X1184859Y278596D03*
X1188239Y276646D03*
Y280547D03*
X1198379Y231797D03*
X1205139Y227896D03*
X1191619Y259096D03*
X1194999Y249347D03*
X1184859Y262996D03*
X1161200Y233746D03*
X1191619Y243496D03*
X1188239Y241547D03*
X1214732Y243496D03*
X1212199Y239596D03*
X1217476Y243482D03*
X1216234Y265555D03*
X1181479Y331247D03*
X1198379Y321496D03*
X1194999Y323446D03*
X1181479Y315647D03*
X1191619Y337096D03*
X1181479Y323446D03*
X1171339Y337096D03*
X1174719Y331247D03*
X1178099Y321496D03*
X1174719Y327347D03*
X1167960Y335147D03*
X1171339Y329296D03*
X1178099Y333196D03*
Y325396D03*
X1171339Y333196D03*
X1178099Y329296D03*
X1174719Y319547D03*
X1171339Y282496D03*
X1167960Y284447D03*
X1164580Y282496D03*
X1184859Y298096D03*
X1191619Y313696D03*
X1188239Y300047D03*
X1191619Y340996D03*
X1188239Y331247D03*
Y327347D03*
X1194999Y311747D03*
X1184859Y305896D03*
X1188239Y296147D03*
X1181479D03*
X1191619Y325396D03*
X1188239Y307847D03*
X1208819Y284447D03*
X1174719Y323446D03*
X1161200Y288347D03*
Y292247D03*
X1201759D03*
X1171339Y340996D03*
X1174719Y300047D03*
Y284447D03*
X1164580Y294196D03*
Y290296D03*
Y286396D03*
X1161200Y284447D03*
X1178099Y294196D03*
Y298096D03*
Y286396D03*
X1164580Y301996D03*
X1171339D03*
X1161200Y307847D03*
X1174719Y292247D03*
Y288347D03*
X1171339Y286396D03*
Y290296D03*
X1167960Y300047D03*
X1164580Y298096D03*
X1167960Y296147D03*
Y292247D03*
Y288347D03*
X1161200Y296147D03*
X1178099Y290296D03*
X1161200Y311747D03*
Y300047D03*
Y303947D03*
X1174719D03*
X1167960D03*
X1178099Y309797D03*
X1171339Y305896D03*
X1164580Y309797D03*
Y305896D03*
X1167960Y307847D03*
Y311747D03*
X1171339Y309797D03*
X1178099Y301996D03*
X1174719Y311747D03*
Y307847D03*
X1178099Y305896D03*
X1171339Y298096D03*
Y294196D03*
X1174719Y296147D03*
X1161200Y335147D03*
Y339047D03*
X1164580Y329296D03*
Y333196D03*
Y337096D03*
X1167960Y339047D03*
Y327347D03*
X1161200Y331247D03*
Y327347D03*
X1178099Y337096D03*
Y317596D03*
X1164580Y321496D03*
Y317596D03*
X1161200Y323446D03*
Y319547D03*
Y315647D03*
X1167960Y323446D03*
Y315647D03*
Y319547D03*
X1174719Y315647D03*
X1171339Y317596D03*
X1164580Y325396D03*
X1171339D03*
X1174719Y335147D03*
Y339047D03*
X1164580Y340996D03*
X1167960Y331247D03*
X1171339Y321496D03*
X1178099Y313696D03*
X1171339D03*
X1164580D03*
X1205500Y309797D03*
X1198379D03*
X1194999Y288347D03*
Y292247D03*
Y296147D03*
Y300047D03*
Y307847D03*
Y303947D03*
X1191619Y298096D03*
X1198379Y282496D03*
X1181479Y300047D03*
Y288347D03*
Y292247D03*
Y311747D03*
Y307847D03*
Y303947D03*
X1188239Y288347D03*
Y284447D03*
Y292247D03*
X1184859Y294196D03*
Y290296D03*
X1191619Y294196D03*
X1184859Y309797D03*
X1188239Y311747D03*
X1184859Y301996D03*
X1201759Y284447D03*
Y288347D03*
X1205439Y298096D03*
X1198379Y286396D03*
X1205439Y305896D03*
X1194999Y335147D03*
Y331247D03*
X1212200Y333196D03*
X1208519Y339047D03*
X1208826Y319544D03*
X1184859Y325396D03*
Y333196D03*
X1198379Y337096D03*
Y329296D03*
X1181479Y327347D03*
Y319547D03*
Y335147D03*
X1198379Y313696D03*
X1188239Y319547D03*
X1184859Y321496D03*
X1188239Y339047D03*
Y335147D03*
X1184859Y329296D03*
X1191619Y321496D03*
X1198379Y325396D03*
Y340996D03*
X1201759Y323446D03*
X1205139Y333196D03*
X1194999Y319547D03*
Y315647D03*
X1181479Y339047D03*
X1178099Y340996D03*
X1205139D03*
X1201759Y339047D03*
X1198379Y333196D03*
X1201759Y335147D03*
Y331247D03*
X1184859Y337096D03*
X1191619Y309797D03*
X1188239Y303947D03*
X1194999Y327347D03*
X1184859Y317596D03*
X1191619D03*
Y305896D03*
Y301996D03*
X1184859Y340996D03*
X1194999Y339047D03*
X1191619Y333196D03*
Y329296D03*
X1188239Y323446D03*
X1184859Y313696D03*
X1188239Y315647D03*
X1198379Y290296D03*
Y294196D03*
X1205439Y286596D03*
X1181479Y284447D03*
X1205439Y294196D03*
X1191619Y282496D03*
Y290296D03*
X1205439D03*
X1191619Y286396D03*
X1178099Y282496D03*
X1205139D03*
X1184859D03*
X1194999Y284447D03*
X1184859Y286396D03*
X1161201Y401447D03*
X1178099Y368296D03*
X1164580Y391696D03*
X1171339Y352696D03*
X1164580Y364396D03*
X1167960Y350747D03*
X1161200Y362447D03*
Y358547D03*
X1178099Y352696D03*
X1164580Y376096D03*
X1194999Y350747D03*
X1198379Y348796D03*
X1184859Y379996D03*
X1188239Y350747D03*
X1191619Y356596D03*
X1184859Y372197D03*
X1181479Y366347D03*
Y362447D03*
X1188239D03*
Y358547D03*
Y354647D03*
X1198379Y383896D03*
X1191619Y379996D03*
X1184859Y376096D03*
X1198379D03*
X1171339Y391696D03*
X1191619Y344896D03*
X1178099Y376096D03*
X1171339Y395596D03*
X1174719Y389747D03*
X1171339Y383896D03*
X1161200Y389747D03*
X1164580Y395597D03*
X1178099Y387796D03*
X1167960Y346847D03*
X1164580Y360496D03*
X1161200Y366347D03*
X1167960Y354647D03*
X1161200D03*
X1164580Y368296D03*
X1181479Y378047D03*
X1188239Y374146D03*
X1184859Y368296D03*
Y364396D03*
X1181479Y358547D03*
X1184859Y360496D03*
X1167960Y370247D03*
X1164580Y372197D03*
X1171339Y356596D03*
Y360496D03*
X1164580Y356596D03*
X1167960Y342947D03*
X1171339Y348796D03*
X1174719Y354647D03*
Y342947D03*
X1161200Y370247D03*
X1171339Y372197D03*
X1167960Y362447D03*
X1178099Y364396D03*
X1174719Y346847D03*
X1178099Y348796D03*
Y344896D03*
X1167960Y358547D03*
X1171339Y344896D03*
X1174719Y350747D03*
X1167960Y366347D03*
X1171339Y368296D03*
Y399496D03*
X1164580Y403396D03*
X1178099D03*
X1167960Y389747D03*
X1161200Y397546D03*
X1167960Y397547D03*
X1161200Y374146D03*
X1178099Y391696D03*
X1174719Y397546D03*
X1164580Y399496D03*
X1174719Y393647D03*
X1161200Y378047D03*
X1164580Y379996D03*
X1174719Y381947D03*
X1194999Y346847D03*
Y354647D03*
X1209219Y370247D03*
X1212199Y356597D03*
Y344896D03*
Y352696D03*
X1188239Y370247D03*
X1191619Y372197D03*
Y364396D03*
Y352696D03*
X1194999Y342947D03*
X1181479Y346847D03*
X1188239Y366347D03*
X1194999D03*
X1191619Y348796D03*
X1184859Y356596D03*
X1191619Y360496D03*
X1201759Y350747D03*
X1205139Y360496D03*
X1181479Y374146D03*
Y389747D03*
X1209769Y374146D03*
X1184859Y383896D03*
X1188239Y393647D03*
X1201759Y389747D03*
X1197258Y397546D03*
X1194999Y385847D03*
X1188239Y378047D03*
X1201759D03*
X1208819Y393647D03*
Y381897D03*
X1181479Y385847D03*
X1188239Y381947D03*
X1208819Y385847D03*
X1181479Y393647D03*
X1184859Y399496D03*
X1178099Y395596D03*
X1174719Y401447D03*
X1198379Y356596D03*
Y360496D03*
X1181479Y370247D03*
X1174719D03*
X1178099Y360496D03*
X1191619Y383896D03*
X1167960Y381947D03*
X1181479Y342947D03*
X1201759Y346847D03*
X1198379Y344896D03*
X1201759Y342947D03*
X1184859Y387796D03*
X1188239Y385847D03*
Y389747D03*
X1194999Y370247D03*
X1184859Y391696D03*
Y395596D03*
X1181479Y397546D03*
X1178099Y399496D03*
X1171339Y403396D03*
X1198379Y352696D03*
X1201759Y358547D03*
X1194999Y362447D03*
X1198379Y372197D03*
Y364396D03*
X1167960Y401447D03*
X1194999Y374146D03*
X1171339Y364396D03*
X1201759Y374146D03*
X1194999Y378047D03*
X1178099Y372197D03*
X1171339Y376096D03*
X1167960Y374146D03*
X1171339Y379996D03*
X1164580Y383896D03*
X1161200Y381947D03*
X1181479Y350747D03*
Y354647D03*
X1174719Y358547D03*
Y362447D03*
Y366347D03*
X1178099Y356596D03*
X1184859Y348796D03*
X1174719Y374146D03*
Y378047D03*
X1167960D03*
X1188239Y346847D03*
Y342947D03*
X1181479Y381947D03*
X1167960Y385847D03*
X1161200D03*
X1164580Y387796D03*
X1174719Y385847D03*
X1178099Y383896D03*
Y379996D03*
X1161200Y393647D03*
X1184859Y352696D03*
X1198379Y379996D03*
X1194999Y381947D03*
X1167960Y393647D03*
X1184859Y344896D03*
X1171339Y387796D03*
X1197100Y408200D03*
X1198029Y405411D03*
X1195555Y405773D03*
X1192200Y409550D03*
X1185989Y407800D03*
X1181479Y405347D03*
X1174719D03*
X1167960D03*
X1161417Y518157D03*
X1174803D03*
X1177849Y513114D03*
X1180400Y495787D03*
X1167500Y495800D03*
X1174203Y495787D03*
X1161320Y495800D03*
X1170656Y491144D03*
X1164363Y491044D03*
X1177849Y490944D03*
X1170656Y493844D03*
X1164363Y493744D03*
X1177799Y493544D03*
X1168110Y510114D03*
X1164763Y515814D03*
X1161417Y510114D03*
X1177799Y515714D03*
X1171456Y515814D03*
X1174803Y510114D03*
X1168110Y518157D03*
X1171456Y513114D03*
X1208267Y493444D03*
X1200974Y490744D03*
X1193063Y490909D03*
X1187978Y490609D03*
X1184142Y490794D03*
Y493394D03*
X1200974Y493344D03*
X1193063Y493509D03*
X1208267Y496144D03*
X1187978Y495909D03*
X1193063Y496209D03*
X1181346Y510114D03*
X1204400Y495887D03*
X1198100Y495800D03*
X1208267Y515814D03*
X1211614Y510114D03*
X1218157D03*
X1187963Y510098D03*
X1204921Y510114D03*
X1198228D03*
X1201574Y515814D03*
X1184142D03*
X1187939Y517900D03*
X1193039Y510100D03*
X1193063Y518114D03*
X1187978Y498609D03*
X1193063Y498909D03*
X1181496Y518157D03*
X1184142Y513114D03*
X1204921Y518157D03*
X1208267Y513114D03*
X1198228Y518157D03*
X1201574Y513114D03*
X1211614Y518157D03*
X1214874Y512774D03*
X1187963Y515300D03*
X1193063Y512914D03*
X1187963Y512700D03*
X1193063Y515514D03*
X1204400Y498487D03*
X1198100Y498400D03*
X1187978Y493209D03*
X1180400Y498387D03*
X1174203D03*
X1161417Y498487D03*
X1167510D03*
X1218307Y518157D03*
X1164763Y513114D03*
Y535100D03*
X1177763Y534700D03*
X1174803Y528899D03*
X1171456Y550914D03*
X1164763D03*
X1177849D03*
X1161417Y547914D03*
X1168110D03*
X1174803D03*
X1177799Y553514D03*
X1177763Y530949D03*
X1168110Y537049D03*
X1164763Y530949D03*
X1161417Y537049D03*
X1171456Y530949D03*
X1174803Y536999D03*
X1164763Y553614D03*
X1171456D03*
Y535100D03*
X1168110Y528899D03*
X1161417Y566699D03*
X1174803D03*
X1171456Y588714D03*
X1164763D03*
X1177849D03*
X1174803Y574799D03*
X1161417Y574849D03*
X1171456Y568749D03*
X1168110Y585714D03*
X1161417D03*
X1168110Y574849D03*
X1164763Y568749D03*
X1174803Y585714D03*
X1177763Y568749D03*
X1184142Y550914D03*
X1208267D03*
X1201574D03*
X1214874Y550574D03*
X1187963Y553100D03*
X1193063Y550714D03*
Y553314D03*
X1181496Y537049D03*
X1181346Y547914D03*
X1211614Y536999D03*
X1214574Y530949D03*
X1184142Y531100D03*
X1193076Y528936D03*
X1198228Y547914D03*
X1204921D03*
X1201574Y553614D03*
Y530949D03*
X1204921Y537049D03*
X1198228D03*
X1193039Y547900D03*
X1187963Y547898D03*
X1184142Y553614D03*
X1193089Y536750D03*
X1187989Y529150D03*
X1187963Y536999D03*
X1218307Y537049D03*
X1211614Y547914D03*
X1208267Y553614D03*
Y530949D03*
X1218157Y547914D03*
X1184142Y534700D03*
X1181496Y528899D03*
X1208267Y535100D03*
X1204921Y528899D03*
X1201574Y535100D03*
X1198228Y528899D03*
X1218307D03*
X1214574Y534700D03*
X1211614Y528899D03*
X1187989Y531750D03*
X1193063Y534149D03*
X1187963Y534399D03*
X1193063Y531540D03*
X1201574Y588714D03*
X1214660D03*
X1193063Y588514D03*
X1187963Y588300D03*
X1181346Y585714D03*
X1181496Y574849D03*
X1193063Y555914D03*
X1187939Y555700D03*
X1218157Y585714D03*
X1218307Y574849D03*
X1208267Y568749D03*
X1214574D03*
X1211614Y574799D03*
Y585714D03*
X1184142Y568900D03*
X1187989Y566950D03*
X1193076Y566736D03*
X1193039Y585700D03*
X1187963Y585698D03*
X1193089Y574550D03*
X1187963Y574799D03*
X1198228Y585714D03*
Y574849D03*
X1204921Y585714D03*
Y574849D03*
X1201574Y568749D03*
X1181496Y566699D03*
X1204921D03*
X1198228D03*
X1218307Y555957D03*
Y566699D03*
X1211614Y555957D03*
X1214574Y572500D03*
X1211614Y566699D03*
X1187989Y569550D03*
X1193063Y571949D03*
Y569340D03*
X1184142Y588714D03*
X1208267D03*
X1204921Y555957D03*
X1198228D03*
X1187963Y550500D03*
X1184142Y572500D03*
X1201574Y572900D03*
X1187963Y572199D03*
X1208267Y572900D03*
X1181496Y555957D03*
X1174803D03*
X1161417D03*
X1171456Y572900D03*
X1168110Y555957D03*
Y566699D03*
X1177763Y572500D03*
X1164763Y572900D03*
X1161417Y528899D03*
X1181496Y612649D03*
X1218307D03*
X1211614Y612599D03*
X1187963D03*
X1204921Y612649D03*
X1198228D03*
X1168110D03*
X1161417D03*
X1174803Y612599D03*
X1168110Y593757D03*
X1171456Y610700D03*
X1168110Y604499D03*
X1161417Y593757D03*
Y604499D03*
X1174803Y593757D03*
X1177763Y610300D03*
X1174803Y604499D03*
X1171456Y606549D03*
X1164763D03*
Y591414D03*
X1171456D03*
X1177799Y591314D03*
X1177763Y606549D03*
X1204921Y604499D03*
X1198228Y593757D03*
X1201574Y610700D03*
X1198228Y604499D03*
X1218307Y593757D03*
Y604499D03*
X1211614Y593757D03*
X1214574Y610300D03*
X1211614Y604499D03*
X1187963Y590900D03*
X1187989Y607350D03*
X1193063Y609749D03*
X1187963Y609999D03*
X1193063Y591114D03*
Y607140D03*
X1208267Y591414D03*
X1214574Y606549D03*
X1208267D03*
X1187939Y593500D03*
X1184142Y591414D03*
X1193063Y593714D03*
X1187989Y604750D03*
X1193076Y604536D03*
X1193089Y612350D03*
X1184142Y606700D03*
X1201574Y591414D03*
Y606549D03*
X1181496Y593757D03*
X1184142Y610300D03*
X1181496Y604499D03*
X1208267Y610700D03*
X1204921Y593757D03*
X1164763Y610700D03*
X1238385Y29949D03*
Y14814D03*
X1245078Y29949D03*
Y14814D03*
X1251771Y16999D03*
X1248425Y27899D03*
X1269700Y13078D03*
X1267960Y28494D03*
X1241732Y27899D03*
X1251771D03*
X1248425Y17057D03*
X1258464Y27899D03*
X1261811D03*
Y16999D03*
X1258464D03*
X1265157Y27899D03*
Y16999D03*
X1241732Y-1751D03*
X1238385Y-7851D03*
X1241732Y9114D03*
X1248425Y-1751D03*
Y-9901D03*
X1251771D03*
X1245078Y-7851D03*
X1248425Y9157D03*
X1269800Y-5822D03*
X1265157Y9157D03*
X1261000Y9100D03*
X1258464Y9157D03*
X1251771D03*
Y-1743D03*
X1261811Y-9901D03*
X1258464D03*
X1261811Y-1743D03*
X1265157D03*
X1258464D03*
X1265157Y-9901D03*
X1276346Y-10250D03*
X1278900Y-14800D03*
X1235039Y9114D03*
X1224774Y9098D03*
X1224822Y-9700D03*
X1229887Y-9864D03*
X1224774Y-1801D03*
X1235039Y-1751D03*
X1229922Y-2000D03*
X1220953Y-7700D03*
Y33700D03*
X1235039Y27899D03*
X1224800Y30750D03*
X1229874Y30540D03*
X1224774Y33399D03*
X1229874Y33149D03*
X1229800Y9300D03*
X1224790Y16900D03*
X1229874Y17114D03*
X1229887Y27936D03*
X1220953Y30100D03*
X1224800Y28100D03*
X1220953Y14814D03*
Y-4100D03*
X1245078Y-3700D03*
X1241732Y-9901D03*
X1238385Y-3700D03*
X1235039Y-9901D03*
X1224800Y-7050D03*
X1229874Y-7260D03*
X1224774Y-4401D03*
X1229874Y-4651D03*
X1255118Y-9901D03*
Y-1743D03*
X1220953Y12114D03*
X1241732Y17157D03*
X1245078Y12114D03*
X1235039Y17157D03*
X1238385Y12114D03*
X1224774Y14300D03*
X1229874Y14514D03*
X1224774Y11700D03*
X1229874Y11914D03*
X1255118Y27899D03*
Y16999D03*
Y9157D03*
X1241732Y36049D03*
Y46914D03*
X1238385Y52614D03*
Y67749D03*
X1245078Y52614D03*
X1251771Y65699D03*
X1248425D03*
Y36049D03*
Y46957D03*
X1245078Y67749D03*
X1267976Y73676D03*
X1268022Y54443D03*
X1241732Y65699D03*
Y54957D03*
X1245078Y34100D03*
Y49914D03*
X1238385Y34100D03*
Y49914D03*
X1251771Y36057D03*
Y54799D03*
X1248425Y54857D03*
X1251771Y46957D03*
X1258464D03*
Y36057D03*
Y54799D03*
X1261811Y46957D03*
Y54799D03*
X1265157Y36057D03*
X1261811D03*
X1265157Y46957D03*
X1261811Y65699D03*
X1258464D03*
X1265157D03*
X1267959Y47245D03*
X1268111Y58040D03*
X1241732Y92757D03*
X1245078Y71900D03*
Y87714D03*
X1238385Y71900D03*
Y87714D03*
X1251771Y84757D03*
X1248425Y92657D03*
X1265157Y73857D03*
X1261811D03*
X1258464D03*
X1261811Y84757D03*
X1258464D03*
X1265157D03*
X1251771Y73857D03*
X1261811Y92599D03*
X1258464D03*
X1241732Y84714D03*
Y73849D03*
X1238385Y90414D03*
X1251771Y92599D03*
X1245078Y90414D03*
X1248425Y84757D03*
Y73849D03*
X1268581Y92706D03*
X1220953Y49914D03*
X1235039Y54957D03*
X1224774Y52100D03*
X1229874Y52314D03*
X1224774Y49500D03*
X1229874Y49714D03*
X1224774Y84698D03*
X1224750Y92500D03*
X1224774Y73799D03*
X1235039Y84714D03*
Y73849D03*
X1220953Y71500D03*
Y87714D03*
X1235039Y92757D03*
X1224774Y89900D03*
X1229874Y70949D03*
Y87514D03*
X1224774Y71199D03*
Y87300D03*
X1229800Y35750D03*
X1229874Y54914D03*
X1235039Y46914D03*
Y36049D03*
X1224774Y46898D03*
X1220953Y52614D03*
X1224774Y35999D03*
X1229887Y65736D03*
X1224800Y65950D03*
X1220953Y67900D03*
X1235039Y65699D03*
X1224800Y68550D03*
X1229874Y68340D03*
Y90114D03*
X1229900Y73550D03*
X1229850Y84700D03*
X1229874Y92714D03*
X1220953Y90414D03*
X1255118Y65699D03*
Y54799D03*
Y36057D03*
Y46957D03*
X1265157Y54799D03*
X1255118Y92599D03*
Y84757D03*
Y73857D03*
X1265157Y92599D03*
X1240927Y154932D03*
X1243948Y154916D03*
X1251344Y127925D03*
X1277100Y122670D03*
X1264550Y114670D03*
X1277100Y114800D03*
X1261030Y105350D03*
X1268900Y122500D03*
X1270350Y98300D03*
X1277600Y106200D03*
X1268576Y117788D03*
X1275470Y99390D03*
X1266200Y122500D03*
X1254024Y128013D03*
X1246251Y130066D03*
X1257800Y110900D03*
X1260500Y117500D03*
X1247326Y122802D03*
X1254300Y105200D03*
X1277660Y109450D03*
X1277230Y117570D03*
X1278030Y148510D03*
X1237704Y148423D03*
X1269810Y154398D03*
X1249025Y130460D03*
X1263798Y133493D03*
X1278000Y145780D03*
X1268236Y141938D03*
X1272100Y141603D03*
X1265828Y140568D03*
X1237400Y103100D03*
X1268600Y104700D03*
X1266646Y150540D03*
X1257850Y116950D03*
Y113850D03*
X1255400Y108000D03*
X1259950Y144650D03*
X1264700Y154800D03*
X1240022Y141773D03*
X1261546Y150584D03*
X1264146D03*
X1268500Y102100D03*
X1271500D03*
X1240000Y129500D03*
X1271500Y122500D03*
X1271490Y104700D03*
X1248616Y133817D03*
X1261800Y154973D03*
X1262569Y147201D03*
X1252000Y145300D03*
X1252437Y140192D03*
X1260737Y133877D03*
X1251980Y106960D03*
X1250200Y122900D03*
X1240010Y144754D03*
X1257800Y120800D03*
X1221767Y175858D03*
X1233902Y173337D03*
X1240309Y161900D03*
X1267050Y169800D03*
X1241381Y172040D03*
X1246655Y176395D03*
X1244410Y173150D03*
X1246910D03*
X1242800Y175200D03*
X1263080Y191320D03*
X1260140Y191670D03*
X1263300Y169450D03*
X1241712Y187710D03*
X1259200Y168350D03*
X1252800Y176000D03*
X1255200D03*
X1267800Y161800D03*
X1271400Y161900D03*
X1260510Y206840D03*
X1267220Y203600D03*
X1267218Y207495D03*
X1258810Y204840D03*
X1263728Y211444D03*
X1262250Y201227D03*
X1265718Y201459D03*
X1258482Y201495D03*
X1257770Y199150D03*
X1260260Y199862D03*
X1264180Y199510D03*
X1240500Y218200D03*
X1240452Y208240D03*
Y215740D03*
Y213240D03*
Y210740D03*
X1243196Y207002D03*
X1242800Y204150D03*
X1244380Y202160D03*
X1255310Y193850D03*
X1252930Y193270D03*
X1263040Y193930D03*
X1259360Y193950D03*
X1257210Y192340D03*
X1268986Y205727D03*
X1269254Y197923D03*
X1270930Y200220D03*
X1268930Y201820D03*
X1272522Y202191D03*
X1270754Y203959D03*
X1267486Y199691D03*
X1262018Y197959D03*
X1265786Y197691D03*
X1259518Y197459D03*
X1263950Y203227D03*
X1260620Y203130D03*
X1255982Y200995D03*
X1255833Y197423D03*
X1256810Y203340D03*
X1262182Y204995D03*
X1265420Y205400D03*
X1250235Y199342D03*
X1251940Y197530D03*
X1247803Y198486D03*
X1254065Y199191D03*
X1252330Y201030D03*
X1254310Y202840D03*
X1250625Y202804D03*
X1248290Y201720D03*
X1246620Y203570D03*
X1246090Y200330D03*
X1245014Y205405D03*
X1251089Y194810D03*
X1249571Y196718D03*
X1253521Y195666D03*
X1267554Y195923D03*
X1261220Y195650D03*
X1263804Y196318D03*
X1265570Y194510D03*
X1257601Y195655D03*
X1262080Y209140D03*
X1265450Y209263D03*
X1263680Y207160D03*
X1229780Y181980D03*
Y178980D03*
X1232780Y181980D03*
X1226914Y184708D03*
X1232780Y178980D03*
X1226780D03*
Y181980D03*
X1226785Y210403D03*
X1221300Y205400D03*
X1226500Y199800D03*
X1226867Y207904D03*
X1220167Y194407D03*
X1227200Y215543D03*
X1220702Y216708D03*
X1226785Y213003D03*
X1221300Y208000D03*
X1226500Y202400D03*
X1220580Y179810D03*
X1243300Y223100D03*
X1268404Y246304D03*
X1277504Y250346D03*
X1275154Y236296D03*
X1279950Y229338D03*
X1276628Y234270D03*
X1272761Y240220D03*
X1278183Y231886D03*
X1274100Y255300D03*
X1275577Y253123D03*
X1251395Y226373D03*
X1253791Y226228D03*
X1248672Y226494D03*
X1252221Y228668D03*
X1245300Y224800D03*
X1220017Y220323D03*
X1220194Y243384D03*
X1223100Y258600D03*
X1223508Y262600D03*
X1270478Y243490D03*
X1279393Y247602D03*
X1225908Y259300D03*
Y261800D03*
X1243399Y398339D03*
X1249230Y402022D03*
X1246010Y400110D03*
X1262700Y461804D03*
X1259800Y463300D03*
X1255530Y474770D03*
X1277978Y491571D03*
X1258140Y474540D03*
X1271571Y479000D03*
X1271662Y487326D03*
X1271640Y474420D03*
X1271647Y482500D03*
X1269050Y486650D03*
X1269600Y480800D03*
X1272830Y471660D03*
X1257720Y493060D03*
X1255388Y483557D03*
X1256130Y467820D03*
X1265157Y510157D03*
X1261811Y517999D03*
X1258464Y510157D03*
Y517999D03*
X1261811Y510157D03*
X1248425Y518057D03*
X1251771Y510157D03*
X1262843Y497553D03*
X1277800Y497108D03*
X1280595Y496439D03*
X1266162Y496404D03*
X1269006Y496016D03*
X1241732Y510114D03*
X1238385Y515814D03*
X1269000Y514700D03*
X1245078Y515814D03*
X1251771Y517999D03*
X1248425Y510157D03*
X1241732Y518157D03*
X1245078Y513114D03*
X1238385D03*
X1278573Y519596D03*
X1235039Y510114D03*
X1220953Y515814D03*
X1229874Y518114D03*
X1229850Y510100D03*
X1224750Y517900D03*
X1224774Y510098D03*
X1220953Y513114D03*
X1235039Y518157D03*
X1224774Y515300D03*
X1229874Y512914D03*
X1224774Y512700D03*
X1229874Y515514D03*
X1274576Y510235D03*
X1267584Y499694D03*
X1271105Y498516D03*
X1271300Y510600D03*
X1269209Y501777D03*
X1255120Y510158D03*
Y518000D03*
X1248474Y488913D03*
X1249193Y491308D03*
X1265157Y517999D03*
X1262900Y466504D03*
X1256320Y490660D03*
X1258126Y469540D03*
X1256350Y486080D03*
X1255120Y574834D03*
X1265157Y547957D03*
X1261811D03*
X1258464D03*
X1251771D03*
X1265157Y537057D03*
X1261811D03*
X1258464Y528899D03*
X1251771Y537057D03*
X1258464D03*
X1261811Y528899D03*
X1265157Y528876D03*
X1277200Y539100D03*
X1277137Y547393D03*
X1279318Y545212D03*
X1241732Y547914D03*
Y537049D03*
X1238385Y530949D03*
Y553614D03*
X1269800Y532978D03*
X1251771Y528899D03*
X1248425Y537049D03*
Y528899D03*
X1245078Y553614D03*
Y530949D03*
X1248425Y547957D03*
X1245078Y535100D03*
X1241732Y528899D03*
X1238385Y535100D03*
X1245078Y550914D03*
X1238385D03*
X1241732Y574849D03*
Y585714D03*
X1238385Y568749D03*
X1268500Y555800D03*
X1267900Y574300D03*
X1248425Y585757D03*
Y574849D03*
Y566699D03*
X1245078Y568749D03*
X1241732Y555957D03*
X1245078Y572900D03*
X1241732Y566699D03*
X1238385Y572900D03*
X1245078Y588714D03*
X1238385D03*
X1265157Y585757D03*
X1261811D03*
X1258464D03*
X1251771D03*
X1261811Y555799D03*
X1258464D03*
X1251771D03*
X1248425Y555857D03*
X1251771Y566699D03*
Y574857D03*
X1265157D03*
X1261811D03*
X1258464D03*
X1261811Y566699D03*
X1258464D03*
X1273200Y582200D03*
X1265157Y566676D03*
Y555799D03*
X1220953Y550914D03*
X1229874Y550714D03*
X1224774Y550500D03*
X1229874Y553314D03*
X1220953Y531100D03*
X1229887Y528936D03*
X1229900Y536750D03*
X1224800Y529150D03*
X1224774Y536999D03*
X1235039Y537049D03*
Y547914D03*
X1229850Y547900D03*
X1224774Y547898D03*
X1220953Y553614D03*
X1235039Y528899D03*
X1224800Y531750D03*
X1229874Y534149D03*
X1224774Y534399D03*
X1229874Y531540D03*
X1220953Y588714D03*
X1229874Y588514D03*
X1224774Y588300D03*
X1229874Y555914D03*
X1224750Y555700D03*
X1220953Y568900D03*
X1229900Y574550D03*
X1224774Y574799D03*
X1229850Y585700D03*
X1224774Y585698D03*
X1229887Y566736D03*
X1224800Y566950D03*
X1235039Y585714D03*
Y574849D03*
X1220953Y572500D03*
X1235039Y555957D03*
Y566699D03*
X1229874Y571949D03*
X1224774Y572199D03*
X1229874Y569340D03*
X1255120Y537034D03*
Y555144D03*
X1224774Y553100D03*
X1224800Y569550D03*
X1220953Y534700D03*
X1265157Y604476D03*
Y593599D03*
X1241732Y612649D03*
X1238385Y606549D03*
Y591414D03*
X1263800Y606800D03*
X1267800Y593600D03*
X1248425Y612649D03*
X1251771Y604499D03*
X1248425D03*
X1245078Y606549D03*
X1251771Y593599D03*
X1245078Y591414D03*
X1270400Y593600D03*
X1241732Y593757D03*
X1245078Y610700D03*
X1241732Y604499D03*
X1238385Y610700D03*
X1258464Y593599D03*
X1261811D03*
X1248425Y593657D03*
X1251771Y612657D03*
X1258464Y604499D03*
X1261811D03*
X1265157Y612657D03*
X1261811D03*
X1258464D03*
X1224774Y612599D03*
X1235039Y612649D03*
X1220953Y610300D03*
X1235039Y593757D03*
Y604499D03*
X1224774Y590900D03*
X1224800Y607350D03*
X1229874Y609749D03*
X1224774Y609999D03*
X1229874Y591114D03*
Y607140D03*
X1220953Y591414D03*
X1229874Y593714D03*
X1224750Y593500D03*
X1224800Y604750D03*
X1229887Y604536D03*
X1220953Y606700D03*
X1229900Y612350D03*
X1255120Y612634D03*
Y593600D03*
X1301279Y10058D03*
X1304079D03*
X1306879D03*
X1301200Y12610D03*
X1306800D03*
X1303774Y-18842D03*
X1299549Y-18619D03*
X1287700Y-16700D03*
X1292692Y1008D03*
X1299369Y-15680D03*
X1293600Y-17000D03*
X1293816Y-13533D03*
X1282252Y-14747D03*
X1284859Y-14524D03*
X1301200Y15200D03*
X1301100Y2700D03*
X1316300Y-14800D03*
X1320800Y-16900D03*
X1307900Y-14700D03*
X1309500Y-16800D03*
X1323600Y-16900D03*
X1322000Y-14800D03*
X1324800D03*
X1326000Y-12700D03*
X1323600Y-12600D03*
X1327600Y-14800D03*
Y4700D03*
X1326400Y2600D03*
X1324800Y4700D03*
X1322000D03*
X1323600Y2600D03*
X1306700Y2700D03*
X1309500D03*
X1307900Y4800D03*
X1320800Y2600D03*
X1316300Y4700D03*
X1317900Y2600D03*
X1319200Y4700D03*
X1313500Y4800D03*
X1315004Y2567D03*
X1326400Y-16900D03*
X1302300Y4800D03*
X1303900Y2700D03*
X1310700Y4800D03*
X1312300Y2700D03*
X1305100Y4800D03*
X1322532Y9822D03*
X1325332D03*
X1306700Y-16800D03*
X1328800Y-12700D03*
X1312300Y-16800D03*
X1310700Y-14700D03*
X1315004Y-16933D03*
X1313500Y-14700D03*
X1319200Y-14800D03*
X1317900Y-16900D03*
X1321452Y31803D03*
X1304000Y15200D03*
X1328085Y9865D03*
X1322483Y12834D03*
X1328045Y15831D03*
X1325308Y15734D03*
X1322508D03*
X1328123Y12730D03*
X1306800Y15200D03*
X1328987Y2525D03*
X1313942Y30714D03*
X1309760Y30691D03*
X1316300Y31911D03*
X1318700Y31943D03*
X1311809Y32096D03*
X1325383Y12634D03*
X1304940Y32350D03*
X1304000Y12610D03*
X1336500Y81100D03*
X1320000Y85500D03*
X1327168Y61483D03*
X1296935Y51335D03*
X1296908Y36900D03*
X1296928Y48700D03*
X1295581Y94320D03*
X1298422Y74000D03*
X1298754Y83233D03*
X1301219Y89141D03*
X1301000Y62000D03*
X1323500Y68000D03*
X1318341Y60000D03*
X1321841Y63000D03*
X1304000Y62000D03*
X1308983Y93814D03*
X1304500Y40066D03*
X1324127Y50827D03*
X1327452Y55544D03*
X1327500Y51547D03*
X1310600Y41500D03*
X1308100D03*
X1323400Y41439D03*
X1326000D03*
X1326058Y43956D03*
X1323400Y43839D03*
X1318341Y63000D03*
X1341400Y46100D03*
X1309700Y83300D03*
X1317195Y87098D03*
X1311559Y91431D03*
X1311551Y93952D03*
X1304685Y78827D03*
X1336850Y76450D03*
X1317300Y89600D03*
X1330300Y83500D03*
X1336900Y89896D03*
X1323500Y75000D03*
Y71500D03*
X1308400Y79600D03*
X1317300Y84600D03*
X1327500Y68000D03*
X1327467Y70786D03*
X1327500Y65300D03*
X1323000Y83000D03*
X1335120Y94450D03*
X1337400Y72000D03*
X1328500Y92500D03*
X1336900Y61600D03*
X1325100Y145000D03*
X1327900Y142918D03*
X1310175Y154696D03*
X1286116Y118932D03*
Y115932D03*
X1295581Y97320D03*
X1293700Y121800D03*
X1288381Y97320D03*
X1291381D03*
X1295240Y149830D03*
X1295172Y153670D03*
X1291735Y150061D03*
X1291772Y153694D03*
X1293335Y148177D03*
X1293543Y151756D03*
X1287790Y156575D03*
X1295700Y144450D03*
X1286000Y134500D03*
Y139500D03*
Y137000D03*
X1298400Y144500D03*
X1288500Y137000D03*
Y139500D03*
Y134500D03*
X1286000Y132000D03*
X1288500D03*
X1308972Y96742D03*
X1338500Y96000D03*
X1302526Y119102D03*
X1302504Y116700D03*
Y111700D03*
Y114300D03*
X1325125Y100001D03*
X1322628Y100134D03*
X1323800Y104250D03*
X1326800D03*
Y107250D03*
X1323800D03*
X1326600Y123450D03*
X1323600D03*
X1326600Y126450D03*
X1323600D03*
X1340100Y145000D03*
X1301770Y101300D03*
X1310098Y150040D03*
X1335100Y155000D03*
Y145000D03*
X1330100Y150000D03*
X1340100D03*
Y155000D03*
X1315100Y145000D03*
X1335100Y150000D03*
X1330100Y145000D03*
Y155000D03*
X1323026Y133323D03*
X1326026D03*
X1306900Y131744D03*
X1301900Y124400D03*
X1320500Y145000D03*
X1315180Y169950D03*
X1315130Y164870D03*
X1295500Y159970D03*
X1299907Y159808D03*
X1330100Y165000D03*
Y170000D03*
X1340100Y165000D03*
Y170000D03*
X1335100D03*
Y165000D03*
X1320100D03*
X1325100D03*
X1320100Y170000D03*
X1325100D03*
X1310061Y165235D03*
X1305171Y164767D03*
X1330100Y160000D03*
X1340100D03*
X1306363Y169928D03*
X1335100Y160000D03*
X1323030Y216531D03*
X1329324Y208951D03*
X1338224Y209051D03*
X1334724D03*
X1326474Y216500D03*
X1331824Y209051D03*
X1324938Y209251D03*
X1322500D03*
X1320390Y216824D03*
X1333074Y216500D03*
X1336074D03*
X1300300Y169900D03*
X1303838Y169922D03*
X1330074Y216500D03*
X1281799Y193190D03*
X1283720Y223870D03*
X1288800Y233900D03*
X1300444Y267919D03*
X1336900Y232118D03*
X1325900D03*
X1314900D03*
X1342400D03*
X1331400D03*
X1320400D03*
X1309462Y240229D03*
X1320400Y234959D03*
X1325900D03*
X1314900D03*
X1336900D03*
X1331400D03*
X1342400D03*
X1334113Y273115D03*
X1340866Y268795D03*
X1327625Y275971D03*
X1330039Y279618D03*
X1308200Y255800D03*
X1310950Y255650D03*
X1315100Y237645D03*
X1325900Y237900D03*
X1342400D03*
X1331400D03*
X1320289Y237671D03*
X1323734Y279663D03*
X1330171Y276035D03*
X1336448Y271755D03*
X1340248D03*
X1333680Y276035D03*
X1327243Y279663D03*
X1336900Y237900D03*
X1306585Y258250D03*
X1319310Y300795D03*
X1299700Y298557D03*
X1299735Y301298D03*
X1336480Y309755D03*
X1336793Y303784D03*
X1342500Y312100D03*
X1316300Y282000D03*
X1325300Y282600D03*
X1314792Y286427D03*
X1314490Y283862D03*
X1335400Y284900D03*
X1334400Y292050D03*
X1337200Y292012D03*
X1336240Y301243D03*
X1341740D03*
X1323688Y290205D03*
X1303866Y292345D03*
X1305558Y294313D03*
X1306290Y298255D03*
X1303380Y309441D03*
X1302768Y296942D03*
X1319297Y296878D03*
X1321600Y294700D03*
X1338700Y284700D03*
X1305873Y309245D03*
X1305950Y306611D03*
X1341920Y309755D03*
X1342480Y303852D03*
X1302203Y314439D03*
X1331720Y334810D03*
X1326300Y341309D03*
X1320900Y321300D03*
X1323750Y319750D03*
X1331650Y317250D03*
X1319906Y338025D03*
X1338500Y319600D03*
X1318751Y282730D03*
X1322260D03*
X1336240Y306760D03*
X1341740D03*
X1319888Y290205D03*
X1341375Y314675D03*
Y319675D03*
X1308887Y285015D03*
X1316600Y305500D03*
X1336336Y333825D03*
X1326014Y347732D03*
X1342570Y368220D03*
X1330100Y350100D03*
X1332600Y349900D03*
X1315496Y361190D03*
X1332613Y346417D03*
X1329757Y346511D03*
X1341954Y360368D03*
X1335250Y344250D03*
X1331770Y399490D03*
X1332650Y374450D03*
X1317788Y402562D03*
Y400062D03*
X1331856Y401995D03*
X1329064Y399556D03*
X1329288Y402062D03*
X1330200Y377300D03*
X1330758Y389785D03*
Y386785D03*
Y383785D03*
X1324872Y380682D03*
X1322054Y380560D03*
X1324872Y383682D03*
X1327800Y383500D03*
X1325000Y377500D03*
X1327600Y377400D03*
X1319300Y378500D03*
X1327700Y380400D03*
X1322100Y377800D03*
X1323288Y402062D03*
X1323064Y399556D03*
X1320423Y399579D03*
X1320288Y402062D03*
X1326288D03*
X1326064Y399556D03*
X1332600Y377200D03*
X1332748Y380503D03*
X1330190Y380406D03*
X1336886Y351113D03*
X1339597Y349756D03*
X1335100Y427500D03*
X1329419Y464337D03*
X1323815Y463543D03*
X1318054Y460507D03*
X1285769Y440062D03*
X1341528Y463528D03*
X1321172Y464474D03*
X1288671Y445338D03*
X1326626Y464400D03*
X1296468Y437500D03*
X1300100Y442500D03*
X1301000Y460900D03*
X1300438Y433001D03*
X1300315Y427902D03*
X1305100Y432500D03*
X1320100Y427500D03*
Y432500D03*
X1325100Y427500D03*
Y432500D03*
X1305181Y427834D03*
X1310100Y427500D03*
Y432500D03*
X1315100Y427500D03*
Y432500D03*
X1340100Y427500D03*
X1330100Y432500D03*
Y427500D03*
X1340100Y432500D03*
X1335100D03*
X1319320Y418900D03*
X1334889Y421400D03*
X1332236Y419004D03*
X1329400Y404524D03*
X1329736Y419004D03*
X1329889Y421400D03*
X1332389D03*
X1331973Y404580D03*
X1322370Y421400D03*
X1324889Y421470D03*
X1320400Y404524D03*
X1326400D03*
X1323400D03*
X1324736Y419074D03*
X1322217Y419004D03*
X1327236Y419030D03*
X1327389Y421426D03*
X1334967Y419001D03*
X1325100Y457500D03*
Y452500D03*
X1320100Y457500D03*
Y452500D03*
X1315100D03*
X1310100D03*
X1315100Y457500D03*
X1305100D03*
Y452500D03*
X1310100Y457500D03*
X1330100D03*
Y452500D03*
X1335100Y457500D03*
Y452500D03*
Y447500D03*
Y442500D03*
X1330100D03*
X1305100D03*
X1310100D03*
X1320100D03*
X1315100D03*
X1325100D03*
X1340100Y457500D03*
Y452500D03*
Y447500D03*
Y442500D03*
X1304200Y462030D03*
X1316820Y421400D03*
Y418900D03*
X1286831Y443058D03*
X1337100Y499300D03*
X1319738Y477497D03*
X1322360Y472592D03*
X1322260Y477492D03*
X1326877Y469279D03*
X1319699Y472327D03*
X1297878Y493150D03*
X1295240Y493359D03*
X1290500Y480200D03*
Y482700D03*
X1299450Y484950D03*
X1295960Y519450D03*
Y516450D03*
Y513450D03*
X1295880Y510810D03*
X1298460Y513450D03*
Y516450D03*
Y519450D03*
X1298380Y510810D03*
X1301000Y466500D03*
X1301240Y476228D03*
X1304200Y466600D03*
X1320300Y498300D03*
X1335100Y507700D03*
X1332500Y509100D03*
X1339600Y515800D03*
X1341050Y498275D03*
X1334300Y499300D03*
X1340986Y511187D03*
X1313700Y515200D03*
Y517800D03*
X1309870Y499254D03*
X1319300Y525450D03*
X1321800D03*
X1311772Y501000D03*
X1319075D03*
X1316675Y500983D03*
X1314272Y501000D03*
X1329419Y469337D03*
X1287770Y501897D03*
X1339900Y518900D03*
X1332600Y506300D03*
X1308500Y540784D03*
X1305500Y542500D03*
X1295660Y527700D03*
X1298460Y536700D03*
Y530700D03*
Y533700D03*
Y527700D03*
X1295660Y536700D03*
Y530700D03*
Y533700D03*
X1285400Y561000D03*
X1282600Y581000D03*
Y583600D03*
X1295090Y579360D03*
X1293290Y581160D03*
X1290900Y563300D03*
X1288100Y562000D03*
X1300000Y552400D03*
Y558400D03*
Y555400D03*
X1343100Y566300D03*
X1340700D03*
X1338000D03*
X1340526Y563337D03*
X1343026D03*
X1338026D03*
X1333026D03*
X1335526D03*
Y566237D03*
X1318500Y539900D03*
X1327956Y545655D03*
X1317500Y552400D03*
X1320500D03*
X1323500D03*
X1324707Y545493D03*
X1316100Y543400D03*
X1321800Y532750D03*
X1319300Y532650D03*
X1321800Y527850D03*
X1319300D03*
Y530250D03*
X1321800D03*
X1317500Y555400D03*
X1320500D03*
X1323500D03*
X1303000Y576000D03*
Y579000D03*
Y571400D03*
Y568900D03*
Y565900D03*
Y563400D03*
X1306000Y579000D03*
X1323774Y563145D03*
Y566145D03*
X1309000Y565900D03*
Y563400D03*
Y571400D03*
X1306000Y568900D03*
X1309000D03*
X1306000Y576000D03*
X1324000Y568900D03*
X1306000Y571400D03*
X1321000D03*
X1324000D03*
X1321000Y568900D03*
X1318000D03*
X1312000D03*
X1318000Y571400D03*
X1315000D03*
Y568900D03*
X1312000Y571400D03*
X1320500Y558400D03*
X1317500D03*
X1312000Y563400D03*
Y565900D03*
X1315000Y563400D03*
Y565900D03*
X1323500Y558400D03*
X1318000Y563400D03*
Y565900D03*
X1321000Y563400D03*
Y565900D03*
X1306000D03*
Y563400D03*
X1333026Y566237D03*
X1292190Y576952D03*
X1290292Y578962D03*
X1298100Y598300D03*
Y595800D03*
Y590000D03*
Y592500D03*
X1296295Y615596D03*
X1311876Y619501D03*
X1314476D03*
X1307600Y620100D03*
X1301384Y618119D03*
X1306600Y610000D03*
X1306556Y607558D03*
X1324200Y610100D03*
Y600100D03*
Y597600D03*
X1321100Y598500D03*
Y601000D03*
X1315100Y598500D03*
Y601000D03*
X1312100Y598500D03*
X1309100D03*
Y601000D03*
X1312100D03*
X1318100Y598500D03*
Y601000D03*
X1324200Y602700D03*
Y605100D03*
Y607500D03*
X1402600Y10000D03*
X1400100D03*
X1357400Y-19800D03*
X1360400Y10600D03*
X1350654Y-18411D03*
X1348154Y-15911D03*
Y-18411D03*
X1357600Y5140D03*
X1345518Y-18476D03*
X1353154Y-18411D03*
X1376094Y4406D03*
X1380008Y-3805D03*
X1366789Y5776D03*
X1375676Y7630D03*
X1385608Y-17485D03*
X1388294Y-5675D03*
X1389523Y4966D03*
X1380678Y-422D03*
X1380300Y2944D03*
X1374100Y-16900D03*
X1376719Y-16802D03*
X1382151Y-5545D03*
X1369389Y5776D03*
X1380950Y30232D03*
X1376842Y15185D03*
X1374431Y15170D03*
X1381642Y25898D03*
X1400616Y13795D03*
X1379200Y27000D03*
X1355950Y-16507D03*
X1359450Y-7D03*
X1355950D03*
X1357489Y-1924D03*
X1359450Y2493D03*
X1355950D03*
X1357489Y-14424D03*
Y-10524D03*
Y-6124D03*
X1355889Y-8524D03*
X1355847Y-12275D03*
X1355989Y-3924D03*
X1356261Y32017D03*
X1356300Y20100D03*
X1356376Y24167D03*
X1356200Y28200D03*
X1357900Y30200D03*
X1357800Y26100D03*
X1357803Y22200D03*
X1356261Y15517D03*
X1357700Y17800D03*
X1359761Y32317D03*
X1371650Y-907D03*
X1371589Y-3424D03*
Y-5924D03*
X1371900Y28600D03*
X1371598Y-11633D03*
X1371632Y-9191D03*
X1371653Y-16654D03*
X1371605Y-14069D03*
X1371941Y22617D03*
X1371950Y20200D03*
X1371900Y17800D03*
Y15400D03*
Y26100D03*
Y31100D03*
X1380219Y5581D03*
X1379025Y-9799D03*
X1369408Y50479D03*
X1351908Y40402D03*
X1362448Y43413D03*
X1375412Y92182D03*
X1378464Y91979D03*
X1371500Y63200D03*
X1375500Y76000D03*
X1397500Y51000D03*
X1365855Y46972D03*
X1359800Y37300D03*
X1357300D03*
X1361634Y95519D03*
X1347000Y87500D03*
X1343500D03*
X1360700Y86550D03*
X1351500Y83000D03*
X1344000D03*
X1402700Y51100D03*
X1381817Y46484D03*
X1388627Y35032D03*
X1380500Y54500D03*
X1380900Y59820D03*
X1372400Y37785D03*
X1376989Y46971D03*
X1397550Y68059D03*
X1395050D03*
X1397050Y58559D03*
X1392050D03*
X1394550D03*
X1397050Y55559D03*
X1394550D03*
X1392050D03*
X1397539Y65098D03*
X1394939D03*
X1392339D03*
X1369700Y37800D03*
X1377009Y39753D03*
X1367100Y37800D03*
X1389138Y58499D03*
X1395000Y78800D03*
X1397400D03*
X1392584Y78798D03*
X1395000Y76200D03*
X1392584D03*
X1397400D03*
X1367700Y86450D03*
X1403746Y91680D03*
X1370100Y82500D03*
X1366100D03*
X1364700Y86550D03*
X1389068Y78556D03*
X1389100Y74600D03*
X1359500Y83000D03*
X1355500D03*
X1350830Y60730D03*
X1356261Y34517D03*
X1356950Y54370D03*
X1356760Y66660D03*
X1357000Y60500D03*
X1359761Y34817D03*
X1350800Y66600D03*
X1351190Y54710D03*
X1363170Y54280D03*
X1362900Y60500D03*
X1363040Y66660D03*
X1362674Y46058D03*
X1348945Y40264D03*
X1370975Y67225D03*
X1343260Y53770D03*
X1351488Y74000D03*
X1358500Y74500D03*
X1347500Y83000D03*
X1357000Y86640D03*
X1383171Y57549D03*
X1379110Y45033D03*
X1392149Y68006D03*
X1371910Y48800D03*
X1370849Y59349D03*
X1380500Y50500D03*
X1372300Y86400D03*
X1363500Y77400D03*
X1403264Y82000D03*
X1356230Y126500D03*
X1359230D03*
X1360730Y129000D03*
X1362230Y126500D03*
X1355100Y155000D03*
Y145000D03*
Y150000D03*
X1360100Y155000D03*
Y145000D03*
Y150000D03*
X1345000Y104500D03*
X1361634Y97919D03*
X1345100Y150000D03*
X1350100Y155000D03*
Y150000D03*
Y145000D03*
X1345100D03*
Y155000D03*
X1404200Y119200D03*
X1398600Y116500D03*
X1371500Y101000D03*
X1374808Y99366D03*
X1388100Y108500D03*
X1377308Y106866D03*
Y104366D03*
Y101866D03*
X1374808Y106866D03*
Y104366D03*
Y101866D03*
X1381359Y108496D03*
X1384600Y108500D03*
X1394298Y108548D03*
X1394310Y111506D03*
X1391359Y108496D03*
X1400300Y121500D03*
X1396780Y119080D03*
X1401200Y124300D03*
X1399400Y126400D03*
X1394700Y122950D03*
X1391700D03*
Y125950D03*
X1394700D03*
Y128950D03*
X1391700D03*
X1397994Y103350D03*
X1397952Y105998D03*
X1395326Y100913D03*
Y103413D03*
X1395347Y106040D03*
X1386700Y125450D03*
Y128450D03*
X1383700Y125450D03*
Y128450D03*
X1380700Y125450D03*
Y128450D03*
X1376100Y116100D03*
X1376669Y121763D03*
Y118763D03*
X1376100Y124950D03*
X1373850Y114450D03*
X1369730Y129000D03*
X1363730D03*
X1366730D03*
X1373850Y117450D03*
X1368230Y126500D03*
X1373850Y123450D03*
X1365230Y126500D03*
X1397193Y112602D03*
X1394253Y116989D03*
X1401300Y149600D03*
X1385100Y155000D03*
X1375100D03*
X1365100D03*
X1380100D03*
Y145000D03*
X1385100D03*
X1380100Y150000D03*
X1385100D03*
X1365100Y145000D03*
Y150000D03*
X1375100D03*
X1370100Y155000D03*
Y145000D03*
X1375100D03*
X1370100Y150000D03*
X1402500Y116300D03*
X1352200Y104950D03*
Y108400D03*
X1357700D03*
Y104950D03*
X1345257Y100000D03*
X1348615Y96239D03*
X1353500Y96959D03*
X1345500Y107529D03*
X1364700Y96440D03*
X1373850Y120450D03*
X1380100Y165000D03*
Y160000D03*
X1350100Y170000D03*
X1360100Y160000D03*
X1355100D03*
Y170000D03*
X1360100D03*
X1355100Y165000D03*
X1360100D03*
X1345100D03*
X1350100D03*
X1345100Y170000D03*
Y160000D03*
X1350100D03*
X1344462Y209272D03*
X1365100Y170000D03*
Y165000D03*
X1370100D03*
X1375100Y170000D03*
X1370100D03*
X1375100Y165000D03*
X1380100Y170000D03*
X1402020Y165561D03*
X1399100Y166900D03*
X1390100Y160000D03*
X1370100D03*
X1390100Y170000D03*
X1385100Y160000D03*
Y165000D03*
Y170000D03*
X1365100Y160000D03*
X1375100D03*
X1390100Y165000D03*
X1403400Y204766D03*
X1384671Y214832D03*
X1367789Y209216D03*
X1396933Y215763D03*
X1359500Y209200D03*
X1356926Y209100D03*
X1362000Y209300D03*
X1402870Y207918D03*
X1353569Y208960D03*
X1348569D03*
X1397211Y226041D03*
X1402400Y223600D03*
X1399852Y252353D03*
X1383753Y265548D03*
X1397400Y234959D03*
X1391900D03*
X1386400D03*
X1399978Y233775D03*
X1400066Y236274D03*
X1398600Y228700D03*
X1401565Y229435D03*
X1399600Y223600D03*
X1358900Y232118D03*
X1347900D03*
X1353400D03*
X1358900Y234959D03*
X1353400D03*
X1347900D03*
X1349500Y265500D03*
X1359100Y265600D03*
X1345050Y272350D03*
X1380900Y232118D03*
X1369900D03*
X1397400D03*
X1386400D03*
X1375400D03*
X1364400D03*
X1388518Y230789D03*
X1380900Y234959D03*
X1369900D03*
X1364400D03*
X1375400Y235100D03*
X1369100Y265500D03*
X1374864Y265629D03*
X1397400Y237900D03*
X1375400D03*
X1364400D03*
X1353400D03*
X1394881Y226997D03*
X1377522Y265600D03*
X1366312Y265525D03*
X1352468Y265695D03*
X1343668Y268095D03*
X1381031Y265600D03*
X1347468Y268095D03*
X1356268Y265695D03*
X1362803Y265525D03*
X1391900Y237900D03*
X1380900D03*
X1369900D03*
X1358900D03*
X1347900D03*
X1391900Y232118D03*
X1386400Y237900D03*
X1347892Y299741D03*
X1369320Y301219D03*
X1358514Y300815D03*
X1392135Y302051D03*
X1380601Y301465D03*
X1364260Y331619D03*
X1388450Y331250D03*
X1392400Y330800D03*
X1398062Y315743D03*
X1403100Y321350D03*
X1383639Y315274D03*
X1389600Y315200D03*
X1384024Y320225D03*
X1386048Y310310D03*
X1386265Y304310D03*
X1389600Y320100D03*
X1397640Y310631D03*
X1397880Y304640D03*
X1392380D03*
X1392340Y310625D03*
X1403260Y310623D03*
X1403300Y304640D03*
X1388208Y341489D03*
X1400400Y335400D03*
X1348080Y309825D03*
X1353142Y309761D03*
X1358792Y309760D03*
X1358800Y303700D03*
X1353359Y303767D03*
X1353672Y299605D03*
X1345700Y285300D03*
X1348190Y303810D03*
X1355300Y321675D03*
X1359200Y322200D03*
X1346550Y322350D03*
X1350650Y315050D03*
X1357452Y319395D03*
X1369540Y310125D03*
X1374900Y310130D03*
X1397635Y302051D03*
X1386101Y301465D03*
X1374820Y301219D03*
X1364014Y300815D03*
X1368200Y284000D03*
X1365246Y285931D03*
X1381100Y304360D03*
X1380910Y310300D03*
X1364044Y309691D03*
X1364213Y303694D03*
X1375040Y304135D03*
X1369540D03*
X1371000Y322400D03*
X1363059Y314514D03*
X1368947Y313993D03*
X1355800Y285000D03*
X1352400D03*
X1359000Y284900D03*
X1367200Y321600D03*
X1363700D03*
X1400558Y316357D03*
X1404286Y281729D03*
X1403037Y307630D03*
X1360294Y315025D03*
X1371090Y315395D03*
X1380904Y315947D03*
X1392226Y315658D03*
X1349134Y321145D03*
X1402092Y284022D03*
X1398347Y284023D03*
X1398926Y281582D03*
X1392135Y307630D03*
X1380548Y307310D03*
X1369340Y307130D03*
X1358544Y306690D03*
X1347642Y306760D03*
X1397635Y307630D03*
X1386048Y307310D03*
X1374840Y307130D03*
X1364044Y306690D03*
X1353142Y306760D03*
X1392226Y319458D03*
X1349134Y317436D03*
X1400558Y320157D03*
X1380904Y319747D03*
X1371090Y319195D03*
X1360294Y318825D03*
X1396470Y330014D03*
X1381431Y284259D03*
X1358500Y338400D03*
X1370200D03*
X1364300Y338300D03*
X1403037Y302046D03*
X1392144Y364617D03*
X1389450Y372250D03*
X1384700Y359700D03*
X1392500Y344600D03*
X1392805Y360466D03*
X1388500Y350864D03*
X1391200Y386300D03*
X1384531Y382957D03*
X1394760Y394720D03*
X1394370Y384230D03*
X1394260Y351170D03*
X1389500Y360500D03*
X1388300Y346200D03*
X1384300Y398900D03*
X1386800D03*
X1384252Y401343D03*
X1386752D03*
X1380900Y383164D03*
X1371600Y368700D03*
X1362510Y360717D03*
X1354024Y398985D03*
X1352338Y404153D03*
X1351379Y399227D03*
X1352239Y401593D03*
X1359600Y360800D03*
X1356466Y360680D03*
X1344731Y359567D03*
X1358512Y371792D03*
X1360450Y402100D03*
X1359360Y398810D03*
X1357880Y403760D03*
X1356560Y398910D03*
X1362250Y399160D03*
X1354681Y401444D03*
X1354982Y404154D03*
X1357542Y401381D03*
X1378200Y346900D03*
X1374344Y371431D03*
X1380200Y370400D03*
X1376979Y370536D03*
X1364856Y366666D03*
X1382017Y367584D03*
X1380800Y392300D03*
X1372007Y396668D03*
X1380200Y373100D03*
X1377103Y373428D03*
X1374300Y402053D03*
X1376800D03*
X1381752Y401343D03*
X1379252D03*
X1381800Y398900D03*
X1378207Y394568D03*
X1369407Y396668D03*
X1363250Y401700D03*
X1371200Y402100D03*
X1381500Y396200D03*
X1375201Y396303D03*
X1365731Y360698D03*
X1358500Y374500D03*
X1360200Y377400D03*
X1358655Y379352D03*
X1362068Y393385D03*
X1360300Y381100D03*
X1360200Y384700D03*
Y389000D03*
X1358700Y386700D03*
X1358568Y390885D03*
Y393385D03*
X1358600Y382800D03*
X1362068Y390885D03*
X1374300Y377885D03*
Y381485D03*
X1374268Y374285D03*
Y389985D03*
X1374207Y384968D03*
Y387468D03*
X1391845Y348325D03*
X1383700Y392300D03*
X1388900Y387800D03*
X1380872Y378098D03*
X1370300Y350200D03*
X1358300Y344200D03*
X1358400Y350100D03*
X1370200Y343900D03*
X1364100Y350200D03*
X1390100Y432500D03*
X1377028Y458125D03*
X1375100Y447500D03*
X1390100Y452500D03*
X1372028Y458125D03*
X1395375Y453561D03*
X1385100Y427500D03*
Y442500D03*
Y437500D03*
X1385416Y410502D03*
X1404558Y416575D03*
X1402725Y408136D03*
X1402520Y413246D03*
X1388085Y410479D03*
X1403998Y429775D03*
X1404558Y421575D03*
X1398275Y453561D03*
X1397975Y457561D03*
X1403998Y434775D03*
X1395725Y417193D03*
X1393900Y415000D03*
X1396900D03*
Y412500D03*
X1393900D03*
X1385100Y452500D03*
Y447500D03*
X1389900Y427400D03*
X1385100Y432500D03*
X1395100Y427500D03*
Y432500D03*
X1389900Y447400D03*
X1344090Y463630D03*
X1346739Y463615D03*
X1382849Y410471D03*
X1380449Y410479D03*
X1358990Y411040D03*
X1358910Y408480D03*
X1358980Y406060D03*
X1355100Y427500D03*
Y432500D03*
X1361558Y410527D03*
X1349800Y458200D03*
X1350100Y447500D03*
Y452500D03*
X1360100Y447500D03*
Y452500D03*
Y457500D03*
X1345100Y442500D03*
X1350100D03*
X1345100Y437500D03*
X1350100D03*
X1355100D03*
Y442500D03*
X1362560Y463478D03*
X1369034Y458075D03*
X1365100Y432500D03*
Y427500D03*
X1369907Y410513D03*
X1372535Y410512D03*
X1375239Y410590D03*
X1377928Y410451D03*
X1366984Y410481D03*
X1364403Y410496D03*
X1370100Y447500D03*
X1365100Y437500D03*
X1380100Y442500D03*
Y437500D03*
X1370100D03*
X1375100D03*
Y452500D03*
X1370100D03*
X1380100Y447500D03*
X1370100Y442500D03*
X1365100Y452500D03*
X1379857Y458108D03*
X1365100Y442500D03*
X1375100D03*
X1380100Y452500D03*
X1365100Y447500D03*
X1402775Y453561D03*
X1395375Y457561D03*
X1390100Y457500D03*
X1395100Y447500D03*
X1401398Y429775D03*
Y434775D03*
X1402775Y457561D03*
X1388900Y525230D03*
X1395581Y525357D03*
X1383600Y482504D03*
X1386041Y493723D03*
X1383519Y487445D03*
X1390330Y516690D03*
X1385033Y516848D03*
X1387568Y516892D03*
X1388865Y519788D03*
X1388850Y522266D03*
X1386033Y498811D03*
X1403027Y520231D03*
X1402950Y510650D03*
X1400445Y510159D03*
X1395242Y520301D03*
X1383859Y519931D03*
X1386359D03*
X1396035Y514863D03*
X1386241Y487323D03*
Y482623D03*
X1388719Y498745D03*
X1383263Y493673D03*
X1347546Y476897D03*
X1350500Y475100D03*
X1354462Y474141D03*
X1347196Y472941D03*
X1355800Y508500D03*
X1344761Y498282D03*
X1344073Y508263D03*
X1363800Y481600D03*
X1363662Y486636D03*
X1365741Y492723D03*
X1382578Y516805D03*
X1377492Y516892D03*
X1369757Y517465D03*
X1365719Y497545D03*
X1373345Y519940D03*
X1381095D03*
X1376109Y519931D03*
X1378609D03*
X1368441Y497523D03*
X1366309Y486618D03*
X1366341Y481823D03*
X1360741Y486523D03*
X1381041Y482575D03*
X1362841Y492823D03*
X1380741Y487489D03*
X1352490Y515470D03*
X1346870Y515450D03*
X1352590Y519170D03*
X1346970Y519150D03*
X1388741Y493623D03*
X1383241Y498595D03*
X1368441Y492723D03*
X1362880Y497556D03*
X1360863Y481673D03*
X1347081Y507919D03*
X1396158Y537595D03*
X1401777Y557632D03*
X1385033Y544267D03*
X1390623Y574986D03*
X1400830Y564090D03*
X1400288Y570099D03*
X1404420Y576330D03*
X1400980Y587086D03*
X1397980D03*
X1399721Y537509D03*
X1386800Y535600D03*
Y541500D03*
Y538500D03*
X1384310Y538540D03*
Y535540D03*
Y541540D03*
X1385316Y574705D03*
X1387986Y574960D03*
X1390595Y549328D03*
X1387907Y544286D03*
X1404519Y560280D03*
Y557380D03*
X1361600Y559400D03*
X1358529Y537492D03*
X1361163Y540052D03*
X1358518Y540073D03*
X1356018D03*
X1356029Y537492D03*
X1363674Y537471D03*
X1355548Y559959D03*
X1361926Y584037D03*
Y586537D03*
X1359100Y586200D03*
X1357400Y588400D03*
X1360100D03*
X1344613Y556376D03*
Y561376D03*
Y558876D03*
X1347700Y554100D03*
X1353520Y537480D03*
X1344613Y553876D03*
X1361174Y537471D03*
X1358439Y559959D03*
X1375479Y540117D03*
X1375500Y537717D03*
X1366265Y537437D03*
X1363663Y540052D03*
X1363568Y550589D03*
X1380521Y535276D03*
X1378021D03*
X1375621Y535254D03*
X1371265Y537437D03*
X1368765D03*
X1366459Y550589D03*
X1377979Y537717D03*
Y540117D03*
X1380479Y537717D03*
X1368596Y539889D03*
X1371096D03*
X1366096D03*
X1380479Y540117D03*
X1382331Y543818D03*
X1382032Y560143D03*
X1376070Y559760D03*
X1382200Y562700D03*
X1379000Y561500D03*
X1373700Y584656D03*
X1379053Y581864D03*
X1371100Y584656D03*
X1376800Y584328D03*
X1364426Y586637D03*
Y584137D03*
X1382500Y575400D03*
Y579100D03*
X1365028Y547954D03*
X1362528D03*
X1360500Y570900D03*
Y574700D03*
X1360261Y578873D03*
X1360247Y567390D03*
X1360261Y562373D03*
Y581373D03*
X1362000Y576700D03*
Y572800D03*
X1362100Y569100D03*
X1362000Y565600D03*
X1375961Y569473D03*
X1376000Y565700D03*
X1375961Y562273D03*
X1363761Y581373D03*
X1375961Y577973D03*
X1376000Y575456D03*
Y572956D03*
X1390500Y539000D03*
X1383074Y581963D03*
X1390462Y541800D03*
X1400216Y560128D03*
X1387050Y615350D03*
X1392500Y592000D03*
X1384744Y605689D03*
X1385000Y602700D03*
X1386921Y620689D03*
X1390851D03*
X1400980Y589586D03*
X1395060Y590630D03*
X1373838Y616161D03*
X1380890Y615820D03*
X1371100Y615756D03*
X1376556D03*
X1357726Y591037D03*
X1360226D03*
X1382586Y609602D03*
X1382605Y612102D03*
X1375600Y589700D03*
X1382100Y592800D03*
X1382000Y589500D03*
X1382200Y606300D03*
X1363761Y612573D03*
X1360261D03*
X1360200Y597800D03*
X1361600Y599900D03*
X1361500Y595700D03*
X1360100Y610100D03*
X1360200Y606300D03*
Y602000D03*
X1361900Y608200D03*
X1361500Y604200D03*
X1360261Y593573D03*
X1375961Y600673D03*
X1375861Y597073D03*
X1375961Y593473D03*
X1363761Y610073D03*
X1375961Y609173D03*
X1375900Y604156D03*
Y606656D03*
X1398010Y590040D03*
X1405100Y10000D03*
X1413721Y13139D03*
X1416871D03*
X1454991Y5589D03*
X1454715Y2784D03*
X1450508Y2756D03*
X1410600Y9100D03*
X1410571Y13170D03*
X1420019Y13466D03*
X1448367Y13533D03*
X1438918D03*
X1429469Y13466D03*
X1457814D03*
X1436131Y5248D03*
X1432661Y5220D03*
X1449991Y5589D03*
X1436025Y7756D03*
X1427442Y11563D03*
X1431025Y7756D03*
X1422442Y11563D03*
X1465237D03*
X1460237D03*
X1446340D03*
X1441340D03*
X1407422Y13139D03*
X1420337Y45477D03*
X1416837D03*
X1411546Y43116D03*
X1406546D03*
X1406674Y46120D03*
X1411254Y46018D03*
X1412250Y65359D03*
X1407150Y58859D03*
X1410150D03*
X1407150Y52859D03*
X1410150D03*
X1409250Y65359D03*
X1407150Y55859D03*
X1410150D03*
X1413721Y36749D03*
X1412250Y68359D03*
X1409250D03*
X1407964Y79700D03*
X1407960Y93800D03*
X1407300Y77300D03*
X1410200Y77400D03*
X1405149Y93679D03*
X1406746Y91680D03*
X1406264Y82000D03*
X1409264D03*
X1404964Y79700D03*
X1409150Y71259D03*
X1412150D03*
X1425081Y48412D03*
X1442067Y34830D03*
X1423170Y36635D03*
X1432619Y34830D03*
X1451516D03*
X1460965D03*
X1453809Y94639D03*
X1453700Y83750D03*
X1455889Y73700D03*
X1453221Y73750D03*
X1455347Y92065D03*
X1457000Y82000D03*
X1450973Y112225D03*
X1452648Y103788D03*
X1451198Y143761D03*
X1451590Y138750D03*
X1451021Y151626D03*
X1438348Y155908D03*
X1451228Y141261D03*
X1451233Y146405D03*
X1451273Y148905D03*
X1452232Y109500D03*
X1422196Y218052D03*
X1446331Y197285D03*
X1458569Y192143D03*
X1449847Y202322D03*
X1439000Y208500D03*
X1442251Y180818D03*
X1408247Y206270D03*
X1418300Y199900D03*
X1451386Y173499D03*
X1451366Y165296D03*
X1451365Y170318D03*
Y176014D03*
X1450532Y178372D03*
X1454070Y163360D03*
X1454660Y166200D03*
X1440150Y175550D03*
X1440124Y166180D03*
X1451427Y167818D03*
X1447999Y205645D03*
X1458908Y187699D03*
X1444850Y242730D03*
X1433362Y280744D03*
X1412579Y268273D03*
X1433362Y278244D03*
X1426658Y274252D03*
X1455600Y254826D03*
X1439700Y253100D03*
X1434800Y248900D03*
X1435655Y246550D03*
X1441750Y236800D03*
X1434300Y251600D03*
X1437400Y244150D03*
X1464150Y235550D03*
X1462700Y221700D03*
X1464200Y231400D03*
X1407274Y245652D03*
X1410979Y270473D03*
X1451850Y262200D03*
X1461348Y244350D03*
X1454350Y262200D03*
X1466006Y265300D03*
X1465063Y253544D03*
X1464700Y256100D03*
X1447154Y251710D03*
X1462704Y254470D03*
X1422281Y221479D03*
X1454056Y266169D03*
X1466404Y245350D03*
X1454000Y259700D03*
X1437800Y258300D03*
X1452200Y254500D03*
X1452728Y243306D03*
X1458800Y254882D03*
X1433700Y254200D03*
X1458318Y243000D03*
X1426905Y267045D03*
X1448500Y257700D03*
X1430365Y262624D03*
X1433057Y257388D03*
X1438500Y255400D03*
X1459548Y221731D03*
X1410800Y316100D03*
X1408580Y310632D03*
X1408760Y304637D03*
X1408376Y339882D03*
X1408250Y333000D03*
X1408348Y336436D03*
X1410550Y320800D03*
X1410489Y337988D03*
X1443500Y327900D03*
X1416000Y332900D03*
Y338100D03*
X1444311Y324366D03*
X1419343Y310652D03*
X1416000Y335500D03*
X1419283Y304570D03*
X1413983Y304645D03*
X1413943Y310628D03*
X1419220Y301983D03*
X1408537Y302046D03*
X1419333Y307598D03*
X1413387Y316233D03*
X1405392Y284022D03*
X1413720Y307634D03*
X1408537Y307630D03*
X1413387Y320033D03*
X1413720Y301983D03*
X1464400Y382720D03*
X1448050Y374950D03*
X1464273Y397648D03*
X1463200Y362200D03*
X1463870Y367869D03*
X1453900Y353350D03*
X1463617Y357259D03*
X1413400Y361300D03*
X1456000Y360700D03*
X1463942Y359742D03*
X1464400Y390800D03*
X1450400Y354300D03*
X1460400Y353000D03*
X1459111Y356353D03*
X1447685Y352025D03*
X1453251Y356676D03*
X1461016Y359965D03*
X1417656Y367547D03*
X1420101Y396236D03*
X1418138Y386361D03*
X1415000Y399000D03*
X1412220Y388360D03*
X1417217Y379129D03*
X1417349Y382137D03*
X1417773Y374107D03*
X1464124Y353776D03*
X1465500Y395400D03*
X1456750Y381850D03*
X1459033Y395334D03*
X1446700Y387900D03*
X1437897Y402315D03*
X1443100Y368950D03*
X1464361Y385275D03*
X1415500Y353200D03*
X1445510Y350327D03*
X1415450Y350550D03*
X1456981Y384569D03*
X1445100Y374900D03*
X1452699Y404060D03*
X1439934Y403730D03*
X1444400Y371600D03*
X1465048Y402370D03*
X1420515Y373585D03*
Y368585D03*
X1456900Y387600D03*
X1457300Y373600D03*
X1420075Y378375D03*
Y393402D03*
Y383375D03*
Y388402D03*
X1413735Y396302D03*
Y391302D03*
X1408225Y438233D03*
X1411900Y429775D03*
X1405375Y453561D03*
X1405608Y456761D03*
X1411900Y434775D03*
X1408225Y441000D03*
X1435479Y423107D03*
X1439350Y406900D03*
X1459200Y459800D03*
Y454100D03*
X1459000Y449997D03*
X1451400Y454100D03*
Y459800D03*
X1445000Y437000D03*
X1429000Y437059D03*
X1444800Y442500D03*
X1444500Y448000D03*
X1429100Y453400D03*
X1429000Y448000D03*
Y442600D03*
X1448800Y427800D03*
X1459478Y432851D03*
X1462131D03*
X1458300Y442675D03*
X1412484Y440748D03*
X1412375Y443545D03*
X1412447Y416368D03*
X1412545Y421974D03*
X1413300Y454400D03*
X1413075Y457561D03*
X1448800Y416500D03*
X1464300Y404900D03*
X1439000Y423000D03*
X1464600Y428000D03*
X1459300Y430000D03*
X1464525Y420014D03*
X1464731Y432942D03*
X1445100Y431500D03*
X1459200Y465500D03*
X1451400D03*
X1461800Y454100D03*
X1464200Y449997D03*
X1439813Y409422D03*
X1439651Y412466D03*
X1466382Y406773D03*
X1442830Y406472D03*
X1443252Y409029D03*
X1405423Y413281D03*
X1407158Y421575D03*
X1454000Y459800D03*
X1405423Y408281D03*
X1407158Y416575D03*
X1414982Y417040D03*
X1409300Y429775D03*
X1410475Y457561D03*
X1415146Y421946D03*
X1409300Y434775D03*
X1464400Y465500D03*
X1456600D03*
X1461800Y459800D03*
X1454000Y454100D03*
X1414107Y447267D03*
X1461600Y449997D03*
X1464400Y454100D03*
X1461800Y465500D03*
X1454000D03*
X1410475Y453561D03*
X1456600Y454100D03*
X1464400Y459800D03*
X1456600D03*
X1448000Y431500D03*
X1431900Y453500D03*
X1447500Y448000D03*
X1431900Y442600D03*
X1448000Y437000D03*
X1431900Y448000D03*
X1447700Y442500D03*
X1431900Y437100D03*
X1408753Y527518D03*
X1405950Y510650D03*
X1407884Y512751D03*
X1461713Y515196D03*
X1460661Y484891D03*
X1459213Y515196D03*
X1461267Y489790D03*
X1456602Y485864D03*
X1452188Y487223D03*
X1456590Y488976D03*
X1418241Y489523D03*
X1418441Y482523D03*
X1441842Y482924D03*
X1442041Y494423D03*
X1415541Y489523D03*
X1416100Y483500D03*
X1415800Y477500D03*
Y495200D03*
X1420200Y520500D03*
X1447749Y485395D03*
X1439314Y477723D03*
X1439400Y483600D03*
X1439341Y489323D03*
X1453700Y501600D03*
X1458357Y523271D03*
X1461100Y523600D03*
X1439400Y494700D03*
X1431690Y521530D03*
X1449568Y487276D03*
X1417800Y521500D03*
X1414800Y521400D03*
X1458060Y495020D03*
X1458935Y512470D03*
X1428500Y521000D03*
X1438390Y527175D03*
X1436396Y477691D03*
X1413041Y477423D03*
X1412941Y489523D03*
X1464553Y508872D03*
X1436441Y489323D03*
X1412741Y494223D03*
X1436541Y494423D03*
X1436600Y482900D03*
X1413193Y482532D03*
X1436358Y525142D03*
X1418341Y494423D03*
Y477323D03*
X1442141Y477623D03*
X1442041Y489223D03*
X1409693Y560343D03*
X1412093D03*
X1410850Y564210D03*
X1410340Y570370D03*
X1410486Y529792D03*
X1407019Y557380D03*
X1412019D03*
X1409519D03*
X1406993Y560343D03*
X1447852Y575687D03*
X1445800Y574300D03*
X1445750Y539000D03*
X1461500Y540000D03*
X1439861Y540497D03*
X1461653Y580762D03*
X1461707Y583162D03*
X1461878Y585556D03*
X1441252Y548631D03*
X1422509Y576823D03*
X1419809Y570723D03*
X1422509Y573823D03*
X1419809Y573723D03*
Y576723D03*
X1422509Y570823D03*
X1417252Y573470D03*
X1414743Y573363D03*
X1414851Y576624D03*
X1414744Y570801D03*
X1417182Y570711D03*
X1417288Y576624D03*
X1451150Y569900D03*
Y573200D03*
X1436160Y561200D03*
X1458629Y531604D03*
X1461500Y531500D03*
X1433100Y581770D03*
X1430570Y580890D03*
X1432590Y584550D03*
X1427500Y581100D03*
X1441409Y561117D03*
X1447022Y546578D03*
X1449922Y546664D03*
X1425243Y562260D03*
X1418402Y562624D03*
X1465700Y570500D03*
X1441805Y570887D03*
X1443797Y572482D03*
X1422500Y579800D03*
X1414800D03*
X1461930Y587956D03*
X1415173Y586332D03*
X1412673D03*
X1422920Y586250D03*
X1417920D03*
X1420420D03*
X1438799Y542785D03*
X1439123Y545294D03*
X1409500Y538000D03*
X1420500Y549800D03*
X1420400Y538000D03*
X1451533Y527867D03*
X1413600Y531300D03*
X1432560Y561160D03*
X1428791Y535512D03*
X1419600Y531500D03*
X1453533Y532667D03*
X1426870Y530800D03*
X1423800Y534800D03*
X1421560Y563455D03*
X1415582Y562904D03*
X1439822Y537382D03*
X1428281Y546119D03*
X1429026Y541026D03*
X1462039Y590354D03*
X1445145Y605727D03*
X1442525Y597279D03*
X1443654Y594749D03*
X1456277Y603454D03*
X1453628Y603368D03*
X1450720Y606067D03*
X1448071Y605981D03*
X1443473Y599944D03*
X1453451Y606114D03*
X1456100Y606200D03*
X1460200D03*
X1462155Y592761D03*
X1465334Y618564D03*
X1451314Y623298D03*
X1458000Y623400D03*
X1455000D03*
X1461000D03*
X1442200D03*
X1445200D03*
X1448200D03*
X1463419Y606912D03*
X1410950Y589670D03*
X1506300Y-6600D03*
X1498800Y-12676D03*
X1477100Y2400D03*
X1524800Y3500D03*
X1527700Y6963D03*
X1504400Y20300D03*
X1513700Y7082D03*
X1520700Y7100D03*
X1511900Y3500D03*
X1481600Y5300D03*
X1506900Y3500D03*
X1509400D03*
X1522600Y-6500D03*
X1514400Y3500D03*
X1520100D03*
X1469388Y5589D03*
X1469807Y2967D03*
X1474388Y5589D03*
X1473674Y2953D03*
X1476712Y13466D03*
X1467264Y13533D03*
X1485242Y4589D03*
X1496660Y-10252D03*
X1516900Y3500D03*
X1501900Y-9124D03*
X1492900Y4000D03*
X1489600D03*
X1521900Y27500D03*
X1509500Y31900D03*
X1495611Y13466D03*
X1486162Y13500D03*
X1524154Y28918D03*
X1521092Y21665D03*
X1527600Y3500D03*
X1493770Y6909D03*
X1484135Y11563D03*
X1488770Y6909D03*
X1479135Y11563D03*
X1470862Y38209D03*
X1470414Y34830D03*
X1479863D03*
X1497711Y34427D03*
X1489311Y34830D03*
X1490057Y85165D03*
X1490821Y73750D03*
X1524557Y88336D03*
X1520314Y78880D03*
X1517162Y78784D03*
X1519599Y86117D03*
X1491164Y82923D03*
X1519580Y81313D03*
X1499613Y84046D03*
X1515294Y91306D03*
X1523563Y93565D03*
X1511700Y84600D03*
X1499875Y86681D03*
X1526744Y93265D03*
X1513335Y92921D03*
X1499875Y90481D03*
X1524744Y133656D03*
X1513935Y120143D03*
Y108332D03*
X1513013Y96546D03*
X1514600Y126650D03*
X1482455Y124222D03*
X1474717Y110370D03*
X1473096Y120999D03*
X1468755Y128478D03*
X1482300Y118400D03*
X1468590Y131200D03*
X1475200Y142600D03*
X1476761Y152725D03*
X1469747Y148276D03*
X1483093Y130796D03*
X1489053Y103325D03*
X1489780Y105820D03*
X1524284Y112773D03*
X1511800Y127050D03*
X1513879Y113349D03*
X1518514Y130991D03*
X1526513Y120769D03*
Y103958D03*
X1526728Y124168D03*
X1518438Y100926D03*
X1490178Y112315D03*
X1518376Y111499D03*
X1523950Y104050D03*
X1523889Y99033D03*
X1523557Y116165D03*
X1523813Y120546D03*
X1523756Y108762D03*
X1501603Y108500D03*
X1499618Y124520D03*
X1497699Y112140D03*
X1511634Y121195D03*
X1511635Y114535D03*
X1511650Y109400D03*
Y103400D03*
X1511651Y98675D03*
X1500775Y98101D03*
X1501700Y103300D03*
X1513023Y140630D03*
X1511664Y133603D03*
X1488350Y149450D03*
X1523719Y149488D03*
X1488800Y145000D03*
X1502000Y147500D03*
X1492013Y155610D03*
X1495848Y150600D03*
X1496150Y148115D03*
X1511660Y138510D03*
X1513136Y157081D03*
X1515358Y151743D03*
X1513500Y153800D03*
X1500643Y154819D03*
X1496038Y154229D03*
X1503466Y142486D03*
X1510184Y142614D03*
X1505673Y146346D03*
X1490900Y146600D03*
X1500455Y110933D03*
X1496658Y115088D03*
X1472500Y123700D03*
X1473100Y131900D03*
X1473200Y118300D03*
X1514425Y134180D03*
X1524900Y139100D03*
X1484113Y128513D03*
X1500700Y127250D03*
X1498705Y99522D03*
X1483366Y120746D03*
X1493069Y152834D03*
X1473354Y153246D03*
X1485210Y134837D03*
X1513935Y104532D03*
Y116343D03*
X1524000Y123300D03*
X1490674Y98787D03*
X1498810Y108290D03*
X1526813Y108958D03*
X1526513Y115769D03*
X1500455Y114388D03*
X1496726Y120588D03*
X1473100Y128950D03*
X1514425Y137980D03*
X1526310Y142190D03*
X1485755Y131671D03*
X1500806Y133339D03*
X1526744Y98265D03*
X1483366Y115902D03*
X1498660Y102746D03*
X1520150Y127600D03*
X1500703Y158233D03*
X1507524Y218600D03*
X1510800Y193330D03*
X1512500Y199837D03*
X1492136Y199125D03*
X1479000Y207225D03*
X1512700Y205100D03*
X1497237Y217281D03*
X1519243Y191627D03*
X1513900Y218000D03*
X1478611Y209695D03*
X1478089Y182650D03*
X1511100Y186275D03*
X1499800Y199300D03*
X1491196Y218527D03*
X1523400Y217900D03*
X1483523Y181100D03*
X1517328Y186208D03*
X1475401Y210017D03*
X1515060Y192443D03*
X1487716Y218650D03*
X1470382Y188372D03*
X1472758Y216495D03*
X1510638Y166240D03*
X1468700Y163100D03*
X1476761Y157400D03*
X1471388Y173700D03*
X1496713Y174853D03*
X1527500Y167726D03*
X1502192Y164871D03*
X1494783Y177907D03*
X1493200Y162700D03*
X1488300Y161700D03*
X1497493Y162078D03*
X1492469Y179387D03*
X1494939Y159500D03*
X1492500Y176887D03*
X1489088Y176680D03*
X1488900Y172576D03*
X1489015Y179832D03*
X1516616Y205537D03*
X1512525Y208944D03*
X1516598Y203037D03*
X1516872Y208863D03*
X1504706Y164871D03*
X1488300Y158300D03*
X1477388Y172988D03*
X1473888Y173721D03*
X1474883Y182275D03*
X1492597Y172636D03*
X1474439Y207621D03*
X1527657Y278700D03*
X1470950Y252846D03*
X1469004Y246287D03*
X1467040Y260357D03*
X1470556Y256900D03*
X1468450Y252900D03*
X1472200Y243000D03*
X1469150Y242931D03*
X1479500Y238500D03*
X1499559Y231173D03*
X1498022Y221900D03*
X1498685Y224715D03*
X1491700Y241661D03*
X1478500Y252000D03*
X1479000Y254500D03*
X1477397Y256657D03*
X1484000Y257500D03*
X1496812Y273718D03*
X1491265Y226492D03*
X1519300Y245196D03*
X1491438Y221137D03*
X1523580Y237960D03*
X1509814Y247215D03*
X1509800Y244676D03*
X1503842Y245678D03*
X1499070Y255934D03*
X1499472Y250370D03*
X1504772Y259229D03*
X1507003Y272249D03*
X1504461Y274426D03*
X1521962Y278650D03*
X1526150Y234300D03*
X1479700Y224801D03*
X1482004Y222483D03*
X1497082Y277987D03*
X1474096Y256706D03*
X1483457Y244568D03*
X1495682Y255861D03*
X1493199Y255507D03*
X1484700Y251800D03*
X1487500Y244500D03*
X1495696Y258361D03*
X1492697Y267303D03*
X1475004Y246287D03*
X1492753Y273724D03*
X1499681Y279910D03*
X1512790Y240099D03*
X1516549Y234278D03*
X1486926Y247834D03*
X1491407Y258353D03*
X1523470Y242580D03*
X1470950Y229669D03*
X1471604Y246287D03*
X1516613Y240656D03*
X1498478Y233675D03*
X1520413Y239498D03*
X1482400Y248000D03*
X1474520Y251740D03*
X1525650Y248700D03*
X1502165Y251200D03*
X1505946Y254432D03*
X1500840Y319870D03*
X1517115Y330005D03*
X1470276Y330774D03*
X1468399Y324930D03*
X1470257Y321929D03*
X1466970Y320235D03*
X1472500Y341074D03*
X1526722Y295400D03*
X1501583Y339389D03*
X1521817Y330937D03*
X1526000Y341000D03*
X1517600Y320940D03*
X1487426Y330100D03*
X1514050Y327490D03*
X1526936Y307015D03*
X1473231Y320250D03*
X1516138Y310749D03*
X1487858Y340412D03*
X1484100Y330115D03*
X1499829Y341250D03*
X1482550Y333600D03*
X1482585Y340856D03*
X1493240Y325828D03*
X1520766Y341000D03*
X1505000Y340990D03*
X1484620Y339152D03*
X1510851Y340113D03*
X1513796Y330680D03*
X1497997Y338546D03*
X1504370Y330970D03*
X1518060Y317520D03*
X1525677Y311835D03*
X1510584Y330640D03*
X1492540Y328250D03*
X1516301Y313244D03*
X1527537Y330048D03*
X1525051Y329553D03*
X1487904Y337500D03*
X1482386Y336926D03*
X1483506Y326061D03*
X1514100Y321792D03*
X1514067Y315626D03*
X1493290Y287984D03*
X1526900Y292866D03*
X1496900Y293900D03*
X1493268Y293943D03*
X1496600Y281400D03*
X1493700Y281476D03*
X1508650Y287500D03*
X1496628Y288440D03*
X1499987Y288487D03*
X1518006Y286706D03*
X1501550Y293750D03*
X1514722Y293257D03*
X1515482Y280800D03*
X1512300Y280847D03*
X1511900Y287500D03*
X1472450Y337500D03*
X1472500Y334800D03*
X1471562Y325531D03*
X1487000Y333300D03*
X1523935Y318901D03*
X1497179Y306372D03*
X1499723Y300106D03*
X1505923Y309510D03*
X1505935Y306674D03*
X1508455Y313041D03*
X1503538Y318068D03*
X1495810Y341200D03*
X1495445Y338724D03*
X1496400Y336376D03*
X1512182Y293317D03*
X1498600Y334800D03*
X1524575Y387654D03*
X1503878Y364717D03*
X1487525Y384274D03*
X1505075Y394414D03*
X1501175Y387654D03*
X1505075Y401174D03*
X1501175D03*
X1522625Y391034D03*
X1495325Y397794D03*
X1499225D03*
X1493375Y401174D03*
X1489475D03*
X1507025Y384274D03*
X1501175Y380894D03*
X1522625Y397794D03*
X1507025Y377514D03*
X1518725Y384274D03*
X1510925Y397794D03*
X1483868Y390233D03*
X1516775Y394414D03*
X1510925Y377514D03*
X1512875Y380894D03*
X1518725Y377514D03*
X1522625Y384274D03*
X1510925Y391034D03*
X1512875Y387654D03*
X1510925Y384274D03*
X1489475Y380894D03*
X1493375D03*
X1487525Y397794D03*
Y377514D03*
X1498183Y365405D03*
X1505075Y387654D03*
X1499225Y377514D03*
X1473255Y372654D03*
X1507200Y356000D03*
X1502970Y350610D03*
X1520675Y394414D03*
X1470100Y392350D03*
X1472940Y384030D03*
X1467597Y363000D03*
X1470800Y395200D03*
X1469000Y345850D03*
X1472550Y397500D03*
X1470800Y402250D03*
X1472680Y380630D03*
X1473083Y393770D03*
X1489475Y387654D03*
X1514265Y355542D03*
X1495325Y391034D03*
X1493375Y387654D03*
X1495325Y377514D03*
X1524575Y394414D03*
X1520313Y357069D03*
X1520429Y354379D03*
X1525561Y350253D03*
X1498309Y360005D03*
X1511000Y350627D03*
X1481000Y350000D03*
X1478607Y359082D03*
X1498246Y352305D03*
X1478612Y361670D03*
X1498246Y354905D03*
X1507154Y353100D03*
X1524746Y356717D03*
Y354217D03*
X1516775Y380894D03*
X1526659Y397500D03*
X1524575Y380894D03*
X1522476Y361907D03*
X1522625Y377514D03*
X1483172Y351806D03*
X1474500Y365500D03*
X1478500D03*
X1483500D03*
X1482000Y395098D03*
Y399035D03*
Y383287D03*
Y387224D03*
X1473255Y376254D03*
X1528146Y349842D03*
X1519626Y365817D03*
X1488394Y365466D03*
X1497275Y401174D03*
X1508975D03*
X1483950Y401650D03*
X1491425Y391034D03*
X1503125Y377514D03*
X1491425D03*
X1507200Y358700D03*
X1498246Y357505D03*
X1518725Y397794D03*
Y391034D03*
X1512875Y401174D03*
Y394414D03*
X1514925Y358844D03*
X1489838Y350011D03*
X1484600Y394100D03*
X1483740Y359550D03*
X1524746Y359217D03*
X1495325Y384274D03*
X1483664Y362914D03*
X1520675Y401174D03*
X1516775D03*
X1515328Y363389D03*
X1516775Y387654D03*
X1478163Y354940D03*
X1483867Y356753D03*
X1526525Y377514D03*
X1514825D03*
X1526525Y384274D03*
Y391034D03*
X1514825Y384274D03*
X1520675Y387654D03*
Y380894D03*
X1514825Y391034D03*
X1508975Y387654D03*
Y380894D03*
X1503125Y384274D03*
Y391034D03*
X1497275Y380894D03*
X1491425Y384274D03*
X1497275Y387654D03*
Y394414D03*
X1491425Y397794D03*
X1503125D03*
X1508975Y394414D03*
X1514825Y397794D03*
X1524575Y401174D03*
X1507025Y391034D03*
X1489915Y352637D03*
X1498246Y362705D03*
X1501175Y394414D03*
X1499225Y391034D03*
Y384274D03*
X1493375Y394414D03*
X1489475D03*
X1488479Y362967D03*
Y360367D03*
X1496000Y350000D03*
X1488479Y357767D03*
X1466873Y397648D03*
X1469873D03*
X1468048Y402370D03*
X1505075Y380894D03*
X1517367Y349964D03*
X1505075Y463826D03*
X1515500Y448250D03*
X1507025Y404554D03*
X1499225D03*
Y440166D03*
X1522625Y404554D03*
X1491425Y418074D03*
X1487525D03*
X1499225Y446926D03*
Y453686D03*
X1520675Y463826D03*
X1512875D03*
X1508975D03*
X1501175Y421454D03*
X1495325Y418074D03*
X1493375Y443546D03*
X1489475Y414694D03*
X1493375D03*
X1489475Y407934D03*
X1493375D03*
Y421454D03*
X1489475D03*
X1493375Y428214D03*
Y436786D03*
X1499225Y460446D03*
X1489475Y457066D03*
X1487525Y460446D03*
X1472449Y439421D03*
X1467000Y454100D03*
Y459800D03*
X1466800Y449997D03*
X1470262Y420711D03*
X1467355Y432919D03*
X1469931Y432842D03*
X1467401Y411557D03*
X1471900Y406900D03*
X1472530Y432731D03*
X1472400Y428063D03*
X1472800Y420689D03*
X1467000Y465500D03*
X1524575Y463826D03*
X1491425Y411314D03*
X1487525D03*
X1518675Y451425D03*
X1516775Y457066D03*
X1512954Y407653D03*
X1524575Y407624D03*
X1518650Y416750D03*
X1499225Y411314D03*
X1501175Y407934D03*
X1515500Y413600D03*
X1528100Y413700D03*
X1512350Y410450D03*
X1521800Y419900D03*
X1501200Y450600D03*
X1505714Y448145D03*
X1501175Y443546D03*
X1503125Y446926D03*
X1505075Y457066D03*
X1524575D03*
X1524950Y445100D03*
Y448250D03*
X1521800Y445100D03*
X1528147Y454546D03*
X1509200Y410450D03*
X1485250Y408017D03*
X1497200Y421200D03*
X1505715Y441368D03*
X1506059Y429249D03*
X1505459Y421107D03*
X1503128Y419892D03*
X1512350Y423050D03*
X1518650Y426200D03*
Y423050D03*
X1515500Y426200D03*
X1482000Y418720D03*
Y406909D03*
Y410846D03*
Y414783D03*
Y422658D03*
Y426595D03*
X1483400Y438100D03*
X1482603Y442418D03*
X1482000Y462028D03*
X1483115Y454379D03*
X1483200Y450455D03*
X1482500Y434600D03*
X1503125Y404554D03*
X1509200Y413600D03*
X1510925Y404554D03*
X1497275Y414694D03*
X1503125Y424834D03*
X1497275Y428214D03*
X1495325Y424834D03*
X1503125Y433406D03*
X1491425D03*
X1495325D03*
X1524950Y419900D03*
X1518650D03*
X1483818Y430597D03*
X1528100Y410550D03*
X1501219Y416596D03*
X1487525Y404554D03*
X1526525D03*
X1515500Y416750D03*
X1518700Y406500D03*
X1491425Y404554D03*
X1495325Y411314D03*
X1512350Y445100D03*
X1509200D03*
Y454550D03*
X1491425Y446926D03*
X1515500Y423050D03*
X1524950Y426200D03*
Y423050D03*
X1509200Y416750D03*
X1512350D03*
X1505605Y423604D03*
X1509200Y423050D03*
Y419900D03*
X1515500D03*
X1512350D03*
Y426200D03*
X1509200D03*
X1515500Y429350D03*
X1518650D03*
X1509200D03*
X1512350D03*
X1518650Y438800D03*
X1515500D03*
X1512350D03*
X1505392Y437133D03*
X1509200Y438800D03*
Y441950D03*
X1512350D03*
X1515500D03*
X1524950Y438800D03*
X1509200Y435650D03*
X1518650D03*
X1515500D03*
X1512350D03*
X1524950D03*
Y429350D03*
X1505462Y434630D03*
X1505075Y407934D03*
X1524950Y413600D03*
X1497273Y407610D03*
X1512400Y454500D03*
X1503125Y440166D03*
X1501175Y436786D03*
X1495325Y440166D03*
X1497275Y436786D03*
X1510925Y460446D03*
X1505442Y443900D03*
X1507025Y460446D03*
X1503125Y453786D03*
Y460446D03*
X1501175Y457066D03*
X1487525Y453686D03*
X1497275Y457066D03*
Y450306D03*
X1495325Y446926D03*
Y453686D03*
X1497275Y443546D03*
X1501175Y463826D03*
X1493375D03*
X1515500Y445100D03*
X1514825Y460446D03*
X1520675Y457066D03*
X1518725Y460446D03*
X1521800Y441950D03*
Y448250D03*
X1526525Y460446D03*
X1522625D03*
X1524950Y441950D03*
X1485300Y443484D03*
X1483375Y458375D03*
X1525000Y416750D03*
X1516700Y409900D03*
X1518650Y413600D03*
X1501175Y428214D03*
X1499225Y424834D03*
X1516775Y463826D03*
X1487525Y440166D03*
X1491425D03*
X1489475Y443546D03*
X1487500Y424600D03*
X1491400D03*
X1470106Y412152D03*
X1472688Y412055D03*
X1467290Y428013D03*
X1469900D03*
X1469400Y449997D03*
X1472000D03*
X1469382Y406773D03*
X1493375Y450306D03*
X1489475Y428214D03*
Y436786D03*
X1491425Y460446D03*
X1489475Y450306D03*
X1491425Y453686D03*
X1493375Y457066D03*
X1495325Y460446D03*
X1497275Y463826D03*
X1485030Y463690D03*
X1489475Y463826D03*
X1508975Y457066D03*
X1515389Y451400D03*
X1521800D03*
X1518650Y448250D03*
X1467262Y420711D03*
X1487525Y480726D03*
X1520675Y470586D03*
X1510925Y467206D03*
X1507025D03*
X1520675Y477346D03*
X1514825Y467206D03*
X1512875Y470586D03*
X1491425Y480726D03*
X1495325Y473966D03*
X1491425Y487486D03*
X1499225Y467206D03*
X1520675Y484106D03*
X1524575Y477346D03*
X1512875D03*
X1526525Y480726D03*
X1524575Y484106D03*
X1522625Y480726D03*
X1516775Y477346D03*
X1470643Y495299D03*
X1473140Y525407D03*
X1482200Y477800D03*
X1482958Y486118D03*
X1485100Y469900D03*
X1482000Y481713D03*
Y469902D03*
X1476800Y498900D03*
X1482300D03*
X1476800Y507300D03*
X1481700Y524200D03*
X1473800Y495800D03*
X1499225Y480726D03*
X1508975Y477346D03*
X1510925Y480726D03*
X1508975Y470586D03*
X1510925Y473966D03*
X1505075Y470586D03*
X1501175D03*
X1503125Y467206D03*
X1507025Y487486D03*
X1487525Y473966D03*
X1491425D03*
X1489475Y470586D03*
X1490100Y489700D03*
X1487525Y487486D03*
X1489475Y484106D03*
X1516775D03*
X1514825Y480726D03*
Y473966D03*
X1516775Y470586D03*
X1518725Y487486D03*
Y480726D03*
Y473966D03*
Y467206D03*
X1522625D03*
Y473966D03*
Y487486D03*
X1526525D03*
Y473966D03*
Y467206D03*
X1514825Y487486D03*
X1511752Y498780D03*
X1490929Y507104D03*
X1506060Y508180D03*
X1501490Y504988D03*
X1501934Y513047D03*
X1505743Y516117D03*
X1511215Y507781D03*
X1512400Y519020D03*
X1493930Y522800D03*
X1488410Y517810D03*
X1497267Y505323D03*
X1496174Y514221D03*
X1509000Y498750D03*
X1488500Y498900D03*
X1526500Y498671D03*
Y506400D03*
X1485300Y498962D03*
X1483804Y509928D03*
X1484200Y524200D03*
X1524575Y470586D03*
X1484200Y515700D03*
X1481700D03*
X1475316Y527194D03*
X1472250Y485100D03*
X1472500Y509810D03*
X1501175Y477346D03*
X1493375D03*
X1505075Y484106D03*
X1501175D03*
X1497275Y470586D03*
X1495325Y467206D03*
X1526500Y503800D03*
Y501300D03*
X1507025Y480726D03*
X1495325D03*
X1503125D03*
X1508975Y484106D03*
X1507025Y473966D03*
X1503125D03*
X1493375Y470586D03*
X1499225Y487486D03*
X1497275Y484106D03*
X1493375D03*
X1499225Y473966D03*
X1495325Y487486D03*
X1512875Y484106D03*
X1510925Y487486D03*
X1497275Y477346D03*
X1489475D03*
X1491425Y467206D03*
X1505075Y477346D03*
X1511126Y503038D03*
X1500655Y516122D03*
X1488293Y508000D03*
X1481975Y507975D03*
X1474400Y517200D03*
X1508626Y503038D03*
X1506985Y510645D03*
X1510005Y518155D03*
X1498277Y508239D03*
X1490100Y520000D03*
X1485693Y508000D03*
X1479375Y507975D03*
X1503400Y524663D03*
X1507405Y518155D03*
X1498055Y516122D03*
X1509585Y510645D03*
X1500877Y508239D03*
X1492700Y520000D03*
X1468101Y573963D03*
X1468649Y570012D03*
X1481200Y531200D03*
X1483700D03*
X1527698Y578870D03*
X1474776Y572315D03*
X1491776Y573571D03*
X1479893Y572315D03*
X1482293D03*
X1477493D03*
X1487093D03*
X1489493D03*
X1484693D03*
X1518000Y562330D03*
X1510740Y557860D03*
X1494422Y574000D03*
X1481400Y539700D03*
X1494200Y530600D03*
X1497106Y531368D03*
X1511388Y531045D03*
X1503200Y530500D03*
X1505600D03*
X1508772Y530416D03*
X1514118Y530411D03*
X1483900Y539700D03*
X1525500Y582674D03*
Y580184D03*
X1525837Y574700D03*
X1523416Y573949D03*
X1527822Y576130D03*
X1525500Y577684D03*
X1499900Y574000D03*
X1496900D03*
X1489380Y546030D03*
X1478700Y533700D03*
X1469701Y599554D03*
X1469301Y607790D03*
X1467839Y618964D03*
X1469200Y610739D03*
X1470356Y618000D03*
X1470353Y592128D03*
X1469767Y596353D03*
X1480975Y620100D03*
X1516400Y619800D03*
X1504700Y608500D03*
X1500445Y619956D03*
X1492750Y615903D03*
X1494100Y613280D03*
X1497800Y610000D03*
X1497097Y613043D03*
X1483279Y619100D03*
X1505679Y620111D03*
X1511204Y620056D03*
X1475883Y619217D03*
X1503008Y620018D03*
X1472412Y596032D03*
Y599532D03*
X1479029Y596132D03*
X1477129Y597656D03*
X1474912Y596032D03*
X1480760Y611602D03*
X1485429Y597571D03*
X1491412Y596032D03*
X1489229Y597571D03*
X1487329Y596032D03*
X1512500Y598639D03*
X1510450Y597300D03*
X1507950D03*
X1510450Y600800D03*
X1508031Y599922D03*
X1524800Y598778D03*
X1522900Y597300D03*
X1526950D03*
X1518800Y597200D03*
X1520813Y598508D03*
X1516800Y598639D03*
X1514500Y597300D03*
X1527050Y613000D03*
X1523450Y612900D03*
X1519850Y613000D03*
X1487912Y611632D03*
X1491512Y611732D03*
X1484312D03*
X1511350Y613000D03*
X1513867Y612939D03*
X1516367D03*
X1475812Y611732D03*
X1474912Y599532D03*
X1478329Y611671D03*
X1483104Y596072D03*
X1481229Y597571D03*
X1472932Y619131D03*
X1504700Y611100D03*
X1518900Y619800D03*
X1508550Y619810D03*
X1513700Y619900D03*
X1478500Y619300D03*
X1549334Y23856D03*
X1538520Y11911D03*
X1584447Y-6702D03*
X1584000Y-16100D03*
X1581947Y-6702D03*
X1530800Y3500D03*
X1534000D03*
X1546800Y3400D03*
X1580398Y5400D03*
X1586500Y-16100D03*
X1580398Y-600D03*
X1579447Y-6702D03*
X1549800Y3400D03*
X1554800D03*
X1560500D03*
X1569000D03*
X1566000D03*
X1567498Y12506D03*
X1577048D03*
X1586998Y11355D03*
X1589623Y24528D03*
X1570200Y12900D03*
X1579773Y13257D03*
X1589259Y10241D03*
X1545111Y24172D03*
X1540000Y3400D03*
X1541400Y12500D03*
X1528384Y28040D03*
X1552300Y3400D03*
X1558000D03*
X1544882Y-6900D03*
X1549600Y-10800D03*
X1551309Y12792D03*
X1560700Y13000D03*
X1551834Y23856D03*
X1554434D03*
X1548698Y12506D03*
X1558148Y12306D03*
X1589500Y-600D03*
X1571500Y-1406D03*
X1573048Y12506D03*
X1581998Y11355D03*
X1554148Y12306D03*
X1563498Y12506D03*
X1544698D03*
X1563200Y3400D03*
X1543500D03*
X1588962Y75926D03*
X1575959Y84198D03*
X1584748Y70840D03*
X1572586Y95639D03*
X1587359Y84348D03*
X1579807Y75841D03*
X1582407D03*
X1570511Y75396D03*
X1573076Y75328D03*
X1573060Y84120D03*
X1589900Y84422D03*
X1583621Y87213D03*
X1588700Y94288D03*
X1573473Y37216D03*
X1582923D03*
X1587734Y70974D03*
X1583374Y81319D03*
X1575018Y71213D03*
X1579100Y69000D03*
X1574780Y90992D03*
X1535300Y78490D03*
X1562850Y73642D03*
X1541520Y79387D03*
X1538870Y78980D03*
X1532800Y78590D03*
X1562575Y76231D03*
X1556810Y71760D03*
X1542179Y39695D03*
X1545572Y38188D03*
X1541988Y90207D03*
Y92707D03*
X1541670Y87760D03*
X1554573Y37216D03*
X1564023D03*
X1544180Y91660D03*
X1546370Y84180D03*
X1545250Y88360D03*
X1556200Y94800D03*
X1577269Y95344D03*
X1529449Y137408D03*
X1557981Y141470D03*
X1572395Y110754D03*
X1574000Y149500D03*
Y152100D03*
X1572634Y98546D03*
X1576506Y143416D03*
X1574197Y127915D03*
X1588000Y100500D03*
X1588500Y106788D03*
X1567968Y136682D03*
X1567981Y139607D03*
X1579310Y128604D03*
X1576606Y104392D03*
X1579290Y131104D03*
X1573153Y103721D03*
X1577770Y149519D03*
X1577950Y152600D03*
X1589622Y112876D03*
X1577700Y155353D03*
Y140149D03*
X1567520Y133354D03*
X1589200Y121800D03*
X1589880Y134851D03*
X1582500Y109900D03*
X1587620Y135921D03*
X1580275Y101041D03*
X1578000Y113000D03*
X1585500Y101000D03*
X1553353Y124209D03*
X1553500Y157000D03*
X1552171Y133000D03*
X1555000Y139000D03*
X1549000Y115571D03*
X1542000Y126246D03*
X1549187Y104713D03*
X1542100Y119200D03*
X1542900Y121700D03*
X1531700Y155600D03*
X1541421Y106742D03*
X1541800Y99700D03*
X1541900Y97300D03*
X1541413Y155259D03*
X1541434Y139871D03*
X1531678Y135284D03*
X1541390Y136498D03*
X1558136Y100877D03*
X1554627D03*
X1553500Y121000D03*
X1548955Y101358D03*
X1558189Y107067D03*
X1554800Y129100D03*
Y98200D03*
X1558100D03*
X1558383Y121500D03*
X1554945Y133400D03*
X1531726Y123800D03*
X1563108Y126423D03*
X1541351Y151900D03*
X1558100Y138025D03*
Y133526D03*
Y124427D03*
Y128926D03*
X1531985Y147000D03*
X1532923Y144518D03*
X1542685Y133321D03*
X1555676Y123283D03*
X1573121Y120649D03*
X1530101Y132671D03*
X1541765Y114000D03*
X1541831Y149030D03*
X1583600Y207495D03*
X1566486Y181270D03*
X1583874Y217746D03*
X1582249Y191716D03*
X1587549Y192000D03*
X1566858Y175192D03*
X1570294Y167384D03*
X1572817Y169910D03*
X1568488Y164058D03*
X1571501Y180031D03*
X1553500Y165400D03*
X1557787Y192236D03*
X1561925Y192675D03*
X1558000Y205100D03*
X1557979Y188844D03*
X1535000Y207200D03*
X1535425Y188016D03*
X1535399Y190920D03*
X1552063Y202031D03*
X1549693Y196707D03*
X1548178Y190880D03*
X1545910Y199977D03*
X1546000Y197400D03*
X1543100Y184128D03*
X1533132Y158068D03*
X1531565Y176645D03*
X1537298Y162703D03*
X1535065Y164300D03*
X1561538Y174649D03*
X1545023Y161675D03*
X1562150Y160700D03*
X1557634Y175948D03*
X1562079Y163580D03*
X1552051Y172053D03*
X1558042Y172448D03*
X1567000Y259560D03*
X1568120Y251710D03*
X1574560Y237660D03*
X1571876Y255800D03*
X1570272Y234889D03*
X1572730Y235931D03*
X1586950Y251267D03*
X1570318Y238116D03*
X1572700Y239400D03*
X1568365Y247761D03*
X1589592Y252472D03*
X1582699Y252646D03*
X1579867Y265445D03*
X1530200Y257200D03*
X1531935Y224160D03*
X1533596Y273504D03*
X1532237Y247801D03*
X1528460Y244371D03*
X1537972Y236000D03*
X1542690Y236050D03*
X1541325Y245090D03*
X1547869Y243356D03*
X1547375Y245850D03*
X1542751Y240477D03*
X1563157Y258164D03*
X1561104Y234255D03*
X1563440Y250955D03*
X1559577Y236300D03*
X1558700Y252000D03*
X1574900Y240900D03*
X1547000Y263500D03*
Y269400D03*
X1541000Y263500D03*
Y269500D03*
X1544000Y266500D03*
X1545802Y233529D03*
X1584568Y281339D03*
X1589476Y322953D03*
X1565235Y303734D03*
X1578630Y293430D03*
X1572336Y287063D03*
X1578790Y290920D03*
X1581077Y284825D03*
X1578577Y284799D03*
X1565000Y290500D03*
X1571293Y284755D03*
X1573790Y284895D03*
X1580365Y341293D03*
X1577486Y307621D03*
X1566000Y341000D03*
X1587800Y308200D03*
X1580150Y329483D03*
X1581090Y338795D03*
X1569211Y331542D03*
Y334142D03*
X1569926Y308064D03*
X1566910Y315117D03*
X1581940Y295820D03*
X1588551Y341410D03*
X1583794Y338767D03*
X1581834Y318591D03*
X1583500Y303120D03*
Y300560D03*
X1573950Y338050D03*
X1585479Y316610D03*
X1582859Y341112D03*
X1570574Y341776D03*
X1528250Y311900D03*
X1530033Y340799D03*
X1533228Y325000D03*
X1529734Y319714D03*
X1532850Y303950D03*
X1530500Y287700D03*
X1537500Y292800D03*
X1533914Y286073D03*
X1533838Y288706D03*
X1554932Y332171D03*
X1560024Y331800D03*
X1564427Y311083D03*
X1548334Y325497D03*
X1548273Y313227D03*
X1543864Y311399D03*
X1551250Y320303D03*
X1547398Y333823D03*
X1554775Y295328D03*
X1560024Y329200D03*
X1536027Y305048D03*
X1534833Y309798D03*
X1539400Y320200D03*
X1544904Y334008D03*
X1557250Y315410D03*
X1551404Y309376D03*
X1560400Y307683D03*
X1550619Y303087D03*
X1559997Y310317D03*
X1534400Y296029D03*
X1564411Y315210D03*
X1538450Y314300D03*
X1543700Y322600D03*
X1563000Y341000D03*
X1538206Y303741D03*
X1542200Y324600D03*
X1548024Y322145D03*
X1548000Y331361D03*
X1546612Y287812D03*
X1559500Y290300D03*
X1559800Y285300D03*
X1548199Y285830D03*
X1552900Y281700D03*
X1554800Y290600D03*
X1548100Y342200D03*
X1538406Y330157D03*
X1554800Y341100D03*
X1557550D03*
X1547882Y318942D03*
X1550800Y296200D03*
X1549000Y316600D03*
X1575645Y320664D03*
X1565244Y300934D03*
X1568524Y312885D03*
X1582800Y312100D03*
X1564400Y308383D03*
X1540175Y387654D03*
X1551875D03*
X1565525Y397794D03*
X1528475Y401174D03*
Y387654D03*
Y394414D03*
X1530425Y377514D03*
X1534325Y384274D03*
Y397794D03*
Y377514D03*
X1542300Y376717D03*
X1551875Y394414D03*
X1540175Y380894D03*
Y401174D03*
X1536275D03*
X1540175Y394414D03*
X1563575Y387654D03*
X1551875Y401174D03*
X1559675Y380894D03*
X1563575D03*
X1565525Y384274D03*
X1586400Y392900D03*
X1567475Y380894D03*
Y387654D03*
X1582420Y377830D03*
X1582350Y374567D03*
X1582124Y381164D03*
X1573000Y391161D03*
X1571366Y401154D03*
X1582000Y396250D03*
X1567475Y394414D03*
X1570672Y362134D03*
X1567121Y365817D03*
X1576380Y362890D03*
X1582500Y369600D03*
X1573521Y365500D03*
X1571375Y394414D03*
X1565525Y377514D03*
X1567121Y363217D03*
X1566922Y359681D03*
X1567475Y401174D03*
X1576074Y359600D03*
X1582600Y389300D03*
X1571450Y359650D03*
X1565525Y391034D03*
X1570289Y384368D03*
X1585150Y397400D03*
X1571585Y382230D03*
X1586500Y354900D03*
X1589100Y358400D03*
X1569425Y391034D03*
Y397794D03*
X1587683Y397414D03*
X1571375Y387654D03*
X1569584Y378002D03*
X1581822Y365770D03*
X1587968Y403368D03*
X1530425Y384274D03*
X1533719Y362783D03*
X1533790Y360283D03*
X1528475Y380894D03*
X1529829Y362655D03*
X1530425Y391034D03*
Y397794D03*
X1532375Y401174D03*
Y380894D03*
Y387654D03*
Y394414D03*
X1533589Y366361D03*
X1532367Y356530D03*
X1553825Y391034D03*
X1546025D03*
X1563575Y394414D03*
X1557725Y397794D03*
X1550639Y350200D03*
X1563575Y401174D03*
X1538200Y364700D03*
X1553825Y397794D03*
X1546025D03*
X1538500Y359363D03*
X1552500Y358500D03*
X1557725Y377514D03*
X1538397Y361861D03*
X1538478Y350694D03*
Y353294D03*
Y355894D03*
X1559675Y401174D03*
X1542125Y397794D03*
X1558950Y363050D03*
X1547975Y394414D03*
X1542932Y355740D03*
X1547975Y387654D03*
X1536275D03*
Y380894D03*
X1534325Y391034D03*
X1559675Y387654D03*
Y394414D03*
X1551875Y380894D03*
X1557725Y391034D03*
X1536275Y394414D03*
X1558980Y360130D03*
X1538225Y377514D03*
Y384274D03*
X1544075Y380894D03*
Y387654D03*
X1538225Y391034D03*
Y397794D03*
X1544075Y394414D03*
X1558996Y365817D03*
X1555775Y394414D03*
X1549925Y397794D03*
X1561625D03*
X1555775Y401174D03*
X1549925Y377514D03*
X1561625D03*
Y391034D03*
Y384274D03*
X1549925Y391034D03*
Y384274D03*
X1555775Y387654D03*
Y380894D03*
X1560500Y350000D03*
X1557534Y353400D03*
X1553825Y377514D03*
X1543300Y360900D03*
X1543528Y352446D03*
X1546182Y355446D03*
X1543528Y349946D03*
X1543300Y363400D03*
X1550417Y362607D03*
X1586500Y358400D03*
X1587684Y362653D03*
X1587032Y350996D03*
X1565525Y460446D03*
X1567475Y414694D03*
Y443546D03*
Y463826D03*
X1565525Y453686D03*
Y418074D03*
X1571375Y421454D03*
X1569425Y418074D03*
X1565525Y424834D03*
X1571375Y414694D03*
Y407934D03*
X1565525Y446926D03*
X1528475Y463826D03*
X1559675D03*
X1542125Y460446D03*
X1536275Y463826D03*
X1555775Y407934D03*
X1561625Y411314D03*
Y440166D03*
X1551875Y443546D03*
X1557725Y460446D03*
X1553825D03*
X1563575Y450306D03*
X1546025Y460446D03*
X1563575Y463826D03*
X1557725Y440166D03*
Y418074D03*
X1563575Y421454D03*
X1580370Y462090D03*
X1584200Y462610D03*
X1557725Y424834D03*
X1569425Y440166D03*
X1587559Y423835D03*
X1567475Y436786D03*
X1588870Y440546D03*
X1571375Y443546D03*
X1588632Y452151D03*
X1587550Y456550D03*
X1585920Y452368D03*
X1587573Y445300D03*
X1587000Y411976D03*
X1571375Y436786D03*
X1589500Y412035D03*
X1583208Y404941D03*
X1569425Y446926D03*
X1584233Y427947D03*
X1565525Y411314D03*
X1583773Y436137D03*
X1585560Y421324D03*
X1581939Y426594D03*
X1583208Y452185D03*
X1569425Y453686D03*
X1589396Y425674D03*
X1567475Y450306D03*
X1565525Y440166D03*
X1571375Y457066D03*
X1567475D03*
X1569425Y460446D03*
X1582200Y456200D03*
X1565525Y431594D03*
X1569425D03*
Y404554D03*
X1583208Y412815D03*
X1584975Y460210D03*
X1587475D03*
X1582200Y460310D03*
X1569425Y424834D03*
Y411314D03*
X1567475Y407934D03*
X1582300Y446100D03*
X1571390Y464480D03*
X1587238Y432593D03*
X1583208Y416752D03*
X1567475Y421454D03*
X1532375Y463826D03*
Y407934D03*
X1531250Y445100D03*
Y448250D03*
X1528475Y457066D03*
X1532349Y455200D03*
X1531250Y419900D03*
Y451400D03*
Y426200D03*
Y429350D03*
Y423050D03*
Y438800D03*
Y435650D03*
Y441950D03*
X1530425Y460446D03*
X1528475Y407934D03*
X1551875D03*
Y414694D03*
X1563575Y407934D03*
X1559675Y414694D03*
X1546025Y404554D03*
X1561625Y424834D03*
X1551990Y421158D03*
X1551875Y428214D03*
X1561625Y431594D03*
X1563575Y428214D03*
X1555775Y443546D03*
Y436786D03*
X1563575Y457066D03*
X1549938Y453714D03*
X1547975Y457066D03*
X1549925Y446926D03*
X1557725D03*
X1561625Y460446D03*
X1555775Y457066D03*
X1551875D03*
X1557725Y453686D03*
X1559675Y443546D03*
Y436786D03*
X1547975Y463826D03*
X1551875D03*
X1555775D03*
X1538225Y460446D03*
X1559675Y407934D03*
X1561625Y446926D03*
X1543850Y416750D03*
Y413600D03*
X1540700Y416750D03*
X1534400D03*
X1537550D03*
X1551875Y450306D03*
X1534400Y413500D03*
X1549950Y404490D03*
X1544075Y463826D03*
X1537550Y413600D03*
X1536275Y407934D03*
X1540175D03*
X1540700Y413600D03*
X1543850Y445100D03*
Y451400D03*
X1549926Y411312D03*
X1553825Y411314D03*
X1544150Y409900D03*
X1553825Y446926D03*
Y440166D03*
X1555775Y414694D03*
X1561625Y418074D03*
X1540700Y445100D03*
X1537550Y448250D03*
X1534400D03*
X1540700D03*
X1537550Y445100D03*
X1534400D03*
X1540700Y435650D03*
X1547754Y430351D03*
X1547755Y423570D03*
X1547754Y427884D03*
X1553825Y453686D03*
X1547000Y435650D03*
X1549925Y431594D03*
X1547755Y421138D03*
X1549925Y440166D03*
X1543950Y438800D03*
X1543850Y441950D03*
X1549964Y424753D03*
X1551875Y436786D03*
X1540653Y454588D03*
X1540700Y423050D03*
X1537550Y429350D03*
X1540700D03*
X1534400Y426200D03*
X1537550D03*
X1540700D03*
X1534400Y429350D03*
Y423050D03*
X1537550D03*
X1534400Y438800D03*
Y435650D03*
X1549925Y460446D03*
X1559595Y450631D03*
X1547000Y416750D03*
X1557725Y404554D03*
X1563575Y414694D03*
X1559675Y457066D03*
X1534400Y419900D03*
X1540700D03*
X1543850Y429350D03*
Y426200D03*
X1537550Y419900D03*
X1534325Y404554D03*
X1538225D03*
X1542125D03*
X1540700Y410450D03*
X1534400Y451400D03*
Y441950D03*
X1537550D03*
X1534325Y460446D03*
X1537550Y451400D03*
X1544075Y457066D03*
X1540175D03*
X1540700Y451400D03*
Y441950D03*
X1540175Y463826D03*
X1543850Y435650D03*
X1537550D03*
Y438800D03*
X1540700D03*
X1536300Y455200D03*
X1553825Y418074D03*
X1559675Y421454D03*
X1555775D03*
X1567475Y477346D03*
X1565525Y473966D03*
X1569425Y467206D03*
X1565525D03*
X1571545Y482842D03*
X1571375Y477346D03*
X1530425Y467206D03*
X1561625D03*
X1563575Y470586D03*
X1561625Y473966D03*
X1551875Y470586D03*
X1549925Y467206D03*
X1559675Y470586D03*
X1557725Y467206D03*
X1547975Y484106D03*
X1551875D03*
X1549925Y480726D03*
X1559675Y477346D03*
X1563575Y484106D03*
X1561625Y480726D03*
X1536275Y477346D03*
X1559675Y484106D03*
X1530425Y480726D03*
Y487486D03*
X1557725D03*
X1561625D03*
X1534325Y473966D03*
X1582644Y495077D03*
X1568600Y494500D03*
X1565210Y509160D03*
X1567817Y499735D03*
X1569425Y473966D03*
X1571375Y470586D03*
X1565525Y480726D03*
X1570062Y487039D03*
X1587970Y472370D03*
X1587433Y490425D03*
X1567475Y470586D03*
X1584970Y472370D03*
X1589025Y495975D03*
X1568400Y503300D03*
X1567475Y484106D03*
X1565525Y487486D03*
X1569425Y480726D03*
X1531685Y499540D03*
Y502040D03*
X1532375Y470586D03*
X1530425Y473966D03*
X1528475Y470586D03*
Y477346D03*
X1534180Y498580D03*
X1534039Y502906D03*
X1531580Y510790D03*
X1534020Y511930D03*
X1533595Y505530D03*
Y509030D03*
X1534325Y467206D03*
X1538225D03*
X1542125D03*
X1540175Y470586D03*
X1555510Y501975D03*
Y499475D03*
X1555438Y507217D03*
Y509717D03*
X1565000Y506329D03*
Y503329D03*
X1534325Y487486D03*
X1536275Y484106D03*
X1544075Y470586D03*
X1542125Y473966D03*
X1540175Y477346D03*
X1536275Y470586D03*
X1544075Y477346D03*
X1538225Y473966D03*
X1542475Y504400D03*
X1542425Y512200D03*
X1546025Y467206D03*
X1553825Y487486D03*
Y480726D03*
X1557725D03*
X1549925Y473966D03*
X1547975Y470586D03*
X1553825Y473966D03*
Y467206D03*
X1555775Y470586D03*
X1557725Y473966D03*
X1555775Y477346D03*
Y484106D03*
X1549925Y487486D03*
X1546025Y480726D03*
X1548300Y499000D03*
X1564600Y500414D03*
X1555424Y504609D03*
X1555832Y512288D03*
X1548300Y506600D03*
X1544075Y484106D03*
X1542125Y480726D03*
X1538225Y487486D03*
X1546025D03*
X1540175Y484106D03*
X1542125Y487486D03*
X1551875Y477346D03*
X1548300Y504000D03*
X1563575Y477346D03*
X1542475Y507000D03*
Y499400D03*
X1548300Y509200D03*
X1538225Y480726D03*
X1534325D03*
X1528475Y484106D03*
X1532375D03*
Y477346D03*
X1547975D03*
X1546025Y473966D03*
X1548300Y501500D03*
X1542475Y501900D03*
Y509600D03*
X1548300Y511800D03*
X1565389Y585721D03*
X1581730Y537170D03*
X1587610Y579550D03*
X1580360Y565524D03*
X1580400Y568000D03*
X1580300Y563000D03*
Y560500D03*
X1566000Y575820D03*
X1565940Y573120D03*
X1565800Y570600D03*
X1565600Y568100D03*
Y565700D03*
X1529944Y574725D03*
X1529894Y577342D03*
X1532354Y577283D03*
X1532642Y579853D03*
X1529600Y582300D03*
X1532400D03*
X1529942Y579853D03*
X1563800Y564100D03*
X1561300Y564000D03*
X1558800Y563900D03*
X1563448Y566766D03*
X1563432Y569340D03*
X1545200Y585724D03*
X1542600D03*
X1550990Y586588D03*
X1554358Y587258D03*
X1589604Y585896D03*
X1581704D03*
X1585155Y538574D03*
X1586700Y620100D03*
X1587679Y596867D03*
X1585179Y596902D03*
X1579900Y606050D03*
X1587504Y605496D03*
Y607996D03*
X1573260Y601600D03*
X1570660Y601563D03*
X1566520Y623382D03*
X1569495Y623365D03*
X1572950Y593950D03*
X1573500Y619500D03*
X1529067Y615784D03*
X1529697Y613384D03*
X1532270Y610764D03*
X1532160Y613408D03*
X1546075Y618145D03*
X1544050Y615296D03*
X1534968Y597268D03*
X1535565Y591658D03*
X1560747Y623576D03*
X1557575Y623559D03*
X1541162Y607903D03*
X1543697Y606719D03*
X1563827Y621376D03*
X1554800Y620910D03*
X1537711Y613397D03*
X1538679Y615641D03*
X1534928Y610532D03*
X1538337Y601097D03*
X1534948Y613302D03*
X1545000Y591100D03*
X1540477Y620308D03*
X1540700Y613700D03*
X1552198Y623479D03*
X1553000Y591100D03*
X1541384Y601262D03*
X1581704Y590196D03*
X1589604D03*
X1558800Y599300D03*
X1560400Y611600D03*
X1564300Y599400D03*
X1564400Y605500D03*
X1561700Y602200D03*
X1552400Y607600D03*
X1554900Y607100D03*
X1556200Y602400D03*
X1554400Y599300D03*
X1564300Y611500D03*
X1577000Y619500D03*
X1545407Y604713D03*
X1555600Y591100D03*
X1579680Y610279D03*
X1545407Y598393D03*
X1595004Y-17346D03*
X1598602Y3437D03*
X1605500Y-3600D03*
X1592453Y8502D03*
X1610004Y-17346D03*
X1623900Y4600D03*
X1605004Y-17346D03*
X1600004D03*
X1602504D03*
X1608500Y-3600D03*
X1592829Y24460D03*
X1597800Y24300D03*
X1646200Y5300D03*
X1646400Y13400D03*
X1637482Y21623D03*
X1638550Y7200D03*
X1597700Y9000D03*
X1595848Y11406D03*
X1617000Y9500D03*
X1617500Y-14500D03*
X1601650Y24160D03*
X1597504Y-17346D03*
X1615000Y12000D03*
X1634200Y9700D03*
X1627500Y11700D03*
X1608123Y13302D03*
X1619100Y6500D03*
X1626400Y4600D03*
X1606700D03*
X1636500D03*
X1607504Y-17346D03*
X1601102Y-600D03*
X1590431Y-6702D03*
X1598602Y-600D03*
X1591848Y11406D03*
X1648748Y6325D03*
X1638865Y11105D03*
X1629148Y6825D03*
X1619798Y10755D03*
X1643865Y11105D03*
X1634148Y6825D03*
X1624798Y10755D03*
X1600898Y11355D03*
X1609833Y5425D03*
X1605898Y11355D03*
X1614833Y5425D03*
X1592715Y70817D03*
X1591600Y75700D03*
X1593000Y78140D03*
X1591270Y93940D03*
X1592200Y37700D03*
X1590464Y77962D03*
X1637700Y67400D03*
X1640900Y66900D03*
X1650876Y65237D03*
X1648276Y65221D03*
X1651250Y36750D03*
X1639623Y38100D03*
X1649073Y38200D03*
X1649900Y78600D03*
X1620050Y35550D03*
X1608500Y72688D03*
X1615115Y70786D03*
X1612000Y70984D03*
X1635337Y73500D03*
X1619000Y38500D03*
X1599000Y61500D03*
X1620900Y81300D03*
X1632000Y73500D03*
X1627489Y74960D03*
X1630386Y41448D03*
X1651298Y39462D03*
X1641848D03*
X1632398Y39862D03*
X1602000Y84500D03*
X1596900D03*
X1620733Y74847D03*
X1623200Y75800D03*
X1606797Y64949D03*
X1608452Y62890D03*
X1599500Y75000D03*
X1606579Y86726D03*
X1599500Y84500D03*
X1614169Y95004D03*
X1617347Y94581D03*
X1597867Y93900D03*
X1614997Y84403D03*
X1596050Y75400D03*
X1606730Y84230D03*
X1632000Y83000D03*
X1625451Y84288D03*
X1605184Y61044D03*
X1610450Y37300D03*
X1627380Y36652D03*
X1630121Y37609D03*
X1595943Y71522D03*
X1603138Y65890D03*
X1602840Y37382D03*
X1635900Y83000D03*
X1625075Y80182D03*
X1610853Y63861D03*
X1622635Y39900D03*
X1646848Y39462D03*
X1637398Y39862D03*
X1627715Y39934D03*
X1632006Y94500D03*
X1643500Y80400D03*
X1621100Y69600D03*
X1597987Y79500D03*
X1630826Y88087D03*
X1613741Y112341D03*
X1593241Y134295D03*
X1628788Y97800D03*
X1593756Y129048D03*
X1590800Y137800D03*
X1593500D03*
X1590949Y97850D03*
X1595335Y98135D03*
X1641600Y96500D03*
X1638500D03*
X1595522Y127278D03*
X1648000Y100597D03*
X1598449Y120760D03*
X1598300Y116477D03*
X1632020Y97871D03*
X1600000Y104243D03*
X1594452Y111377D03*
X1630836Y197560D03*
X1637870Y197577D03*
X1590525Y217033D03*
X1590495Y214525D03*
X1593020Y215129D03*
X1593218Y191776D03*
X1592870Y217900D03*
X1595291Y166423D03*
X1591800Y164900D03*
X1626935Y217775D03*
X1598006Y192421D03*
X1611761Y216250D03*
X1651000Y178628D03*
X1645700Y214050D03*
X1650600Y186300D03*
X1648349Y182276D03*
X1650300Y195251D03*
X1648400Y214100D03*
X1643887Y181841D03*
X1642457Y186948D03*
X1637870Y195077D03*
X1644290Y196383D03*
X1634069Y197454D03*
X1604401Y213500D03*
X1618500Y181680D03*
X1625524Y184531D03*
X1635100Y182800D03*
X1620036Y196186D03*
X1635112Y195181D03*
X1605250Y197250D03*
X1629595Y217725D03*
X1627326Y182759D03*
X1613053Y184949D03*
X1610554Y184877D03*
X1615362Y213507D03*
X1615553Y184908D03*
X1611761Y213507D03*
X1602185Y180709D03*
X1628950Y195344D03*
X1632590D03*
X1635351Y185444D03*
X1619500Y184944D03*
X1622248Y185060D03*
X1644433Y185415D03*
X1641800Y184400D03*
X1614000Y177800D03*
X1598950Y180300D03*
X1595800D03*
X1608056Y184771D03*
X1603300Y185100D03*
X1639258Y185620D03*
X1647852Y197374D03*
X1635621Y208259D03*
X1604222Y268107D03*
X1627177Y260267D03*
X1637281Y254322D03*
X1636684Y279815D03*
X1591865Y237407D03*
X1591174Y225017D03*
X1627024Y253387D03*
X1627043Y256900D03*
X1638216Y246021D03*
X1636684Y274815D03*
X1637269Y264421D03*
X1637281Y260922D03*
X1636914Y270900D03*
X1643106Y233913D03*
X1640871Y235210D03*
X1596600Y246350D03*
X1596300Y250320D03*
X1608489Y252095D03*
X1601870Y270470D03*
X1626124Y225250D03*
X1599270Y246310D03*
X1600810Y266006D03*
X1609051Y243415D03*
X1624798Y241937D03*
X1631300Y280400D03*
X1626291Y273309D03*
X1597201Y238188D03*
X1621164Y223392D03*
X1620250Y254741D03*
X1621164Y225910D03*
X1620240Y257660D03*
X1617498Y273433D03*
X1628624Y225318D03*
X1598028Y256422D03*
X1610290Y265352D03*
X1600552Y261281D03*
X1636684Y277315D03*
X1623447Y273273D03*
X1606849Y241210D03*
X1643775Y246137D03*
X1632128Y225472D03*
X1622000Y279495D03*
X1639413Y310235D03*
X1592110Y322002D03*
X1590176Y331844D03*
X1590212Y315425D03*
X1636800Y287956D03*
X1636922Y302588D03*
X1636861Y305091D03*
X1639040Y316343D03*
X1638086Y319664D03*
X1619897Y338636D03*
Y336136D03*
X1631015Y328350D03*
X1619897Y341136D03*
X1635355Y324228D03*
X1609172Y339630D03*
X1602776Y331304D03*
X1625846Y286154D03*
X1638063Y326504D03*
X1636822Y294946D03*
X1639413Y312735D03*
X1636925Y297444D03*
X1636822Y292446D03*
X1642712Y342347D03*
X1636684Y283141D03*
X1635503Y340146D03*
X1629503D03*
X1620159Y332004D03*
X1625400Y327667D03*
X1608764Y322440D03*
X1630200Y367730D03*
X1630900Y375600D03*
X1622100Y400600D03*
X1603307Y393224D03*
X1591912Y391052D03*
X1590218Y350995D03*
X1642443Y344879D03*
X1638991Y352037D03*
X1640001Y370790D03*
X1650624Y357884D03*
X1650480Y368215D03*
X1642126Y357894D03*
X1642114Y368142D03*
X1601060Y401010D03*
X1599100Y399100D03*
X1610828Y381387D03*
X1596151D03*
X1596168Y375135D03*
X1609761Y372584D03*
X1608146Y380322D03*
Y376171D03*
X1630300Y395300D03*
X1630408Y357603D03*
X1630550Y401300D03*
X1630534Y354900D03*
X1630476Y360103D03*
X1630400Y398700D03*
X1629300Y385400D03*
X1630240Y365099D03*
X1630400Y391800D03*
X1597900Y370000D03*
X1597850Y367329D03*
X1643150Y348692D03*
X1643700Y351667D03*
X1630337Y362600D03*
X1621727Y395374D03*
X1613474Y391105D03*
X1609271Y348166D03*
X1608850Y343835D03*
X1613452Y387098D03*
X1610140Y358350D03*
X1610370Y361890D03*
X1607412Y360895D03*
X1602215Y363981D03*
X1630000Y381400D03*
X1620447Y373926D03*
X1610642Y375135D03*
X1608020Y356500D03*
X1619889Y352841D03*
X1607443Y398649D03*
X1598878Y380344D03*
X1629503Y346146D03*
X1635503Y346046D03*
X1632503Y343146D03*
X1598878Y376346D03*
X1621800Y386300D03*
Y381500D03*
X1630800Y378500D03*
X1640266Y365500D03*
Y360500D03*
X1590154Y354762D03*
X1630120Y418887D03*
X1595800Y405900D03*
X1621000Y452000D03*
X1612500Y411800D03*
X1618800Y453400D03*
X1595200Y412700D03*
X1617900Y409900D03*
X1630750Y404800D03*
X1591446Y440472D03*
X1591344Y452134D03*
X1591430Y409440D03*
X1591350Y445300D03*
X1593400Y432200D03*
X1639500Y435700D03*
X1640625Y429460D03*
X1640000Y456900D03*
X1640100Y459700D03*
X1630200Y457175D03*
X1630300Y452100D03*
X1630150Y427663D03*
X1611642Y461877D03*
X1600400Y446100D03*
X1630219Y446000D03*
X1621000Y440500D03*
X1621044Y433364D03*
X1612250Y432500D03*
X1611418Y422971D03*
X1621182Y427091D03*
X1621347Y415297D03*
X1603719Y412000D03*
X1611638Y454809D03*
X1612100Y446000D03*
X1603000Y435500D03*
X1630386Y413942D03*
X1634400Y412900D03*
X1630276Y449517D03*
X1612183Y442623D03*
X1602600Y444287D03*
X1603050Y432523D03*
X1621010Y435870D03*
X1620500Y463727D03*
X1634500Y418500D03*
X1603650Y415469D03*
X1646540Y441240D03*
X1639750Y445477D03*
X1639500Y433200D03*
X1646480Y443880D03*
X1639774Y439486D03*
X1646451Y452590D03*
X1646469Y450090D03*
X1646525Y447590D03*
X1639822Y453140D03*
X1647200Y430450D03*
X1622700Y461900D03*
X1612825Y405438D03*
Y408974D03*
X1596500Y455500D03*
X1615061Y463157D03*
X1603000Y422971D03*
X1630200Y454675D03*
X1621226Y445026D03*
X1612256Y440088D03*
X1611935Y429515D03*
X1623749Y464213D03*
X1604200Y464387D03*
X1612250Y435500D03*
X1590037Y432515D03*
X1590581Y404170D03*
X1650944Y505166D03*
X1648330Y504544D03*
X1594880Y494880D03*
X1592025Y495975D03*
X1641963Y495964D03*
X1639391Y513065D03*
X1642670Y514939D03*
X1649336Y511502D03*
X1641470Y506403D03*
X1644651Y505500D03*
X1649545Y515215D03*
X1645969Y514870D03*
X1646700Y480300D03*
X1639394Y507798D03*
X1642880Y490047D03*
X1640781Y487760D03*
X1617700Y475957D03*
X1614000Y475970D03*
X1623705Y467855D03*
X1619607Y469945D03*
X1616607D03*
X1601557Y479225D03*
X1617300Y519000D03*
X1614900Y498575D03*
X1615100Y481400D03*
X1617600D03*
X1600780Y495416D03*
X1597380D03*
X1630159Y520608D03*
X1612500Y510300D03*
X1615000D03*
X1627032Y510226D03*
X1627068Y512626D03*
X1606200Y487100D03*
X1623814Y471400D03*
X1614000Y469500D03*
X1617700Y489700D03*
X1615200D03*
X1611506Y474768D03*
X1620500Y475000D03*
X1603500Y495300D03*
X1597178Y472226D03*
X1599900Y487100D03*
X1603802Y487205D03*
X1633359Y472859D03*
X1633075Y470174D03*
X1629778Y507294D03*
X1627407Y520318D03*
X1621783Y498617D03*
X1625485Y494188D03*
X1627622Y524928D03*
X1620030Y525066D03*
X1623551Y525015D03*
X1590580Y472370D03*
X1639113Y496734D03*
X1598700Y479225D03*
X1617771Y498714D03*
X1629530Y496374D03*
X1629500Y491500D03*
X1639271Y491135D03*
X1594280Y472370D03*
X1637500Y529400D03*
X1644800Y532800D03*
X1636848Y533794D03*
X1649900Y583500D03*
X1638674Y556178D03*
X1599070Y562266D03*
X1596570D03*
X1599120Y564764D03*
X1596620D03*
X1596600Y567250D03*
X1626518Y528029D03*
X1622040Y554827D03*
X1609829Y556599D03*
X1624293Y561747D03*
X1615030Y584260D03*
X1610080Y561367D03*
X1603060Y582920D03*
X1603120Y578020D03*
X1599170Y572780D03*
X1602000Y565700D03*
X1631975Y527700D03*
X1601540Y588793D03*
X1625094Y559200D03*
X1601825Y572325D03*
X1607533Y561644D03*
X1601825Y568325D03*
X1607533Y557644D03*
X1605994Y578500D03*
X1612519Y586004D03*
X1605994Y582500D03*
X1625094Y555200D03*
X1594110Y611510D03*
X1592934Y592396D03*
X1590304Y596896D03*
X1590004Y605496D03*
Y607996D03*
X1590530Y610620D03*
X1590881Y618788D03*
X1593519Y618736D03*
X1644856Y604930D03*
X1640921Y605334D03*
X1601504Y591526D03*
X1617600Y619800D03*
X1619700Y617300D03*
X1622330Y592325D03*
X1603550Y618250D03*
X1600950D03*
X1613721Y592325D03*
X1614700Y597000D03*
X1615862Y605507D03*
X1601489Y602812D03*
X1601270Y597200D03*
X1602150Y610720D03*
X1612519Y590004D03*
X1613349Y603250D03*
X1603919Y596750D03*
X1603869Y608450D03*
X1613349Y599250D03*
X1603869Y604450D03*
X1603919Y592750D03*
X1650869Y614200D03*
Y609200D03*
X1654800Y13518D03*
X1653100Y11500D03*
X1685948Y10725D03*
X1711863Y13276D03*
X1672427Y9700D03*
X1680033Y-16711D03*
X1666500Y10500D03*
X1688000Y3000D03*
X1676819Y-16779D03*
X1691000Y3000D03*
X1695200Y11317D03*
X1704771Y11261D03*
X1673500Y-16850D03*
X1680034Y2863D03*
X1664200Y5400D03*
X1656600Y6300D03*
X1664823Y13287D03*
X1685500Y3000D03*
X1682985Y2901D03*
X1675800Y4100D03*
X1702421Y13231D03*
X1684902Y13472D03*
X1691541Y13226D03*
X1653748Y6325D03*
X1676428Y11381D03*
X1666979Y6236D03*
X1657369Y10258D03*
X1690948Y10725D03*
X1681428Y11381D03*
X1671979Y6236D03*
X1662373Y10154D03*
X1700200Y11317D03*
X1709771Y11261D03*
X1682396Y74344D03*
X1693900Y73300D03*
X1697300Y73296D03*
X1700710Y73292D03*
X1690500Y73950D03*
X1679900Y74500D03*
X1678000Y81600D03*
X1653000Y77600D03*
X1669000Y92000D03*
X1659000Y88000D03*
X1661900Y92400D03*
X1708610Y85121D03*
X1709184Y88811D03*
X1707268Y77668D03*
X1692300Y56900D03*
X1684248Y56746D03*
X1658600Y44700D03*
X1696655Y77991D03*
X1694155D03*
X1691655D03*
X1689155D03*
X1700300Y94703D03*
X1704824Y90049D03*
X1674749Y87050D03*
X1676428Y74646D03*
X1673800Y75200D03*
X1675500Y81600D03*
X1673000D03*
X1670500D03*
X1678627Y54616D03*
X1672000Y51500D03*
X1712600Y46100D03*
X1669350Y69962D03*
X1664350Y72462D03*
Y69962D03*
X1659196Y70291D03*
X1661563Y72028D03*
X1709600Y45800D03*
X1711000Y55525D03*
X1669500Y51500D03*
X1656600Y73614D03*
X1659100D03*
X1668000Y81600D03*
X1665500D03*
X1695300Y94712D03*
X1697800Y94612D03*
X1692285D03*
X1692573Y85833D03*
X1702513Y79885D03*
X1696870Y86093D03*
X1689250Y86000D03*
X1668009Y37000D03*
X1667000Y51500D03*
X1706500Y37000D03*
X1678000D03*
X1687500D03*
X1660944Y36761D03*
X1696795Y38260D03*
X1708508Y39350D03*
X1699273Y39679D03*
X1679648Y39462D03*
X1670198D03*
X1660748D03*
X1689098D03*
X1658559Y37890D03*
X1659038Y95111D03*
X1659000Y85500D03*
X1670250Y87873D03*
X1667000Y88000D03*
X1663000Y81600D03*
X1677573Y86930D03*
X1677649Y90301D03*
X1675062Y91219D03*
X1656298Y39462D03*
X1712308Y39350D03*
X1703073Y39679D03*
X1694098Y39462D03*
X1684648D03*
X1675198D03*
X1665748D03*
X1654685Y121790D03*
X1664135Y131239D03*
X1657835D03*
X1689368Y98750D03*
X1686876Y98962D03*
X1680139Y99073D03*
X1696907Y99077D03*
X1664500Y99000D03*
X1657835Y156436D03*
X1660400Y98500D03*
X1672200Y112200D03*
X1701455Y153083D03*
X1698927Y153139D03*
X1674800Y103100D03*
X1678400Y103000D03*
X1655209Y181761D03*
X1680370Y185900D03*
X1674019Y175990D03*
X1663566Y213009D03*
X1674455Y169991D03*
X1677605Y169986D03*
X1674455Y172658D03*
X1655031Y184505D03*
X1654015Y217239D03*
X1655978Y207827D03*
X1663400Y179475D03*
X1681352Y196092D03*
X1686183Y191250D03*
X1683484Y190908D03*
X1687950Y186150D03*
X1682950Y184140D03*
X1680450Y183401D03*
X1708350Y175050D03*
X1708250Y164950D03*
X1688046Y174447D03*
X1667356Y213096D03*
X1660440Y200789D03*
X1702400Y193450D03*
X1702450Y190000D03*
X1664321Y195244D03*
X1658082Y195298D03*
X1673800Y201070D03*
X1660800Y181900D03*
X1687550Y213751D03*
X1671556Y208379D03*
X1702500Y187000D03*
X1713000Y185000D03*
X1709900Y187300D03*
X1705666Y198055D03*
X1676750Y206050D03*
X1667140Y182300D03*
X1674912Y183000D03*
X1669849Y193067D03*
X1674066Y196666D03*
X1673530Y209974D03*
X1703610Y161214D03*
X1700836Y161268D03*
X1695734Y164676D03*
X1691439Y174354D03*
X1677600Y172700D03*
X1707100Y188300D03*
X1664390Y201163D03*
X1659643Y213505D03*
X1676924Y196731D03*
X1671688Y182925D03*
X1666345Y241987D03*
X1683729Y242346D03*
X1690565Y251052D03*
X1667667Y257920D03*
X1670140Y257547D03*
X1670822Y254691D03*
X1661186Y245352D03*
X1662000Y250008D03*
X1664324Y248002D03*
X1666329Y245139D03*
X1662956Y243582D03*
X1681760Y245500D03*
X1684509Y245631D03*
X1688451Y249716D03*
X1686113Y250604D03*
X1683615Y250493D03*
X1679100Y276400D03*
X1681116Y238614D03*
X1681632Y233665D03*
X1657498Y279900D03*
Y274700D03*
Y269700D03*
X1657567Y264600D03*
X1657500Y259700D03*
X1657498Y277300D03*
Y267100D03*
X1657949Y257240D03*
X1666968Y260611D03*
X1684300Y233579D03*
X1679100Y278924D03*
Y271300D03*
Y273900D03*
X1680769Y242605D03*
X1653091Y331618D03*
X1652991Y318741D03*
Y323941D03*
Y329059D03*
X1653091Y326500D03*
X1652991Y321341D03*
X1657498Y284900D03*
X1679100Y292000D03*
Y284093D03*
Y294500D03*
Y286593D03*
Y289500D03*
X1657494Y292816D03*
X1679100Y281593D03*
X1657500Y287800D03*
X1657600Y304500D03*
X1679100Y302100D03*
Y304700D03*
Y299500D03*
Y297000D03*
X1664453Y308557D03*
X1654770Y399145D03*
X1652186Y365600D03*
Y360600D03*
X1654809Y401645D03*
X1652186Y354700D03*
Y352100D03*
X1654861Y396637D03*
X1660972Y401447D03*
X1661243Y390364D03*
Y392943D03*
X1660890Y397300D03*
X1660934Y387883D03*
X1664829Y379194D03*
X1664905Y376695D03*
X1667809Y427809D03*
X1667729Y424621D03*
X1668100Y418700D03*
X1678303Y442765D03*
X1667946Y412987D03*
X1681215Y451786D03*
X1673550Y442696D03*
X1684435Y456832D03*
Y459421D03*
X1661470Y456251D03*
X1661522Y453751D03*
X1669076Y438281D03*
X1664762Y438035D03*
X1676304Y449794D03*
X1676287Y447244D03*
X1667588Y434149D03*
X1667649Y430849D03*
X1667462Y440735D03*
X1669962D03*
X1668843Y465060D03*
X1675744Y456200D03*
X1664762Y443735D03*
X1669816Y443953D03*
Y446453D03*
X1673064Y446022D03*
X1679145Y461950D03*
X1673068Y448522D03*
X1669816Y448953D03*
X1661549Y451251D03*
X1681192Y454286D03*
X1668000Y416200D03*
X1673074Y453185D03*
X1675120Y439731D03*
X1681154Y449286D03*
X1664762Y440735D03*
X1676041Y458884D03*
X1660834Y404934D03*
X1655790Y476593D03*
X1651867Y484741D03*
X1651926Y482197D03*
X1671050Y490850D03*
X1687500Y505200D03*
X1672313Y497300D03*
X1687741Y466988D03*
X1705767Y482434D03*
X1698354Y486873D03*
X1687443Y487203D03*
X1681500Y482000D03*
X1699861Y520192D03*
X1697261D03*
X1695658Y486945D03*
X1694410Y499830D03*
X1692120Y501410D03*
X1699900Y512300D03*
X1692443Y487259D03*
X1710594Y519900D03*
X1667674Y467271D03*
X1681650Y510673D03*
X1687606Y500938D03*
X1672265Y473600D03*
X1678001Y473205D03*
X1665047Y467257D03*
X1689943Y487203D03*
X1671050Y483600D03*
Y481000D03*
X1680500Y473325D03*
X1687500Y484000D03*
X1690091Y503995D03*
X1672606Y499820D03*
X1671050Y487000D03*
X1681115Y525218D03*
X1709400Y513000D03*
X1651754Y488025D03*
X1684650Y505200D03*
X1672159Y494042D03*
X1701617Y482706D03*
X1676800Y483800D03*
X1652500Y575600D03*
X1653960Y562930D03*
X1667277Y535221D03*
X1698600Y584800D03*
X1680133Y535489D03*
X1699600Y578100D03*
X1710389Y577787D03*
X1664113Y548380D03*
X1658466D03*
X1661880Y583900D03*
X1686036Y548251D03*
X1677300Y550200D03*
X1680007Y547917D03*
X1669121Y547923D03*
X1708140Y547538D03*
X1697839Y545759D03*
X1709183Y588700D03*
X1700348Y546633D03*
X1680000Y550544D03*
X1658754Y551000D03*
X1669600Y550544D03*
X1685000D03*
X1663754Y551000D03*
X1674600Y550544D03*
X1652669Y582350D03*
Y578350D03*
X1705348Y546633D03*
X1660680Y586750D03*
X1654100Y615790D03*
X1653970Y607340D03*
X1652700Y591300D03*
Y600850D03*
X1662580Y593200D03*
X1661200Y601300D03*
Y607300D03*
X1709950Y592900D03*
X1710000Y595500D03*
Y604500D03*
Y600000D03*
X1701291Y602268D03*
X1699106Y618018D03*
X1658369Y606250D03*
X1652499Y593950D03*
X1660680Y590750D03*
X1658369Y602250D03*
X1652499Y597950D03*
X1714297Y11180D03*
X1756895Y30452D03*
X1723678Y11381D03*
X1756992Y20007D03*
X1763360Y24010D03*
X1730550Y21160D03*
X1721559Y13500D03*
X1730768Y13313D03*
X1763100Y21500D03*
X1768807Y21512D03*
X1753903Y22116D03*
X1749941Y21163D03*
X1741000Y21200D03*
X1741544Y9151D03*
X1752908Y9481D03*
X1744900Y9100D03*
X1755500Y9076D03*
X1759093Y9310D03*
X1761872Y-7220D03*
X1734875Y9238D03*
X1760693Y20045D03*
X1767069Y24010D03*
X1743152Y23197D03*
X1733168Y22312D03*
X1748152Y23197D03*
X1738168Y22312D03*
X1728678Y11381D03*
X1719297Y11180D03*
X1749085Y9177D03*
X1731350Y92140D03*
X1715259Y35602D03*
X1715100Y46100D03*
X1713550Y56000D03*
X1716900Y87900D03*
X1713900D03*
X1750250Y35925D03*
X1753059Y35300D03*
X1750400Y47400D03*
X1745094Y47106D03*
X1732650Y60650D03*
X1735150D03*
Y58150D03*
X1732650D03*
X1757772Y90174D03*
X1757395Y84794D03*
X1760364Y85136D03*
X1720500Y52440D03*
X1748500Y79500D03*
X1757998Y73637D03*
X1775000Y53500D03*
X1720100Y46100D03*
X1742594Y47106D03*
X1748854Y58533D03*
X1746328Y59011D03*
X1717600Y46100D03*
X1755400Y37700D03*
X1736700Y39600D03*
X1727383Y39465D03*
X1717958Y39880D03*
X1752000Y38865D03*
X1724758Y38600D03*
X1720600Y70200D03*
X1733910Y38233D03*
X1757054Y66059D03*
X1758100Y37000D03*
X1749364Y38971D03*
X1743500Y39300D03*
X1768450Y77376D03*
X1765900Y83700D03*
X1754703Y84053D03*
X1771459Y52695D03*
X1733900Y92200D03*
X1725474Y69250D03*
X1766240Y70500D03*
X1760016Y65774D03*
X1771707Y86500D03*
X1746552Y38900D03*
X1767250Y94500D03*
Y89500D03*
X1766333Y59116D03*
X1769250Y70350D03*
X1756895Y34252D03*
X1746550Y35925D03*
X1740598Y39486D03*
X1731183Y39465D03*
X1721758Y39880D03*
X1715100Y70500D03*
X1746491Y95650D03*
X1754600Y109200D03*
X1748425Y119190D03*
X1765015Y119100D03*
X1758100D03*
X1761300D03*
X1767250Y99500D03*
Y104500D03*
X1770850Y109500D03*
X1768886Y156173D03*
X1719250Y179150D03*
X1713596Y175795D03*
X1714189Y159550D03*
X1714528Y190189D03*
X1758650Y158650D03*
X1750189Y159550D03*
X1745689D03*
X1741189D03*
X1727689D03*
X1723189D03*
X1718689D03*
X1732189D03*
X1736689D03*
X1745777Y179574D03*
X1751975Y179374D03*
X1739377D03*
X1733178Y179574D03*
X1758375D03*
X1764673Y179374D03*
X1770973Y179574D03*
X1726700Y179400D03*
X1719000Y190500D03*
X1730400Y195850D03*
X1740900Y198800D03*
X1744000D03*
X1769100Y209700D03*
X1765950Y209600D03*
X1769016Y198872D03*
X1765866Y198772D03*
X1731260Y209600D03*
X1740709D03*
X1756000Y210000D03*
X1753400Y209900D03*
X1743900Y209700D03*
X1728616Y198872D03*
X1753311Y198700D03*
X1756600Y198800D03*
X1731216Y198872D03*
X1719100Y176000D03*
X1749295Y176104D03*
X1723189Y176012D03*
X1733484Y211631D03*
X1746125D03*
X1758725D03*
X1771325D03*
X1738484D03*
X1751125D03*
X1763725D03*
X1727193Y176525D03*
X1744792D03*
X1757390D03*
X1769988D03*
X1732193D03*
X1739792D03*
X1752390D03*
X1764988D03*
X1733563Y196776D03*
X1746082Y196843D03*
X1758668D03*
X1771241Y196841D03*
X1738563Y196776D03*
X1751082Y196843D03*
X1763668D03*
X1763554Y237712D03*
X1762795Y232106D03*
X1772244D03*
X1752554Y237712D03*
X1771451D03*
X1733880Y232810D03*
X1715837Y246178D03*
X1727896Y246175D03*
X1720651Y246141D03*
X1718820Y249032D03*
X1715078Y250231D03*
X1724181Y246159D03*
X1724944Y250324D03*
X1727444D03*
X1771243Y250100D03*
X1729944Y250324D03*
X1768516Y249983D03*
X1768700Y233644D03*
X1739847Y233334D03*
X1736847D03*
X1719080Y232852D03*
X1744603Y232489D03*
X1753347Y232106D03*
X1763300Y250100D03*
X1733900Y237300D03*
X1736400D03*
X1719080Y236152D03*
X1774451Y237712D03*
X1755554D03*
X1760554D03*
X1742398Y234681D03*
X1722251Y250532D03*
X1766077Y232681D03*
X1751900Y249700D03*
X1746900Y249804D03*
X1749462Y232955D03*
X1716037Y444550D03*
X1724590Y444521D03*
X1737150Y450850D03*
X1766100Y447900D03*
X1762992Y447938D03*
X1740963Y448476D03*
X1753543Y448100D03*
X1750393Y448037D03*
X1737795Y448100D03*
X1727620Y444380D03*
X1721990Y444521D03*
X1730996Y442804D03*
X1719317Y441947D03*
X1724369Y441601D03*
X1718587Y444550D03*
X1760767Y450408D03*
X1748169D03*
X1773366D03*
X1755767D03*
X1743169D03*
X1768366D03*
X1714530Y519900D03*
X1716490Y506970D03*
X1722000Y513000D03*
X1742900Y485000D03*
X1734000Y488100D03*
X1755000Y485000D03*
X1748600D03*
X1749396Y493969D03*
X1751868Y494045D03*
X1770325Y490255D03*
X1773500Y472100D03*
X1767300Y472700D03*
X1765325Y490255D03*
X1758500Y493800D03*
X1760900Y472800D03*
X1772459Y467005D03*
X1769309D03*
X1759860D03*
X1756710D03*
X1747262D03*
X1744112D03*
X1734663D03*
X1729200Y519000D03*
X1733830Y502650D03*
X1768900Y521124D03*
X1749090Y513790D03*
X1740400Y496300D03*
X1726600Y519000D03*
X1728700Y502600D03*
X1737300Y500900D03*
X1738180Y503487D03*
X1719089Y472104D03*
X1728700Y470200D03*
X1774200Y512800D03*
X1766100Y521124D03*
X1722347Y471811D03*
X1750800Y516100D03*
X1762715Y521085D03*
X1748125Y496400D03*
X1733639Y500085D03*
X1758575Y496406D03*
X1743125Y496400D03*
X1728639Y500085D03*
X1753575Y496406D03*
X1713600Y513000D03*
X1770325Y487355D03*
X1765325D03*
X1754300Y487855D03*
X1741900Y487755D03*
X1766700Y475655D03*
X1749300Y487855D03*
X1736900Y487755D03*
X1774300Y475055D03*
X1761700Y475655D03*
X1719560Y501770D03*
X1725694Y568814D03*
Y571814D03*
X1767500Y559800D03*
X1738697Y557888D03*
X1738434Y588986D03*
X1736003Y588244D03*
X1772578Y575993D03*
X1756417Y563840D03*
X1754000Y553500D03*
X1746000Y574000D03*
X1724250Y588250D03*
X1756500Y554500D03*
X1743500Y564500D03*
X1759500Y554500D03*
X1718000Y587723D03*
X1756578Y586743D03*
X1767141Y555500D03*
X1730759Y548162D03*
X1733000Y557000D03*
X1722500Y562000D03*
X1742200Y552863D03*
X1749000D03*
X1762595Y576191D03*
X1769000Y576378D03*
X1754897Y578750D03*
X1742381Y585530D03*
X1730814Y568814D03*
X1733000Y560000D03*
X1764300Y570900D03*
X1767455Y571695D03*
X1738216Y548239D03*
X1753807Y548183D03*
X1757478Y548192D03*
X1738498Y554255D03*
X1737958Y560500D03*
X1743200Y567300D03*
X1743100Y561700D03*
X1767000Y563500D03*
X1767529Y566200D03*
X1743000Y574500D03*
X1730774Y579960D03*
X1733368Y579868D03*
X1724899Y584748D03*
X1738088Y551000D03*
X1739500Y586500D03*
X1770719Y573964D03*
X1728245Y585244D03*
X1743000Y570000D03*
X1765300Y574700D03*
X1742381Y588530D03*
X1739179Y592070D03*
X1746052Y614796D03*
X1735000Y621002D03*
X1764912Y618718D03*
X1725133Y614896D03*
X1724092Y618700D03*
X1770600Y600800D03*
X1766400Y599400D03*
X1728341Y614851D03*
X1739211Y596711D03*
X1772158Y610960D03*
X1750399Y603201D03*
X1764823Y613600D03*
X1750739Y618718D03*
X1718008Y592002D03*
X1718037Y597184D03*
X1716950Y603450D03*
X1718037Y594684D03*
X1757319Y606953D03*
X1758550Y604350D03*
X1742509Y595869D03*
X1742381Y591530D03*
X1740270Y594419D03*
X1739714Y604967D03*
X1762062Y592055D03*
X1763500Y599100D03*
X1762062Y589555D03*
X1727843Y597142D03*
X1732443Y592342D03*
Y597142D03*
X1727743Y592342D03*
X1832449Y-8950D03*
X1835500Y-1700D03*
X1835600Y3900D03*
X1804800Y-1500D03*
X1825324Y1000D03*
X1824564Y3441D03*
X1785612Y10729D03*
X1782371Y26832D03*
X1804508Y11858D03*
X1798676Y11726D03*
X1830344Y13397D03*
X1828824Y3699D03*
X1816693Y13331D03*
X1829636Y26680D03*
X1831000Y-16300D03*
X1788421Y8122D03*
X1825870Y21587D03*
X1832900Y10300D03*
X1785366Y8100D03*
X1823300Y21700D03*
X1832842Y13500D03*
X1836700Y-18900D03*
X1819800Y2100D03*
X1813913Y2287D03*
X1816723Y9781D03*
X1808603Y9300D03*
X1823600Y8800D03*
X1809822Y26585D03*
X1807127Y26918D03*
X1795078Y11900D03*
X1790078Y11860D03*
X1804462Y8830D03*
X1799462D03*
X1808100Y21800D03*
X1815150Y26650D03*
X1797700Y21018D03*
X1791500Y26918D03*
X1813795Y12165D03*
X1808795D03*
X1828874Y-13520D03*
X1819837Y21700D03*
X1786865Y22375D03*
X1829888Y10735D03*
X1819800Y35500D03*
X1790700Y34900D03*
X1799774Y34890D03*
X1826414Y35486D03*
X1827100Y81600D03*
X1798454Y82256D03*
X1788216Y59197D03*
X1815637Y54775D03*
X1818396Y54752D03*
X1779750Y36530D03*
X1784341Y64841D03*
X1820457Y39128D03*
X1789356Y38286D03*
X1796100Y68800D03*
X1829580Y38620D03*
X1824130Y39703D03*
X1826900Y40400D03*
X1808444Y37152D03*
X1800000Y80000D03*
X1827000Y87000D03*
X1834300Y41100D03*
X1824240Y83680D03*
X1802119Y56581D03*
X1786341Y63341D03*
X1799438Y44328D03*
X1817186Y39929D03*
X1827000Y94550D03*
X1788200Y93000D03*
Y89000D03*
Y85000D03*
X1808363Y40033D03*
X1803300Y39900D03*
X1817352Y36909D03*
X1812352Y36949D03*
X1797700Y36804D03*
X1792700Y36871D03*
X1794100Y70898D03*
X1776828Y155211D03*
X1818383Y133277D03*
X1815883D03*
X1777000Y115750D03*
X1787500Y155170D03*
X1813118Y127976D03*
X1807509Y128500D03*
X1778000Y120000D03*
X1780720Y153850D03*
X1807166Y147401D03*
X1783252Y109044D03*
X1788448Y98820D03*
X1788648Y101490D03*
X1807745Y104500D03*
X1803400Y114000D03*
X1796059Y104402D03*
X1801366Y151937D03*
X1811348Y143448D03*
X1800264Y143789D03*
X1828340Y149960D03*
X1803058Y143733D03*
X1815348Y143437D03*
X1796500Y120000D03*
X1827150Y97800D03*
X1830316Y102163D03*
X1828960Y153010D03*
X1824990Y103620D03*
X1787373Y120188D03*
X1824509Y143653D03*
X1821348Y143437D03*
X1815026Y121478D03*
X1808226Y136171D03*
X1803509Y128500D03*
X1800792Y122691D03*
X1821350Y98270D03*
X1810100Y114700D03*
X1812743Y104395D03*
X1810245Y104500D03*
X1814900Y116900D03*
X1816418Y127976D03*
X1800000Y132627D03*
X1788000Y129000D03*
X1784750Y124000D03*
X1808313Y111705D03*
X1800420Y148240D03*
X1820648Y155537D03*
X1816348D03*
X1807818Y124179D03*
X1827500Y144900D03*
X1809810Y155858D03*
X1790100Y154000D03*
X1833629Y170807D03*
X1777172Y179374D03*
X1778466Y198772D03*
X1783572Y179574D03*
X1802369Y179374D03*
X1808769Y179574D03*
X1815000Y179300D03*
X1789870Y179374D03*
X1796170Y179574D03*
X1795348Y172037D03*
X1797848D03*
X1792748Y171937D03*
X1821367Y179574D03*
X1827565Y179174D03*
X1833388Y179500D03*
X1821261Y170012D03*
X1824200Y176900D03*
X1787000Y175500D03*
X1834103Y176021D03*
X1778900Y165800D03*
X1785500Y164000D03*
Y168000D03*
X1834400Y216900D03*
X1830415Y196567D03*
X1791150Y209600D03*
X1794300Y209700D03*
X1794216Y198872D03*
X1791066Y198772D03*
X1819457Y198872D03*
X1828700Y198800D03*
X1820349Y209586D03*
X1828950Y209600D03*
X1832274Y209734D03*
X1816266Y198772D03*
X1804166Y198472D03*
X1807751Y209586D03*
X1803072Y209728D03*
X1806821Y198600D03*
X1815670Y209728D03*
X1781700Y209700D03*
X1778550Y209600D03*
X1781616Y198872D03*
X1816125Y169492D03*
X1816348Y163437D03*
X1818500Y159500D03*
X1820648Y163437D03*
X1776325Y211631D03*
X1777587Y176525D03*
X1783925Y211631D03*
X1796526Y212231D03*
X1809125D03*
X1821685Y212161D03*
X1788925Y211631D03*
X1801526Y212231D03*
X1814125D03*
X1826685Y212161D03*
X1790185Y176525D03*
X1802784D03*
X1815382D03*
X1782587D03*
X1795185D03*
X1807784D03*
X1820382D03*
X1783841Y196841D03*
X1776241D03*
X1814041D03*
X1801441D03*
X1809041D03*
X1821682D03*
X1796441D03*
X1788841D03*
X1807440Y165530D03*
X1836100Y179700D03*
X1807440Y169030D03*
Y162030D03*
X1826682Y196841D03*
X1782452Y237712D03*
X1820281Y250498D03*
X1809281D03*
X1801384D03*
X1790383D03*
X1835936Y235604D03*
X1784440Y232938D03*
X1831700Y252272D03*
X1804388Y249904D03*
X1826662Y232191D03*
X1822638Y232106D03*
X1826287Y250000D03*
X1824300Y251800D03*
X1826085Y236034D03*
X1822877Y235852D03*
X1793600Y235100D03*
X1793700Y232500D03*
X1806083Y232584D03*
X1803280Y232611D03*
X1791141Y232106D03*
X1828936Y249900D03*
X1819488Y232106D03*
X1810040D03*
X1800591D03*
X1781693D03*
X1817282Y250498D03*
X1798384D03*
X1779451Y237712D03*
X1793384Y250498D03*
X1812282D03*
X1775590Y448100D03*
X1778740D03*
X1828600Y450100D03*
X1825984Y448030D03*
X1816535Y448300D03*
X1813385Y447945D03*
X1804000Y447900D03*
X1800787Y447943D03*
X1791338Y448400D03*
X1788189Y448300D03*
X1785964Y450408D03*
X1780964D03*
X1836495Y450600D03*
X1823760Y450408D03*
X1811161D03*
X1798563D03*
X1831495Y450600D03*
X1818760Y450408D03*
X1806161D03*
X1793563D03*
X1776695Y512640D03*
X1779700Y472100D03*
X1784525Y491830D03*
X1781907Y467005D03*
X1785057D03*
X1779303Y497246D03*
X1832301Y467005D03*
X1835550Y466870D03*
X1789774Y476403D03*
X1801500Y471055D03*
X1795164Y476406D03*
X1789525Y491830D03*
X1801125D03*
X1796125D03*
X1817325Y481320D03*
X1806600Y471055D03*
X1812325Y481320D03*
X1806975Y491630D03*
X1830220Y479950D03*
X1824960Y473980D03*
X1824125Y491830D03*
X1822852Y467005D03*
X1819702D03*
X1819125Y491830D03*
X1807104Y467005D03*
X1810254D03*
X1811975Y491630D03*
X1797655Y467005D03*
X1794505D03*
X1810508Y515900D03*
X1804000Y498176D03*
X1834540Y519600D03*
X1790250Y522350D03*
X1834100Y523900D03*
X1791113Y496670D03*
X1788045Y496654D03*
X1825700Y514900D03*
X1828100Y516300D03*
X1828000Y513200D03*
X1814852Y519901D03*
X1809700Y506875D03*
X1820400Y501100D03*
X1806076Y523525D03*
X1798883Y515636D03*
X1810200Y513300D03*
X1815200Y501500D03*
X1801600Y515600D03*
X1794100Y521900D03*
X1803900Y491500D03*
X1796153Y514200D03*
X1783400Y522500D03*
X1780838Y522562D03*
X1836396Y481349D03*
X1789300Y520000D03*
X1836600Y521600D03*
X1828200Y519000D03*
X1833700Y497300D03*
X1786000Y522600D03*
X1796400Y498000D03*
X1804500Y526200D03*
X1795200Y525700D03*
X1816800D03*
X1810350Y525650D03*
X1813500Y526500D03*
X1824125Y488930D03*
X1811975Y488730D03*
X1801125Y488930D03*
X1789525D03*
X1819125D03*
X1806975Y488730D03*
X1796125Y488930D03*
X1784525D03*
X1829967Y476927D03*
X1817375Y478320D03*
X1794975Y479300D03*
X1779300Y475055D03*
X1825297Y476927D03*
X1812375Y478320D03*
X1789975Y479300D03*
X1801525Y473955D03*
X1806525D03*
X1784878Y496701D03*
X1825900Y523500D03*
X1779400Y582500D03*
X1818509Y527893D03*
X1829000Y536315D03*
X1792170Y583900D03*
X1783700Y576400D03*
X1798250Y529200D03*
X1810863Y560637D03*
X1816175Y567669D03*
X1785050Y584550D03*
X1792100Y566900D03*
X1816100Y576200D03*
X1816330Y545260D03*
X1816052Y584101D03*
X1809309Y555713D03*
X1831500Y548000D03*
X1835000Y550300D03*
X1781510Y546362D03*
X1786500Y562200D03*
X1783700Y579200D03*
X1828800Y546500D03*
X1828700Y540252D03*
X1828900Y552300D03*
X1834000Y534900D03*
X1811704Y554341D03*
X1807600Y552047D03*
X1806200Y549200D03*
X1786900Y552500D03*
X1801200Y529800D03*
X1806200Y582900D03*
X1780500Y570718D03*
Y568000D03*
X1781000Y565000D03*
X1780394Y561076D03*
X1782300Y555900D03*
X1779500Y579500D03*
X1779000Y585500D03*
X1810387Y571435D03*
X1794000Y568800D03*
X1793320Y557968D03*
X1828700Y569474D03*
X1836281Y589122D03*
X1828800Y575600D03*
X1828875Y563674D03*
X1828824Y557663D03*
X1810385Y568821D03*
X1807958Y565690D03*
X1781300Y537800D03*
X1808057Y573125D03*
Y570125D03*
X1813456Y583500D03*
X1803752Y529301D03*
X1810052Y545103D03*
X1816584Y530542D03*
X1793900Y550100D03*
X1793660Y560570D03*
X1829300Y572900D03*
X1816280Y550400D03*
Y553500D03*
X1792805Y574675D03*
X1812952Y545501D03*
X1794000Y552800D03*
X1811100Y586800D03*
X1816458Y587480D03*
X1829176Y584287D03*
X1779000Y588500D03*
X1793452Y586701D03*
X1831600Y529000D03*
X1832500Y539500D03*
X1788300Y585100D03*
X1791349Y589122D03*
X1832200Y567760D03*
X1831500Y544500D03*
X1831800Y552300D03*
X1809600Y582800D03*
X1793100Y578500D03*
X1816020Y571448D03*
X1812802Y578693D03*
X1812452Y538501D03*
Y533601D03*
X1807852D03*
X1807752Y538501D03*
X1779000Y598900D03*
X1776500Y621200D03*
X1778400Y618900D03*
X1800352Y596101D03*
X1795000Y599600D03*
X1791323Y594030D03*
X1805000Y606500D03*
X1787500Y600500D03*
X1778675Y592224D03*
X1784200Y593924D03*
X1787500Y597791D03*
X1825014Y593695D03*
X1811500Y603500D03*
X1794500Y612500D03*
X1791500Y606500D03*
X1800378Y593527D03*
X1819654Y593803D03*
X1805500Y603100D03*
X1782700Y610900D03*
X1829051Y591299D03*
X1822273Y595046D03*
X1788290Y612006D03*
X1808152Y591601D03*
X1812852Y596401D03*
X1808252D03*
X1812852Y591601D03*
X1837900Y9700D03*
X1837800Y-3600D03*
X1838850Y13160D03*
X1883041Y15814D03*
X1882999Y7383D03*
X1845420Y13310D03*
X1893094Y-10142D03*
X1838100Y3900D03*
X1868286Y12848D03*
X1871163Y13186D03*
X1870600Y25000D03*
X1848322Y12723D03*
X1841289Y21631D03*
X1876792Y18461D03*
X1876881Y22181D03*
X1843426Y9528D03*
X1840400Y9700D03*
X1893081Y-20735D03*
X1893094Y-12642D03*
X1858600Y74300D03*
X1837500Y35700D03*
X1853467Y35000D03*
X1841060Y35540D03*
X1846527Y34435D03*
X1849027Y34426D03*
X1873956Y60299D03*
X1883200Y76600D03*
X1850600Y41348D03*
X1858198Y41108D03*
X1860786Y41200D03*
X1855400Y40800D03*
X1878800Y43207D03*
Y40200D03*
X1878997Y37546D03*
X1889218Y43530D03*
Y53530D03*
X1846800Y95400D03*
X1847000Y86500D03*
X1848000Y56500D03*
X1850500D03*
X1890803Y63189D03*
X1884500Y79300D03*
X1882000D03*
X1895330Y64390D03*
X1877270Y63473D03*
X1889218Y56030D03*
Y61030D03*
Y46030D03*
Y51030D03*
X1880230Y76820D03*
X1879500Y79300D03*
X1880986Y53299D03*
X1868670Y42765D03*
X1878000Y73950D03*
X1848208Y49427D03*
X1896970Y73460D03*
X1867619Y39779D03*
X1895354Y75650D03*
X1842250Y84000D03*
X1849426Y90700D03*
Y95500D03*
X1893961Y73365D03*
X1860995Y84509D03*
X1856873Y91200D03*
X1856778Y87397D03*
X1864208Y87724D03*
X1864195Y84509D03*
X1864153Y91241D03*
X1860815Y91184D03*
X1842250Y90750D03*
X1877103Y60791D03*
X1838500Y40400D03*
X1856333Y34518D03*
X1875100Y51300D03*
X1854250Y138600D03*
X1854115Y131121D03*
X1864904Y114735D03*
X1872254Y138618D03*
X1839667Y151994D03*
X1837090Y149830D03*
X1848100Y134750D03*
X1839941Y156858D03*
X1845469Y135500D03*
X1872340Y147236D03*
X1895800Y149200D03*
X1885400Y147000D03*
X1878550Y99470D03*
X1882550D03*
X1894834Y139286D03*
X1863908Y140992D03*
X1878950Y137400D03*
X1871855Y104188D03*
X1856700Y110167D03*
X1843107Y97988D03*
X1857110Y113600D03*
X1890974Y105600D03*
X1898102Y107325D03*
X1897536Y120510D03*
Y114600D03*
X1874258Y103196D03*
X1885700Y141200D03*
X1862400Y124500D03*
X1851341Y106358D03*
X1857020Y129619D03*
Y126619D03*
X1861015Y130815D03*
X1867280Y135406D03*
X1878096Y152843D03*
X1871521Y153593D03*
X1881324Y153250D03*
X1869000Y153900D03*
X1875425Y152925D03*
X1875600Y156300D03*
X1886050Y151431D03*
X1886299Y153928D03*
X1895673Y151800D03*
X1865577Y124450D03*
X1878753Y139893D03*
X1866606Y109967D03*
X1860969Y136369D03*
Y133769D03*
X1872400Y144619D03*
X1857919Y156123D03*
X1895060Y136099D03*
X1848590Y141360D03*
X1857250Y138600D03*
X1853317Y108197D03*
X1887830Y102227D03*
X1852600Y97500D03*
X1857849Y148079D03*
X1854962Y133613D03*
X1887300Y121500D03*
X1850700Y156000D03*
X1875700Y115700D03*
Y121500D03*
X1881500Y115700D03*
Y121500D03*
Y127300D03*
X1887300D03*
X1875700D03*
X1887300Y115700D03*
X1846663Y153748D03*
X1894855Y142122D03*
X1893640Y147042D03*
X1888639D03*
X1887497Y105444D03*
X1881165Y105561D03*
X1886000Y156700D03*
X1885102Y101134D03*
X1876001Y105438D03*
X1861932Y146431D03*
X1869668Y146750D03*
X1848532Y144360D03*
X1897507Y124450D03*
X1864637Y201861D03*
X1868843Y207920D03*
X1839873Y159358D03*
X1854942Y181655D03*
X1836932Y170486D03*
X1854900Y175900D03*
X1877517Y217988D03*
X1839500Y212700D03*
X1876700Y207600D03*
X1875700Y184800D03*
X1895614Y204785D03*
X1895100Y201770D03*
X1883539Y199813D03*
X1883350Y202410D03*
X1858470Y206335D03*
X1855670Y206430D03*
X1897450Y213951D03*
Y216551D03*
X1882452Y195888D03*
X1877880Y203780D03*
X1863650Y189750D03*
X1893238Y208042D03*
X1857044Y186292D03*
X1863750Y163750D03*
X1868375Y171900D03*
X1846163Y168448D03*
X1886400Y172600D03*
Y170000D03*
X1886200Y161000D03*
X1883930Y176137D03*
X1883800Y179100D03*
X1857400Y175900D03*
X1862000Y177500D03*
X1876832Y173919D03*
X1875066Y175782D03*
X1886800Y210600D03*
X1886952Y213125D03*
X1883800Y213436D03*
X1884340Y217866D03*
X1859604Y213206D03*
X1861497Y211481D03*
X1874236Y213800D03*
X1871708Y213442D03*
X1850876Y212946D03*
X1847699D03*
X1847000Y198600D03*
X1864464Y198466D03*
X1886093Y202184D03*
X1878789Y213663D03*
X1864000Y184900D03*
X1858500Y200100D03*
X1861243Y183100D03*
X1872100Y207900D03*
X1884400Y183700D03*
X1891880Y204370D03*
X1854663Y158248D03*
X1846663D03*
X1886400Y178700D03*
X1883800Y210575D03*
X1854868Y184667D03*
X1836900Y165800D03*
X1889400Y191200D03*
X1896710Y194380D03*
X1847200Y202050D03*
X1840900Y179700D03*
X1845700D03*
X1858686Y180377D03*
X1885465Y166285D03*
X1855000Y167100D03*
X1864170Y211869D03*
X1892791Y200069D03*
X1884000Y188100D03*
X1865100Y174600D03*
X1836900Y232700D03*
X1850723Y219250D03*
X1843449Y244425D03*
X1856874Y219443D03*
X1896529Y235080D03*
X1884651Y234975D03*
X1854374Y248790D03*
X1844444Y224035D03*
X1850220Y253500D03*
X1858420Y253700D03*
X1843600Y239000D03*
X1840300Y239300D03*
X1861605Y253925D03*
X1881900Y224100D03*
X1884400D03*
X1882200Y234400D03*
X1882345Y231837D03*
X1840149Y244425D03*
X1864305Y253825D03*
X1872323Y264167D03*
X1852300Y252000D03*
X1858400Y251200D03*
X1843700Y253400D03*
X1892274Y235080D03*
X1846517Y253500D03*
X1854720Y253700D03*
X1885000Y227500D03*
X1870815Y453022D03*
X1858633Y452803D03*
X1839400Y450440D03*
X1838768Y454120D03*
X1847185Y454368D03*
X1860158Y450322D03*
X1864300Y447900D03*
X1882677Y447930D03*
X1895275Y454422D03*
X1898425Y447930D03*
Y454422D03*
X1844630Y454321D03*
X1878100Y450200D03*
X1859059Y448076D03*
X1872860Y450550D03*
Y447950D03*
X1875900Y453600D03*
X1866050Y451100D03*
X1868015Y452987D03*
X1841630Y454321D03*
X1863137Y452710D03*
X1867500Y447900D03*
X1837300Y472276D03*
X1837200Y525700D03*
X1866688Y517128D03*
X1845330Y466870D03*
X1843000Y505000D03*
X1857480Y466800D03*
X1861300D03*
X1881285Y467049D03*
X1849795Y493379D03*
X1850290Y486610D03*
X1872908Y471338D03*
X1870138Y485732D03*
X1852340Y509140D03*
X1859530Y516430D03*
X1842400Y516800D03*
X1843100Y494100D03*
X1840500D03*
X1843100Y491500D03*
X1840500D03*
Y484650D03*
Y487250D03*
X1842450Y507520D03*
X1896700Y472600D03*
X1896800Y470200D03*
X1894100Y472600D03*
X1894200Y470200D03*
X1864339Y509560D03*
X1843750Y475724D03*
X1840750D03*
X1841900Y498800D03*
X1852719Y487575D03*
Y492575D03*
X1873632Y500904D03*
X1860280Y520200D03*
X1847000Y487500D03*
X1860000Y495500D03*
X1844490Y509230D03*
X1875973Y499838D03*
X1869914Y517225D03*
X1877518Y527560D03*
X1857450Y473654D03*
X1837857Y468630D03*
X1842857D03*
X1868167Y467855D03*
X1863000Y480000D03*
X1859600Y476200D03*
X1876945Y471316D03*
X1877407Y479046D03*
X1855206Y471112D03*
X1842764Y528136D03*
X1838000Y549700D03*
X1837475Y573835D03*
X1837534Y579322D03*
X1838224Y586650D03*
X1889800Y580200D03*
X1878000Y539000D03*
X1861080Y537090D03*
X1870100Y561150D03*
X1854508Y552708D03*
X1858528Y544528D03*
X1857108Y550108D03*
X1875850Y567200D03*
X1857108Y552708D03*
X1840690Y557190D03*
X1878500Y553500D03*
X1858500Y540000D03*
X1852250Y547900D03*
X1858681Y568087D03*
X1879862Y581862D03*
X1896899Y557790D03*
X1845407Y533178D03*
X1868110Y536000D03*
X1878736Y533040D03*
X1864580Y537060D03*
X1852400Y554900D03*
X1869800Y557100D03*
X1878875Y565475D03*
X1897300Y548800D03*
X1855750Y548000D03*
X1882300Y565550D03*
X1885100Y584300D03*
X1873510Y541710D03*
X1840700Y563800D03*
X1848800Y551400D03*
X1848900Y548200D03*
X1854530Y533132D03*
X1859708Y552708D03*
X1856573Y576534D03*
X1857812Y557245D03*
X1842500Y534500D03*
X1844100Y551000D03*
X1848900Y545500D03*
X1878450Y548650D03*
X1870250Y541950D03*
X1896500Y555300D03*
X1879800Y579000D03*
X1858000Y574000D03*
X1870892Y583245D03*
X1874825Y564125D03*
X1859167Y559350D03*
X1894299Y557790D03*
X1895523Y586365D03*
X1844018Y586482D03*
X1858000Y586250D03*
X1866800Y588000D03*
X1875600Y588500D03*
X1856040Y588704D03*
X1837000Y534900D03*
X1839126Y583354D03*
X1847070Y537610D03*
X1896358Y595255D03*
X1868200Y590939D03*
X1848900Y590750D03*
X1845000Y590800D03*
X1900256Y-14760D03*
Y-18911D03*
X1906438Y-15968D03*
X1916078Y-16368D03*
X1903160Y-19416D03*
X1918352Y89300D03*
X1923300Y94300D03*
X1909406Y76790D03*
X1907986Y82393D03*
X1907929Y84793D03*
X1907907Y87223D03*
X1918379Y84788D03*
X1956891Y92513D03*
X1952110Y95513D03*
X1954391Y92513D03*
X1951670Y90363D03*
Y92863D03*
X1951770Y87863D03*
X1954169Y84111D03*
X1954861Y95163D03*
X1949610Y95513D03*
X1949270Y87863D03*
X1949170Y92863D03*
Y90363D03*
X1946670Y87863D03*
X1946570Y92863D03*
Y90363D03*
X1946670Y85363D03*
X1949270D03*
X1951770D03*
X1957361Y95163D03*
X1918113Y93576D03*
X1926890Y73106D03*
X1920300Y68300D03*
X1917600Y66000D03*
X1948472Y80362D03*
X1905501Y79790D03*
X1902796Y79820D03*
X1927918Y126156D03*
X1900100Y145100D03*
X1918210Y96103D03*
X1921199Y140499D03*
X1929711Y155759D03*
X1904136Y140160D03*
X1937000Y150000D03*
X1946500Y104974D03*
X1950934Y143730D03*
X1936187Y144013D03*
X1951700Y141000D03*
X1940700Y136300D03*
X1904215Y142812D03*
X1927810Y123544D03*
X1937900Y153600D03*
X1921264Y153000D03*
X1943752Y137548D03*
X1947078Y139300D03*
X1919484Y149500D03*
X1911961Y153000D03*
X1905092Y150170D03*
X1927000Y152200D03*
X1906414Y118004D03*
X1906467Y115305D03*
X1919702Y125920D03*
X1919195Y134396D03*
X1926952Y156049D03*
X1952726Y102950D03*
X1914500Y113300D03*
X1944609Y149184D03*
X1944600Y151700D03*
X1932998Y119438D03*
X1923329Y99475D03*
X1947000Y142600D03*
X1905540Y153000D03*
X1919702Y128501D03*
X1926892Y121203D03*
X1923837Y118800D03*
X1937728Y99441D03*
X1949389Y152083D03*
X1934000Y147100D03*
X1925358Y140685D03*
X1929756Y131037D03*
X1906871Y106049D03*
X1911231Y137097D03*
X1908715Y104512D03*
X1912100Y142600D03*
X1915030Y147250D03*
X1911440Y128840D03*
X1952440Y98520D03*
X1942637Y100877D03*
X1914152Y115928D03*
X1950983Y147344D03*
X1928100Y136078D03*
X1934544Y127957D03*
X1933914Y96040D03*
X1946770Y98150D03*
X1914690Y152580D03*
X1929736Y128337D03*
X1899855Y142122D03*
X1909216Y142812D03*
X1908327Y149353D03*
X1923800Y151000D03*
X1916310Y149676D03*
X1919514Y131701D03*
X1943660Y98180D03*
X1918002Y98902D03*
X1934256Y99459D03*
X1913392Y149381D03*
X1934100Y193400D03*
X1927064Y207564D03*
X1938400Y178200D03*
X1932837Y186700D03*
X1918489Y212513D03*
X1903917Y201472D03*
X1935600Y198700D03*
X1950981Y191218D03*
X1939200Y194300D03*
X1930500Y209464D03*
X1943500Y209500D03*
X1925000Y192000D03*
X1904042Y204895D03*
X1931483Y199350D03*
X1901100Y194200D03*
X1921500Y193600D03*
X1917024D03*
X1917568Y201215D03*
X1910123Y217349D03*
X1957334Y201269D03*
X1939300Y204300D03*
X1953200Y195530D03*
X1937100Y206800D03*
X1908967Y201609D03*
X1909186Y211906D03*
X1944500Y183900D03*
X1903524Y208156D03*
X1905074Y198163D03*
X1943200Y214800D03*
X1928400Y212500D03*
X1926000Y212400D03*
X1933898Y216707D03*
X1945156Y160236D03*
X1950994Y173745D03*
X1939316Y173600D03*
X1931639Y178396D03*
X1939550Y165600D03*
X1940647Y161600D03*
X1928218Y175443D03*
X1928249Y178179D03*
X1930300Y170147D03*
X1944550Y176450D03*
X1950981Y168064D03*
X1903150Y217250D03*
X1944300Y190200D03*
X1952717Y198614D03*
X1944611Y193400D03*
X1956901Y215241D03*
X1935600Y176300D03*
X1943217Y217645D03*
X1956901Y218391D03*
X1900740Y178720D03*
X1900700Y172990D03*
Y167290D03*
X1906440Y178720D03*
X1906500Y173100D03*
X1906400Y167290D03*
X1912190Y178870D03*
X1912230Y167330D03*
Y173030D03*
X1940500Y157600D03*
X1925400Y196300D03*
X1909438Y204307D03*
X1929700Y163400D03*
X1940240Y169970D03*
X1931065Y175520D03*
X1927500Y170400D03*
X1929000Y158600D03*
X1939400Y198400D03*
X1929090Y193190D03*
X1909421Y208805D03*
X1918143Y219848D03*
X1925835Y233735D03*
X1926100Y231200D03*
X1944463Y228458D03*
X1910340Y220741D03*
X1902907Y231294D03*
X1903032Y228368D03*
X1944925Y226001D03*
X1946105Y230344D03*
X1902909Y223195D03*
X1943517Y223637D03*
X1943800Y241800D03*
X1943900Y238500D03*
X1934750Y242700D03*
Y240300D03*
X1925600Y242700D03*
X1899816Y235035D03*
X1943217Y221154D03*
X1903020Y225776D03*
X1929000Y445800D03*
X1910500Y435600D03*
X1927100Y436200D03*
X1930100D03*
X1914173Y448200D03*
X1917700Y435600D03*
X1920700D03*
X1914700D03*
X1917322Y447930D03*
X1920472D03*
X1942000Y440500D03*
X1904724Y447930D03*
X1901574Y454422D03*
X1935300Y450600D03*
X1939845Y445055D03*
X1904724Y454422D03*
X1901574Y447930D03*
X1907500Y435600D03*
X1911023Y448400D03*
X1907874Y454422D03*
Y448400D03*
X1937430Y464785D03*
X1933100Y436200D03*
X1957212Y479521D03*
X1957100Y502990D03*
X1955790Y499790D03*
X1947380Y482450D03*
X1928620Y482710D03*
X1919230Y483430D03*
X1899100Y472600D03*
X1899200Y470200D03*
X1945000Y474000D03*
X1909800Y510700D03*
X1915100Y480050D03*
X1905010Y479410D03*
X1939000Y479400D03*
X1952500Y508000D03*
X1959260Y506010D03*
X1938410Y490650D03*
X1947550Y485350D03*
X1956500Y507470D03*
X1910500Y472000D03*
Y475000D03*
X1904200Y472700D03*
X1901700Y472600D03*
X1904300Y470300D03*
X1901800Y470200D03*
X1938300Y486250D03*
X1957250Y512050D03*
X1937300Y508900D03*
X1919510Y475100D03*
Y479200D03*
X1939000Y476600D03*
X1956300Y515900D03*
X1908300Y514500D03*
X1942328Y508712D03*
X1912800Y510700D03*
X1956606Y526671D03*
X1919000Y487210D03*
X1929480Y472880D03*
X1959300Y518000D03*
X1957063Y474769D03*
X1948200Y474300D03*
X1900890Y477200D03*
X1914750Y544863D03*
X1915050Y547900D03*
X1907200Y551600D03*
X1951900Y534900D03*
X1900250Y533700D03*
X1898850Y545250D03*
X1899800Y548100D03*
X1926600Y559500D03*
X1923600Y565100D03*
X1923000Y568700D03*
X1959120Y547050D03*
X1958940Y538890D03*
X1911000Y556700D03*
X1939800Y543700D03*
X1922500Y546700D03*
X1934600Y561900D03*
X1922000Y543750D03*
X1956191Y548700D03*
X1958500Y535000D03*
X1907500Y545600D03*
X1905000Y533900D03*
X1906050Y569100D03*
X1923600Y554200D03*
X1955400Y530500D03*
X1923600Y572300D03*
X1908400Y556800D03*
X1915593Y576807D03*
X1953500Y551900D03*
X1943300Y535700D03*
X1921244Y533750D03*
X1900729Y569557D03*
X1913800Y555500D03*
X1937250Y578200D03*
X1934400Y569400D03*
X1937200Y545100D03*
X1937300Y541600D03*
X1934200Y573700D03*
Y577700D03*
X1939700Y540900D03*
X1935400Y583000D03*
X1940800Y537300D03*
X1945900Y549900D03*
X1932800Y564300D03*
X1935400Y550800D03*
X1936900Y568000D03*
X1937800Y549700D03*
X1923500Y579500D03*
X1939800Y546300D03*
X1948100Y538700D03*
X1923400Y583000D03*
X1923600Y575500D03*
X1921800Y586100D03*
X1918880Y586460D03*
X1932390Y590100D03*
X1936770Y607210D03*
X1938130Y601480D03*
X1938000Y597320D03*
X1937870Y594480D03*
X1923504Y592500D03*
X1911750Y592800D03*
X1927000Y614500D03*
X1914700Y594600D03*
X1930500Y618900D03*
Y616100D03*
X1906200Y607800D03*
X1916050Y604450D03*
X1924000Y611391D03*
X1922900Y604450D03*
X1919900Y604550D03*
X1959400Y601100D03*
X1934350Y609250D03*
X1968179Y77969D03*
X1965679D03*
Y75369D03*
X1968179D03*
X1965679Y82969D03*
Y80469D03*
X1968179D03*
X1966212Y72897D03*
X1970679Y75369D03*
Y80469D03*
Y77969D03*
X1962800Y143700D03*
X1971200Y152500D03*
X1965400Y149700D03*
X1973328Y147303D03*
X1963400Y141100D03*
X1967580Y104721D03*
X1973004Y143120D03*
X1964382Y147318D03*
X1962800Y149300D03*
X1966700Y152400D03*
X1961472Y165760D03*
X1963300Y191000D03*
X1967817Y201029D03*
X1965900Y184600D03*
X1965057Y176447D03*
X1966542Y179606D03*
X1965973Y166190D03*
X1972598Y165236D03*
X1963092Y167936D03*
X1970270Y474640D03*
X1968870Y481710D03*
X1970500Y502720D03*
X1963500Y521000D03*
X1967200Y521600D03*
X1964270Y511410D03*
X1968375Y509375D03*
X1964890Y534940D03*
X1961500Y561700D03*
Y582700D03*
X1972700Y552700D03*
X1963000Y573000D03*
X1963097Y551000D03*
X1972700Y576400D03*
Y549950D03*
X1972800Y536800D03*
Y565200D03*
X1962950Y566600D03*
X1961715Y555639D03*
X1962500Y578500D03*
X1961700Y616700D03*
Y619500D03*
X1965400D03*
X1973000Y597200D03*
X1961771Y591744D03*
X1963300Y612800D03*
G54D321*
X1938249Y80902D03*
G54D142*
X667019Y318748D03*
G54D40*
X39500Y-975D03*
X8100Y503800D03*
X666100Y263000D03*
X1357000Y60500D03*
X1414560Y543955D03*
X1558200Y605500D03*
G54D151*
X710650Y59390D03*
Y57421D03*
Y55453D03*
Y53484D03*
Y51516D03*
Y49547D03*
Y47579D03*
Y45610D03*
Y43642D03*
Y61358D03*
Y545640D03*
Y543671D03*
Y541703D03*
Y539734D03*
Y537766D03*
Y535797D03*
Y533829D03*
Y531860D03*
Y529892D03*
Y547608D03*
X1370850Y119340D03*
Y117371D03*
Y115403D03*
Y113434D03*
Y111466D03*
Y109497D03*
Y107529D03*
Y105560D03*
Y103592D03*
Y121308D03*
X1365650Y526003D03*
Y524034D03*
Y522066D03*
Y520097D03*
Y518129D03*
Y516160D03*
Y514192D03*
Y529940D03*
Y527971D03*
Y531908D03*
G54D241*
X1478330Y608784D03*
X1513868Y610052D03*
G54D313*
X1881500Y121500D03*
G54D250*
X1560365Y243947D03*
X1585165D03*
G54D133*
X657250Y-14930D03*
Y3070D03*
X652130Y-14930D03*
Y3070D03*
X654690Y-14930D03*
Y3070D03*
X649570Y-14930D03*
Y3070D03*
X1274050Y109670D03*
Y127670D03*
X1268930Y109670D03*
Y127670D03*
X1271490Y109670D03*
Y127670D03*
X1266370Y109670D03*
Y127670D03*
G54D322*
X1943369Y80902D03*
G54D331*
X1953740Y217834D03*
Y215866D03*
Y213897D03*
Y233582D03*
Y231614D03*
Y225708D03*
Y223740D03*
X1960433Y217834D03*
Y215866D03*
Y233582D03*
Y231614D03*
Y229645D03*
Y227677D03*
Y225708D03*
Y223740D03*
Y221771D03*
Y219803D03*
G54D115*
X280143Y203154D03*
X283523Y201203D03*
X280143Y199254D03*
X286903D03*
X283523Y197303D03*
X290283D03*
X417978Y204390D03*
X421358Y202441D03*
X929751Y203154D03*
X933131Y201203D03*
X929751Y199254D03*
X936511D03*
X933131Y197303D03*
X939891D03*
X1067586Y204390D03*
X1070966Y202441D03*
G54D22*
X-16000Y534300D03*
Y570300D03*
X21652Y8515D03*
X25152D03*
X25558Y-8431D03*
X22058D03*
X46550Y20464D03*
X31907Y-19337D03*
X35407D03*
X31899Y-14906D03*
X35399D03*
X31599Y17909D03*
X28099D03*
X9100Y22344D03*
X12600D03*
X20100D03*
X16600D03*
X28099Y14409D03*
X31599D03*
X45113Y-16137D03*
X20411Y50456D03*
X16911D03*
X-1000Y78900D03*
X2500D03*
X21347Y81785D03*
X17847D03*
X9823Y53541D03*
X13323D03*
X20425Y53711D03*
X16925D03*
X2200Y75650D03*
X-1300D03*
X2170Y51080D03*
X5670D03*
X4742Y270027D03*
X1242D03*
X9450Y451000D03*
X5950D03*
X33678Y426855D03*
X30178D03*
X30305Y436582D03*
X33805D03*
X28500Y500500D03*
X25000D03*
X-569Y488479D03*
X-4069D03*
X6353Y488492D03*
X2853D03*
X28500Y492500D03*
X25000D03*
X-13400Y499300D03*
X-9900D03*
X-13400Y502800D03*
X-9900D03*
X-10500Y506300D03*
X-14000D03*
X-10500Y512300D03*
X-14000D03*
X-10500Y509300D03*
X-14000D03*
X28500Y496500D03*
X25000D03*
X-1093Y467071D03*
X2407D03*
X-12500Y534300D03*
Y570300D03*
X10200Y528800D03*
X6700D03*
X0D03*
X3500D03*
X-7746Y587765D03*
X-11246D03*
X10780Y559064D03*
X7280D03*
X-4800Y564000D03*
X-8300D03*
X-1000D03*
X2500D03*
X10000D03*
X6500D03*
X30422Y562532D03*
X33922D03*
X24265Y529069D03*
X27765D03*
X-3800Y528800D03*
X-7300D03*
X-7483Y551374D03*
X-10983D03*
X-10842Y554878D03*
X-7342D03*
X8678Y593224D03*
X5178D03*
X-9785Y590965D03*
X-6285D03*
X53704Y8216D03*
X57204D03*
X50050Y20464D03*
X63712Y2888D03*
X60212D03*
X57204Y4716D03*
X53704D03*
X58389Y-13808D03*
X54889D03*
X58389Y-10601D03*
X54889D03*
X48613Y-16137D03*
X58200Y95000D03*
X54700D03*
X58200Y91500D03*
X54700D03*
X101000Y118000D03*
X104500D03*
Y121500D03*
X101000D03*
X52100Y148500D03*
X55600D03*
X58200Y105500D03*
X54700D03*
X58200Y112500D03*
X54700D03*
X58200Y116000D03*
X54700D03*
X58200Y140500D03*
X54700D03*
X58200Y133500D03*
X54700D03*
X58200Y137000D03*
X54700D03*
X58200Y144000D03*
X54700D03*
X58200Y126500D03*
X54700D03*
X58200Y123000D03*
X54700D03*
X58200Y130000D03*
X54700D03*
X58200Y119500D03*
X54700D03*
X58200Y109000D03*
X54700D03*
X58200Y102000D03*
X54700D03*
X58200Y98500D03*
X54700D03*
X72700Y171900D03*
X69200D03*
X48300Y157500D03*
X51800D03*
X91600Y162300D03*
X95100D03*
X63600Y163400D03*
X67100D03*
X56500Y200500D03*
X53000D03*
X56500Y204000D03*
X53000D03*
X94250Y267122D03*
X90750D03*
X94278Y270852D03*
X90778D03*
X93700Y262300D03*
X97200D03*
X62500Y275500D03*
X66000D03*
X59500D03*
X56000D03*
X93858Y240300D03*
X97358D03*
X106698Y219572D03*
X108462Y316200D03*
X98500Y298500D03*
X102000D03*
X55500Y334500D03*
X59000D03*
X91000Y297000D03*
X87500D03*
Y300500D03*
X91000D03*
X87500Y289000D03*
X91000D03*
Y285300D03*
X87500D03*
Y293500D03*
X91000D03*
X87500Y313500D03*
X91000D03*
X87500Y309500D03*
X91000D03*
Y306000D03*
X87500D03*
X73000Y324500D03*
X76500D03*
X55500Y323500D03*
X59000D03*
Y327000D03*
X55500D03*
X84650Y338700D03*
X81150D03*
X59000Y280500D03*
X62500D03*
X91000Y282200D03*
X87500D03*
X81700Y343900D03*
X85200D03*
X58000Y351500D03*
X54500D03*
Y348400D03*
X58000D03*
X68500Y388600D03*
X72000D03*
X61300Y392100D03*
X57800D03*
X54500Y354600D03*
X58000D03*
X85200Y347000D03*
X81700D03*
X68500Y385500D03*
X72000D03*
X61000Y385400D03*
X64500D03*
X59900Y388600D03*
X63400D03*
X74648Y461201D03*
X71148D03*
X78100Y465511D03*
X74600D03*
X123892Y13078D03*
X120392D03*
X123892Y50878D03*
X120392D03*
X123907Y87248D03*
X120407D03*
X159700Y199100D03*
X156200D03*
X159700Y195600D03*
X156200D03*
X123100Y209200D03*
X126600D03*
X120179Y210345D03*
X116679D03*
X134124Y209533D03*
X130624D03*
X150400Y208300D03*
X153900D03*
X110088Y252322D03*
X113588D03*
X110198Y219572D03*
X133924Y273300D03*
X130424D03*
X124124Y272533D03*
X127624D03*
X117000Y263500D03*
X113500D03*
X113100Y266763D03*
X116600D03*
X133788Y269786D03*
X130288D03*
X153200Y272900D03*
X156700D03*
X113100Y234713D03*
X116600D03*
X134324Y241333D03*
X130824D03*
X116900Y231450D03*
X113400D03*
X134378Y237702D03*
X130878D03*
X120177Y242977D03*
X116677D03*
X123624Y240533D03*
X127124D03*
X149710Y240512D03*
X153210D03*
X110817Y283595D03*
X114317D03*
X111962Y316200D03*
X113299Y295373D03*
X109799D03*
X111000Y301000D03*
X114500D03*
X134250Y302000D03*
X130750D03*
X134519Y337550D03*
X131019D03*
X121519Y336550D03*
X125019D03*
X134250Y334000D03*
X130750D03*
X113100Y330563D03*
X116600D03*
X123624Y304533D03*
X127124D03*
X134124Y305533D03*
X130624D03*
X117000Y327300D03*
X113500D03*
X150600Y306100D03*
X154100D03*
X116995Y338517D03*
X113495D03*
X149909Y337400D03*
X153409D03*
X109866Y348586D03*
X113366D03*
X113200Y402500D03*
X116700D03*
X110120Y378710D03*
X113620D03*
X114500Y360500D03*
X111000D03*
Y363700D03*
X114500D03*
X134250Y365900D03*
X130750D03*
X123871Y368603D03*
X127371D03*
X134369Y369241D03*
X130869D03*
X147710Y369400D03*
X151210D03*
X117020Y392130D03*
X113520D03*
X132111Y402698D03*
X128611D03*
X132131Y399498D03*
X128631D03*
X151343Y418959D03*
X154843D03*
X151314Y422658D03*
X154814D03*
X163375Y404446D03*
X159875D03*
X163375Y407446D03*
X159875D03*
X116600Y414700D03*
X113100D03*
X116600Y411700D03*
X113100D03*
X116700Y408600D03*
X113200D03*
X116700Y405500D03*
X113200D03*
X123792Y507300D03*
X120292D03*
X123492Y551400D03*
X119992D03*
X123692Y589200D03*
X120192D03*
X449100Y273300D03*
X445600D03*
X432000Y268000D03*
X428500D03*
X461500Y300500D03*
X458000D03*
X461400Y287500D03*
X457900D03*
X461400Y290500D03*
X457900D03*
X457248Y281341D03*
X460748D03*
X458000Y303500D03*
X461500D03*
Y297500D03*
X458000D03*
X461400Y284500D03*
X457900D03*
X461300Y293700D03*
X457800D03*
X595500Y102000D03*
X599000D03*
X655500Y25500D03*
X652000D03*
X660893Y35488D03*
X657393D03*
X607500Y120200D03*
X611000D03*
Y113700D03*
X607500D03*
X611000Y116700D03*
X607500D03*
Y110200D03*
X611000D03*
X661005Y134450D03*
X657505D03*
X661005Y137650D03*
X657505D03*
X640566Y278324D03*
X644066D03*
X649500Y275300D03*
X646000D03*
Y265000D03*
X649500D03*
Y272000D03*
X646000D03*
X650000Y268300D03*
X646500D03*
X636800Y262500D03*
X640300D03*
X640500Y302000D03*
X644000D03*
X640500Y322000D03*
X644000D03*
X640500Y327000D03*
X644000D03*
X640500Y337000D03*
X644000D03*
X640500Y332000D03*
X644000D03*
X640500Y317000D03*
X644000D03*
X640500Y307000D03*
X644000D03*
X640500Y312000D03*
X644000D03*
X625500Y469159D03*
X622000D03*
X616300Y466000D03*
X612800D03*
X615834Y469559D03*
X612334D03*
X616034Y472759D03*
X612534D03*
X625500D03*
X622000D03*
X632930Y492550D03*
X629430D03*
X625430D03*
X621930D03*
X655900Y587500D03*
X659400D03*
X659500Y591500D03*
X656000D03*
X683900Y21500D03*
X687400D03*
X673850Y27300D03*
X677350D03*
X687000Y14500D03*
X683500D03*
X687000Y11000D03*
X683500D03*
X696750Y31000D03*
X693250D03*
X679300Y30800D03*
X675800D03*
X686900Y17900D03*
X683400D03*
X679300Y34200D03*
X675800D03*
X667650Y34500D03*
X664150D03*
X698137Y69515D03*
X694637D03*
X696750Y34500D03*
X693250D03*
X688416Y69515D03*
X684916D03*
X718000Y203100D03*
X714500D03*
X714400Y207050D03*
X717900D03*
X722300Y218100D03*
X718800D03*
X697267Y200989D03*
X700767D03*
X684050Y278000D03*
X687550D03*
X687520Y257570D03*
X684020D03*
X687500Y251307D03*
X684000D03*
X703700Y258900D03*
X707200D03*
X688250Y264000D03*
X684750D03*
X684050Y260597D03*
X687550D03*
X707000Y262000D03*
X703500D03*
Y265500D03*
X707000D03*
X687550Y274500D03*
X684050D03*
X688250Y271000D03*
X684750D03*
X688250Y267500D03*
X684750D03*
X712300Y227500D03*
X715800D03*
X709000Y229000D03*
X705500D03*
X698000D03*
X701500D03*
X673713Y227609D03*
X670213D03*
X687500Y254470D03*
X684000D03*
X694000Y305500D03*
X690500D03*
X694000Y300500D03*
X690500D03*
X694000Y330500D03*
X690500D03*
X694000Y335500D03*
X690500D03*
X694000Y325500D03*
X690500D03*
X713050Y304375D03*
X709550D03*
X717300Y300700D03*
X720800D03*
X694000Y320500D03*
X690500D03*
X701000Y315500D03*
X697500D03*
X701000Y310500D03*
X697500D03*
X687556Y295292D03*
X684056D03*
X677124Y295168D03*
X680624D03*
X709550Y301275D03*
X713050D03*
X717300Y297500D03*
X720800D03*
X709550Y297975D03*
X713050D03*
X706662Y287275D03*
X710162D03*
X706662Y290775D03*
X710162D03*
X669200Y295000D03*
X665700D03*
X669000Y290200D03*
X665500D03*
X678772Y359140D03*
X682272D03*
X682150Y521600D03*
X678650D03*
X675250Y512500D03*
X671750D03*
X696750Y521000D03*
X693250D03*
X696750Y517000D03*
X693250D03*
X697500Y555750D03*
X694000D03*
X708155Y567556D03*
X704655D03*
X708153Y570862D03*
X704653D03*
X686500Y587800D03*
X690000D03*
X689500Y555750D03*
X686000D03*
X686500Y578500D03*
X683000D03*
X686599Y573493D03*
X683099D03*
X689950Y591000D03*
X686450D03*
X674380Y591560D03*
X677880D03*
X773500Y13078D03*
X770000D03*
X773500Y50878D03*
X770000D03*
X773500Y89000D03*
X770000D03*
X772732Y209533D03*
X776232D03*
X783732D03*
X780232D03*
X736000Y250500D03*
X739500D03*
X783115Y269655D03*
X779615D03*
X772519Y272931D03*
X776019D03*
X767000Y264400D03*
X763500D03*
X763232Y267610D03*
X766732D03*
X783485Y240623D03*
X779985D03*
X784358Y237423D03*
X780858D03*
X772351Y240966D03*
X775851D03*
X737000Y255000D03*
X733500D03*
X763250Y235500D03*
X766750D03*
X766800Y232000D03*
X763300D03*
X783045Y272906D03*
X779545D03*
X758917Y316392D03*
X762417D03*
X737750Y292500D03*
X741250D03*
X772870Y304000D03*
X776370D03*
X783211Y301964D03*
X779711D03*
X766900Y295800D03*
X763400D03*
X763232Y299033D03*
X766732D03*
X772732Y337533D03*
X776232D03*
X766250Y327608D03*
X762750D03*
X763200Y331900D03*
X766700D03*
X783286Y305173D03*
X779786D03*
X784765Y334046D03*
X781265D03*
X783732Y337533D03*
X780232D03*
X758952Y380738D03*
X762452D03*
X783194Y366012D03*
X779694D03*
X783182Y369533D03*
X779682D03*
X772982Y369033D03*
X776482D03*
X766800Y359800D03*
X763300D03*
X763232Y363033D03*
X766732D03*
X766300Y393400D03*
X762800D03*
X784486Y401784D03*
X780986D03*
X784520Y398509D03*
X781020D03*
X773400Y512800D03*
X769900D03*
X773100Y551400D03*
X769600D03*
X773300Y589200D03*
X769800D03*
X810700Y195600D03*
X807200D03*
X810700Y199100D03*
X807200D03*
X799850Y207600D03*
X803350D03*
X803100Y241000D03*
X806600D03*
X802100Y273000D03*
X805600D03*
X801300Y305000D03*
X804800D03*
X801800Y336400D03*
X805300D03*
X802208Y367560D03*
X805708D03*
X807000Y420000D03*
X803500D03*
X807000Y417000D03*
X803500D03*
X815500Y404000D03*
X812000D03*
X815500Y407500D03*
X812000D03*
X1081700Y268000D03*
X1078200D03*
X1105175Y277317D03*
X1101675D03*
X1107000Y302500D03*
X1110500D03*
Y284500D03*
X1107000D03*
X1110500Y295000D03*
X1107000D03*
X1110500Y299000D03*
X1107000D03*
X1110500Y288000D03*
X1107000D03*
X1110500Y291500D03*
X1107000D03*
X1106856Y281341D03*
X1110356D03*
X1109840Y322680D03*
X1106340D03*
X1267100Y134500D03*
X1270600D03*
X1274500Y138000D03*
X1278000D03*
Y141000D03*
X1274500D03*
X1255400Y113917D03*
X1251900D03*
X1255400Y116917D03*
X1251900D03*
Y110417D03*
X1255400D03*
X1251900Y120417D03*
X1255400D03*
X1278000Y134500D03*
X1274500D03*
X1267100Y138000D03*
X1270600D03*
X1246970Y137547D03*
X1250470D03*
X1254400Y125400D03*
X1250900D03*
X1268250Y461504D03*
X1271750D03*
X1275250D03*
X1271750D03*
X1277750Y482500D03*
Y479000D03*
Y474000D03*
Y487500D03*
X1268250Y466204D03*
X1271750D03*
X1275250D03*
X1271750D03*
X1274250Y474000D03*
X1277750D03*
X1274250Y479000D03*
X1277750D03*
X1274250Y482500D03*
X1277750D03*
X1274250Y487500D03*
X1277750D03*
X1258750Y490500D03*
X1262250D03*
X1265750D03*
X1262250D03*
X1258750Y485500D03*
X1262250D03*
X1265750D03*
X1262250D03*
X1260930Y474540D03*
X1264430D03*
X1260930Y469540D03*
X1264430D03*
X1267930Y474540D03*
X1264430D03*
X1267930Y469540D03*
X1264430D03*
X1340090Y7970D03*
X1330500Y80800D03*
X1334000D03*
X1340000Y86500D03*
X1336500D03*
X1334000Y77800D03*
X1330500D03*
X1334000Y68000D03*
X1330500D03*
X1334000Y55000D03*
X1330500D03*
Y64500D03*
X1334000D03*
X1330500Y61000D03*
X1334000D03*
X1317384Y81896D03*
X1313884D03*
X1319000Y95000D03*
X1315500D03*
X1325500D03*
X1322000D03*
X1332000Y95100D03*
X1328500D03*
X1336500Y83500D03*
X1340000D03*
X1334000Y74500D03*
X1330500D03*
X1334000Y71500D03*
X1330500D03*
X1334000Y58000D03*
X1330500D03*
X1333500Y40700D03*
X1330000D03*
X1330500Y51900D03*
X1334000D03*
X1341757Y96489D03*
X1340800Y413500D03*
X1337300D03*
X1342500Y419000D03*
X1314086Y462030D03*
X1310586D03*
X1307086D03*
X1310586D03*
X1332022Y464337D03*
X1335522D03*
X1339022D03*
X1335522D03*
X1338508Y510187D03*
X1335008D03*
X1330750Y501000D03*
X1327250D03*
X1307130Y466600D03*
X1310630D03*
X1314130D03*
X1310630D03*
X1332022Y469337D03*
X1335522D03*
X1281250Y482500D03*
Y479000D03*
Y474000D03*
Y487500D03*
X1339022Y469337D03*
X1335522D03*
X1324863Y477492D03*
X1328363D03*
X1324963Y472592D03*
X1328463D03*
X1331863Y477492D03*
X1328363D03*
X1331963Y472592D03*
X1328463D03*
X1341000Y540050D03*
X1343590Y7970D03*
X1372989Y8876D03*
X1369489D03*
X1363089Y8376D03*
X1366589D03*
X1362985Y11633D03*
X1366485D03*
X1381458Y-13901D03*
X1384958D03*
X1362273Y-20349D03*
X1365773D03*
X1386727Y4966D03*
X1383227D03*
X1382934Y-17458D03*
X1379434D03*
X1349944Y46449D03*
X1346444D03*
X1378000Y58500D03*
X1374500D03*
X1378000Y50500D03*
X1374500D03*
X1384300Y43900D03*
X1387800D03*
X1353040Y85780D03*
X1349540D03*
X1357000Y92340D03*
X1353500D03*
X1357000Y89140D03*
X1353500D03*
X1374400Y40200D03*
X1370900D03*
X1363400D03*
X1366900D03*
X1378000Y54500D03*
X1374500D03*
X1370820Y43895D03*
X1374320D03*
X1345257Y96489D03*
X1357700Y129450D03*
X1354200D03*
X1349700D03*
X1346200D03*
X1393200Y391745D03*
X1389700D03*
X1386100Y372776D03*
X1382600D03*
X1365000Y369139D03*
X1368500D03*
X1350800Y370500D03*
X1347300D03*
X1382933Y375976D03*
X1386433D03*
X1376200Y399100D03*
X1372700D03*
X1365707Y399068D03*
X1369207D03*
X1392200Y394845D03*
X1388700D03*
X1398280Y388701D03*
X1394780D03*
X1346000Y419000D03*
X1358000Y501800D03*
X1354500D03*
X1351700Y502200D03*
X1348200D03*
X1366500Y500500D03*
X1363000D03*
X1351700Y499000D03*
X1348200D03*
X1388986Y578365D03*
X1385486D03*
X1352500Y540050D03*
X1349000D03*
X1380420Y548730D03*
X1383920D03*
X1344500Y540050D03*
X1366484Y553447D03*
X1369984D03*
X1366534Y556907D03*
X1370034D03*
X1385317Y564894D03*
X1388817D03*
X1381685Y585222D03*
X1385185D03*
X1378400Y587056D03*
X1374900D03*
X1367400D03*
X1370900D03*
X1393735Y551044D03*
X1397235D03*
X1386250Y595500D03*
X1389750D03*
X1366791Y590313D03*
X1370291D03*
X1368200Y619200D03*
X1371700D03*
X1378200D03*
X1374700D03*
X1389750Y592000D03*
X1386250D03*
X1460631Y252416D03*
X1457131D03*
X1448839Y255160D03*
X1445339D03*
X1454500Y373000D03*
X1451000D03*
X1457569Y414166D03*
X1454069D03*
X1457569Y410666D03*
X1454069D03*
X1454500Y448000D03*
X1451000D03*
X1439000Y442500D03*
X1435500D03*
X1454500Y437000D03*
X1451000D03*
X1454500Y442500D03*
X1451000D03*
X1439000Y437000D03*
X1435500D03*
X1439000Y448000D03*
X1435500D03*
X1439000Y453500D03*
X1435500D03*
X1454500Y431500D03*
X1451000D03*
X1456100Y503000D03*
X1459600D03*
X1456100Y506000D03*
X1459600D03*
Y509000D03*
X1456100D03*
X1436060Y544955D03*
X1432560D03*
X1423140Y559233D03*
X1426640D03*
X1416272Y559180D03*
X1419772D03*
X1436000Y551500D03*
X1432500D03*
X1436100Y538400D03*
X1432600D03*
X1432560Y541455D03*
X1436060D03*
Y548455D03*
X1432560D03*
X1436100Y535400D03*
X1432600D03*
X1465400Y621700D03*
X1516600Y-6500D03*
X1520100D03*
X1525000D03*
X1512500D03*
X1509000D03*
X1489800Y115088D03*
X1493300D03*
X1489800Y120588D03*
X1493300D03*
X1489800Y115088D03*
X1486300D03*
X1492692Y127250D03*
X1489192D03*
X1489800Y120588D03*
X1486300D03*
X1492692Y127250D03*
X1496192D03*
X1492692Y132750D03*
X1489192D03*
X1492692D03*
X1496192D03*
X1520100Y200200D03*
X1516600D03*
X1492548Y215132D03*
X1489048D03*
X1507446Y221770D03*
X1503946D03*
X1524250Y314300D03*
X1520750D03*
X1523250Y338500D03*
X1519750D03*
X1511955Y310641D03*
X1508455D03*
X1511955Y307641D03*
X1508455D03*
X1512733Y295817D03*
X1509233D03*
X1503226Y623027D03*
X1506726D03*
X1474900Y622900D03*
X1478400D03*
X1468900Y621700D03*
X1576800Y-6800D03*
X1573300D03*
X1551300Y-6200D03*
X1547800D03*
X1554300D03*
X1557800D03*
X1589000Y-12600D03*
X1570300Y-6800D03*
X1566800D03*
X1577398Y-3069D03*
X1573898D03*
X1589000Y-16100D03*
X1528500Y-6500D03*
X1533000D03*
X1536500D03*
X1577398Y3931D03*
X1573898D03*
Y431D03*
X1577398D03*
X1584099Y146538D03*
X1580599D03*
X1584099Y143538D03*
X1580599D03*
X1585750Y149600D03*
X1582250D03*
X1573892Y134959D03*
X1570392D03*
X1585000Y135538D03*
X1581500D03*
X1581810Y132538D03*
X1585310D03*
X1581810Y129538D03*
X1585310D03*
X1575910Y120760D03*
X1579410D03*
X1570374Y140959D03*
X1573874D03*
Y143959D03*
X1570374D03*
X1570354Y137959D03*
X1573854D03*
X1578200Y215770D03*
X1581700D03*
X1578200Y210770D03*
X1581700D03*
X1588701Y172162D03*
X1585201D03*
X1588599Y169038D03*
X1585099D03*
X1588501Y161362D03*
X1585001D03*
X1588599Y164538D03*
X1585099D03*
X1585750Y189000D03*
X1582250D03*
X1585750Y194500D03*
X1582250D03*
X1571036Y159073D03*
X1574536D03*
X1549899Y255747D03*
X1546399D03*
X1557500Y260400D03*
X1561000D03*
X1546399Y252647D03*
X1549899D03*
X1528250Y314300D03*
X1531750D03*
X1557250Y298500D03*
X1553750D03*
X1557525Y308909D03*
X1554025D03*
X1557250Y305500D03*
X1553750D03*
X1557250Y301500D03*
X1553750D03*
X1583559Y321059D03*
X1587059D03*
X1528250Y317400D03*
X1531750D03*
X1536728Y322466D03*
X1533228D03*
X1557250Y312500D03*
X1553750D03*
X1566850Y344350D03*
X1570350D03*
X1566454Y620727D03*
X1569954D03*
X1557583Y620894D03*
X1561083D03*
X1541211Y604235D03*
X1537711D03*
X1539000Y610500D03*
X1542500D03*
X1575790Y597340D03*
X1579290D03*
X1575790Y601040D03*
X1579290D03*
X1534967Y616500D03*
X1531467D03*
X1538060Y598459D03*
X1541560D03*
X1530385Y620053D03*
X1533885D03*
X1592500Y-12600D03*
Y-16100D03*
X1608750Y90500D03*
X1605250D03*
X1627500Y72500D03*
X1624000D03*
X1621599Y90538D03*
X1618099D03*
X1627100Y197580D03*
X1623600D03*
X1602250Y197000D03*
X1598750D03*
X1614250D03*
X1610750D03*
X1645250Y252500D03*
X1641750D03*
X1641350Y231500D03*
X1644850D03*
X1641750Y255500D03*
X1645250D03*
X1604400Y242600D03*
X1600900D03*
X1605650Y246500D03*
X1602150D03*
Y249500D03*
X1605650D03*
Y252500D03*
X1602150D03*
X1615064Y222460D03*
X1618564D03*
X1605650Y255500D03*
X1602150D03*
X1618564Y225460D03*
X1615064D03*
X1644500Y325000D03*
X1641000D03*
Y328500D03*
X1644500D03*
X1594750Y402000D03*
X1598250D03*
X1638500Y398700D03*
X1635000D03*
X1620700Y391100D03*
X1617200D03*
X1645300Y361350D03*
X1648800D03*
X1645300Y364850D03*
X1648800D03*
X1601829Y379923D03*
X1605329D03*
X1601829Y376723D03*
X1605329D03*
X1623750Y446500D03*
X1627250D03*
X1609250Y451000D03*
X1605750D03*
X1605669Y454809D03*
X1609169D03*
X1627300Y439500D03*
X1623800D03*
X1616300Y450000D03*
X1612800D03*
X1615300Y459100D03*
X1611800D03*
X1605750Y446000D03*
X1609250D03*
X1633250Y449500D03*
X1636750D03*
X1627300Y453663D03*
X1623800D03*
X1636700Y445800D03*
X1633200D03*
X1633250Y452500D03*
X1636750D03*
X1623750Y443500D03*
X1627250D03*
X1635700Y441900D03*
X1632200D03*
X1614750Y442500D03*
X1618250D03*
X1614750Y439500D03*
X1618250D03*
X1594000Y455500D03*
X1590500D03*
X1597800Y408400D03*
X1601300D03*
X1601250Y416000D03*
X1597750D03*
X1597800Y412000D03*
X1601300D03*
X1609250Y426000D03*
X1605750D03*
X1627250Y432000D03*
X1623750D03*
X1627250Y435500D03*
X1623750D03*
X1633250D03*
X1636750D03*
Y432000D03*
X1633250D03*
X1605750Y432500D03*
X1609250D03*
X1605750Y435500D03*
X1609250D03*
Y429000D03*
X1605750D03*
X1614750Y432500D03*
X1618250D03*
X1614750Y429000D03*
X1618250D03*
X1614750Y435500D03*
X1618250D03*
X1614750Y426000D03*
X1618250D03*
X1605449Y422971D03*
X1608949D03*
X1606250Y416000D03*
X1609750D03*
Y412000D03*
X1606250D03*
X1615250Y415500D03*
X1618750D03*
X1620847Y418837D03*
X1617347D03*
X1620847Y421837D03*
X1617347D03*
X1627300Y449800D03*
X1623800D03*
X1605260Y442230D03*
X1608760D03*
X1593600Y491500D03*
X1590100D03*
X1593500Y487300D03*
X1590000D03*
X1615898Y495476D03*
X1619398D03*
X1615898Y492476D03*
X1619398D03*
X1623361Y521918D03*
X1619861D03*
X1623361Y518918D03*
X1619861D03*
X1611057Y465508D03*
X1607557D03*
X1608813Y483559D03*
X1605313D03*
X1608813Y480359D03*
X1605313D03*
X1611057Y468708D03*
X1607557D03*
X1603957Y476708D03*
X1600457D03*
X1603957Y473508D03*
X1600457D03*
X1599104Y580396D03*
X1595604D03*
Y588396D03*
X1599104D03*
Y584396D03*
X1595604D03*
X1599104Y592396D03*
X1595604D03*
X1704900Y63200D03*
X1708400D03*
X1686000Y90000D03*
X1682500D03*
X1689000D03*
X1692500D03*
X1704900Y72968D03*
X1708400D03*
X1684020Y142025D03*
X1687520D03*
X1654819Y212708D03*
X1651319D03*
X1696368Y177380D03*
X1699868D03*
X1693343Y177381D03*
X1689843D03*
X1696400Y174350D03*
X1699900D03*
X1706620Y172616D03*
X1710120D03*
X1693242Y198749D03*
X1696742D03*
X1703242D03*
X1699742D03*
X1659050Y410500D03*
X1662550D03*
X1655550Y413500D03*
X1652050D03*
X1655550Y410500D03*
X1652050D03*
X1659050Y413500D03*
X1662550D03*
X1655250Y445000D03*
X1651750D03*
X1658750D03*
X1662250D03*
X1675650Y494800D03*
X1679150D03*
X1675450Y491800D03*
X1678950D03*
X1675350Y488400D03*
X1678850D03*
X1675750Y511000D03*
X1679250D03*
X1675750Y514000D03*
X1679250D03*
X1675750Y498050D03*
X1679250D03*
X1675750Y501250D03*
X1679250D03*
X1675750Y504550D03*
X1679250D03*
X1695802Y502313D03*
X1699302D03*
X1716163Y3233D03*
X1719663D03*
X1756250Y4500D03*
X1752750D03*
X1745250D03*
X1748750D03*
X1729750Y63500D03*
X1726250D03*
X1723250D03*
X1719750D03*
X1729750Y60500D03*
X1726250D03*
X1723250D03*
X1719750D03*
Y57500D03*
X1723250D03*
X1719750Y66500D03*
X1723250D03*
X1748594Y49606D03*
X1745094D03*
Y55606D03*
X1741594D03*
X1745094Y52606D03*
X1741594D03*
X1762500Y63000D03*
X1759000D03*
X1769000Y83500D03*
X1772500D03*
X1771000Y79800D03*
X1774500D03*
X1719450Y86600D03*
X1722950D03*
X1764529Y111540D03*
X1761029D03*
X1764850Y158650D03*
X1761350D03*
X1739000Y566000D03*
X1735500D03*
X1739000Y563000D03*
X1735500D03*
X1736000Y554000D03*
X1732500D03*
X1745250Y577100D03*
X1748750D03*
X1737814Y581186D03*
X1741314D03*
X1765180Y604490D03*
X1761680D03*
X1833600Y-15700D03*
X1828500Y1000D03*
X1832000D03*
X1808000Y6000D03*
X1811500D03*
X1819000D03*
X1815500D03*
X1795696Y6061D03*
X1792196D03*
X1835500Y800D03*
X1833050Y94550D03*
X1829550D03*
X1833050Y90850D03*
X1829550D03*
X1829500Y87500D03*
X1833000D03*
X1829550Y97850D03*
X1833050D03*
X1807348Y151937D03*
X1803848D03*
X1802750Y120000D03*
X1799250D03*
X1790250D03*
X1793750D03*
X1833023Y101490D03*
X1833047Y104556D03*
X1788250Y126500D03*
X1784750D03*
X1792750Y101800D03*
X1796250D03*
X1833280Y570500D03*
X1776500Y604500D03*
X1780000D03*
X1837100Y-15700D03*
X1889594Y-15042D03*
X1893094D03*
X1889581Y-18335D03*
X1893081D03*
X1839000Y800D03*
X1896581Y-18335D03*
X1893081D03*
X1896594Y-15042D03*
X1893094D03*
X1843500Y81300D03*
X1847000D03*
X1880536Y57002D03*
X1884036D03*
X1880536Y60047D03*
X1884036D03*
X1840250Y81300D03*
X1836750D03*
X1863000Y117500D03*
X1859500D03*
X1863000Y120500D03*
X1859500D03*
X1892370Y140100D03*
X1888870D03*
X1836523Y101490D03*
X1836547Y104556D03*
X1879150Y169100D03*
X1882650D03*
Y166100D03*
X1879150D03*
X1882650Y162600D03*
X1879150D03*
Y159100D03*
X1882650D03*
X1853150Y169600D03*
X1856650D03*
X1880750Y562500D03*
X1884250D03*
X1864750Y545000D03*
X1861250D03*
X1864750Y549500D03*
X1861250D03*
X1836780Y570500D03*
X1896450Y539500D03*
X1891750Y562500D03*
X1888250D03*
X1861961Y557512D03*
X1865461D03*
X1872350Y580350D03*
X1875850D03*
X1957169Y81509D03*
X1931500Y153600D03*
X1935000D03*
X1921800Y137300D03*
X1925300D03*
X1922000Y132500D03*
X1925500D03*
X1906590Y110820D03*
X1903090D03*
X1903790Y115280D03*
X1900290D03*
X1903790Y119280D03*
X1900290D03*
X1946190Y101730D03*
X1949690D03*
X1935450Y196100D03*
X1931950D03*
X1936750Y173600D03*
X1933250D03*
X1930150Y190100D03*
X1933650D03*
Y181100D03*
X1930150D03*
X1933650Y184100D03*
X1930150D03*
X1936750Y165600D03*
X1933250D03*
X1936750Y169600D03*
X1933250D03*
X1936750Y161600D03*
X1933250D03*
X1936750Y157600D03*
X1933250D03*
X1949110Y489180D03*
X1945610D03*
X1929480Y475430D03*
X1925980D03*
X1949050Y492280D03*
X1945550D03*
X1916390Y483910D03*
X1912890D03*
X1916460Y487390D03*
X1912960D03*
X1930250Y566442D03*
X1926750D03*
X1930250Y569442D03*
X1926750D03*
X1917744Y540400D03*
X1921244D03*
X1899950Y539500D03*
X1926750Y572942D03*
X1930250D03*
X1931239Y596040D03*
X1934739D03*
X1931249Y599040D03*
X1934749D03*
X1934699Y605040D03*
X1931199D03*
X1934699Y602040D03*
X1931199D03*
X1929600Y590100D03*
X1926100D03*
X1927015Y611391D03*
X1930515D03*
X1963271Y93138D03*
X1959771D03*
X1960669Y81509D03*
G54D160*
X678800Y228100D03*
X1337472Y40715D03*
X1351360Y9620D03*
X1355200Y368200D03*
X1351600Y556000D03*
X1356882Y618600D03*
G54D31*
X25064Y-11490D03*
X6261Y485075D03*
X-1296Y485081D03*
X1351416Y43361D03*
G54D223*
X1407473Y553605D03*
X1409048D03*
X1410623D03*
X1412198D03*
X1413773D03*
X1415347D03*
X1416922D03*
X1418497D03*
X1420072D03*
X1421647D03*
X1551113Y615150D03*
X1552688D03*
X1554263D03*
X1555838D03*
X1557413D03*
X1558987D03*
X1560562D03*
X1562137D03*
X1563712D03*
X1565287D03*
G54D106*
X53953Y649705D03*
X242675Y649805D03*
X430143Y649535D03*
X617691Y649266D03*
X933345Y649255D03*
X1246843Y649285D03*
G54D214*
X1432543Y291443D03*
G54D232*
G01X41000Y265350D02*
Y267950D01*
G01X37000Y265350D02*
Y267950D01*
G01X29000Y255780D02*
X21522D01*
X19904Y254162D01*
G01X41000Y271450D02*
Y274647D01*
G01X45900Y278700D02*
X45800Y278800D01*
G01X37000Y274647D02*
Y271450D01*
G01X-1000Y564000D02*
X-4800D01*
G01X0Y528800D02*
X-3800D01*
G01X56540Y-20308D02*
X58948D01*
X59281Y-20641D01*
G01X53340Y-20296D02*
X56528D01*
X56540Y-20308D01*
G01X48700Y255780D02*
X55820D01*
X57500Y254100D01*
G01X62500Y275500D02*
Y277500D01*
X62000Y278000D01*
G01X59500Y275500D02*
Y278000D01*
G01X66000Y275500D02*
Y277688D01*
X63188Y280500D01*
X62500D01*
G01X56000Y275500D02*
Y278000D01*
X58500Y280500D01*
X59000D01*
G01X80500Y279000D02*
X77000D01*
G01X80500D02*
Y282545D01*
X81906Y283951D01*
X82050D01*
G01X61900Y289200D02*
Y286200D01*
G01X61625Y283201D02*
X62095Y282731D01*
Y282505D01*
X62500Y282100D01*
Y280500D01*
G01X58700Y283000D02*
Y282950D01*
X59000Y282650D01*
Y280500D01*
G01X68500Y388600D02*
Y385500D01*
G01X123892Y13078D02*
Y9386D01*
X123620Y9114D01*
G01X120273Y9157D02*
Y3233D01*
G01X120392Y13078D02*
Y9276D01*
X120273Y9157D01*
G01X123907Y87248D02*
Y85001D01*
X123620Y84714D01*
G01Y46914D02*
X123892Y47186D01*
Y50878D01*
G01X119892Y84700D02*
X120392Y85200D01*
Y87233D01*
G01X119892Y84700D02*
X120273Y84319D01*
Y78833D01*
G01Y46957D02*
Y41033D01*
G01Y46957D02*
X120392Y47076D01*
Y50878D01*
G01X119400Y271600D02*
X120500D01*
X121433Y272533D01*
X124124D01*
G01D02*
Y273876D01*
X123074Y274926D01*
Y275948D01*
G01X408184Y51000D02*
X404700D01*
G01X361178Y50492D02*
X360345Y49659D01*
X357762D01*
G01X358618Y54842D02*
X357872Y55588D01*
G01X371507Y349509D02*
X369257D01*
G01X411416Y593657D02*
X411415Y593658D01*
G01X442508Y13200D02*
X445157D01*
X445657Y13700D01*
X448292D01*
G01X448492Y51000D02*
X442508D01*
G01X455263Y342947D02*
Y340697D01*
G01X458643Y340996D02*
Y338746D01*
G01X474413Y329296D02*
X472163D01*
G01X468783Y335147D02*
Y332897D01*
G01X472163Y313696D02*
X469913D01*
G01X472163Y317596D02*
X469913D01*
G01X445123Y348796D02*
Y346546D01*
G01X441743Y350747D02*
Y348497D01*
G01X431604Y348796D02*
Y346546D01*
G01X421464Y350747D02*
Y348497D01*
G01X424844Y348796D02*
Y346546D01*
G01X438363Y348796D02*
Y346546D01*
G01X448503Y346847D02*
Y344597D01*
G01X451883Y344896D02*
Y342646D01*
G01X434983Y350747D02*
Y348497D01*
G01X428224Y350747D02*
Y348497D01*
G01X418108Y523900D02*
Y529007D01*
G01X428147Y593659D02*
X428149Y593657D01*
G01X688416Y69515D02*
X694637D01*
G01X709000Y229000D02*
X709100Y228900D01*
X711300D01*
X712300Y227900D01*
Y227500D01*
G01X687550Y274500D02*
X688250Y273800D01*
Y271000D01*
G01X687500Y251307D02*
X689447D01*
X689540Y251400D01*
G01X718000Y224600D02*
Y227100D01*
X718300Y227400D01*
G01X720500Y244000D02*
X723500D01*
G01D02*
X725725Y241775D01*
Y241560D01*
G01X716900Y305400D02*
X715875Y304375D01*
X715575D01*
G01X676900Y489400D02*
Y491470D01*
X678400Y492970D01*
X679430D01*
G01X684550Y499970D02*
Y503470D01*
G01D02*
X685050Y503970D01*
G01X773228Y9114D02*
X773500Y9386D01*
Y13078D01*
G01X769883Y3233D02*
X769881D01*
Y9157D01*
G01D02*
X770000Y9276D01*
Y13078D01*
G01X773500Y50878D02*
Y47186D01*
X773228Y46914D01*
G01Y84714D02*
X773500Y84986D01*
Y89000D01*
G01X769883Y78833D02*
X769881D01*
Y84319D01*
X769500Y84700D01*
G01D02*
X770000Y85200D01*
Y89000D01*
G01X769883Y41033D02*
X769881D01*
Y46957D01*
G01D02*
X770000Y47076D01*
Y50878D01*
G01X765134Y271186D02*
X763689D01*
X762616Y270113D01*
G01X763232Y267610D02*
Y269127D01*
X762616Y269743D01*
Y270113D01*
G01X797000Y404700D02*
X799500Y407200D01*
Y410488D01*
X803212Y414200D01*
X805700D01*
X807000Y415500D01*
Y417000D01*
G01Y420000D02*
Y417000D01*
G01X963976Y83835D02*
Y87392D01*
G01X1021115Y349509D02*
X1018865D01*
G01X1020868Y579810D02*
Y561700D01*
G01D02*
Y556868D01*
X1019800Y555800D01*
G01X1009700Y589500D02*
X1008334Y590966D01*
X1006406D01*
G01X1070976Y13200D02*
X1066758D01*
G01X1083116D02*
X1079758D01*
G01X1057792D02*
X1054308D01*
G01X1092116D02*
X1094765D01*
X1095265Y13700D01*
X1097900D01*
G01X1070976Y51000D02*
X1066758D01*
G01X1098100D02*
X1092116D01*
G01X1083116D02*
X1079758D01*
G01X1057792D02*
X1054308D01*
G01X1094731Y348796D02*
Y346546D01*
G01X1091351Y350747D02*
Y348497D01*
G01X1071072Y350747D02*
Y348497D01*
G01X1087971Y348796D02*
Y346546D01*
G01X1084591Y350747D02*
Y348497D01*
G01X1077832Y350747D02*
Y348497D01*
G01X1081212Y348796D02*
Y346546D01*
G01X1074452Y348796D02*
Y346546D01*
G01X1061023Y593658D02*
X1061024Y593657D01*
G01X1077755Y593659D02*
X1077757Y593657D01*
G01X1121771Y274696D02*
Y278596D01*
G01X1108251Y340996D02*
Y338746D01*
G01X1104871Y342947D02*
Y340697D01*
G01X1121771Y325396D02*
X1124021D01*
G01X1121771Y329296D02*
X1124021D01*
G01X1118391Y335147D02*
Y332897D01*
G01X1121771Y313696D02*
X1119521D01*
G01X1121771Y317596D02*
X1119521D01*
G01X1098111Y346847D02*
Y344597D01*
G01X1101491Y344896D02*
Y342646D01*
G01X1378170Y8888D02*
X1376934D01*
X1375676Y7630D01*
G01X1378053Y19907D02*
X1379556D01*
G01X1368591Y88950D02*
Y87341D01*
X1367700Y86450D01*
G01X1376200Y399100D02*
Y397302D01*
X1375201Y396303D01*
G01X1372700Y399100D02*
Y397361D01*
X1372007Y396668D01*
G01X1390623Y574986D02*
Y576728D01*
X1388986Y578365D01*
G01X1378400Y587056D02*
X1379851D01*
X1381685Y585222D01*
G01X1389750Y592000D02*
X1392500D01*
G01X1405460Y524955D02*
X1406592D01*
X1408753Y527116D01*
Y527518D01*
G01X1498760Y30906D02*
Y30669D01*
G01X1567520Y133354D02*
X1568787D01*
X1570392Y134959D01*
G01X1567425Y144373D02*
X1567839Y143959D01*
X1570374D01*
G01X1618449Y83888D02*
Y83619D01*
X1620768Y81300D01*
X1620900D01*
G01X1634611Y506852D02*
X1638448D01*
X1639394Y507798D01*
G01D02*
Y509018D01*
X1637623Y510789D01*
X1634611D01*
G01X1772244Y244105D02*
Y239509D01*
X1771451Y238716D01*
Y237712D01*
G01X1744603Y232489D02*
X1743898Y231784D01*
Y226756D01*
G01X1753347Y232106D02*
Y226756D01*
G01X1762795Y232106D02*
Y226756D01*
G01X1772244Y232106D02*
Y226756D01*
G01X1762795Y244105D02*
Y239559D01*
X1763554Y238800D01*
Y237712D01*
G01X1753347Y244105D02*
Y239509D01*
X1752554Y238716D01*
Y237712D01*
G01X1832449Y-8950D02*
Y-10449D01*
X1833100Y-11100D01*
X1835874D01*
G01X1811900Y117500D02*
X1808600D01*
X1808400Y117300D01*
G01X1803400Y114000D02*
X1806700Y117300D01*
X1808400D01*
G01X1800591Y244105D02*
Y248701D01*
X1801384Y249494D01*
Y250498D01*
G01X1819488Y244105D02*
Y248701D01*
X1820281Y249494D01*
Y250498D01*
G01X1810040Y244105D02*
Y248651D01*
X1809281Y249410D01*
Y250498D01*
G01X1791142Y244105D02*
Y248651D01*
X1790383Y249410D01*
Y250498D01*
G01X1781693Y244105D02*
Y239559D01*
X1782452Y238800D01*
Y237712D01*
G01X1791141Y232106D02*
Y226757D01*
X1791142Y226756D01*
G01X1810040D02*
Y232106D01*
G01X1800591D02*
Y226756D01*
G01X1781693Y232106D02*
Y226756D01*
G01X1847185Y454368D02*
X1851185Y450368D01*
Y441754D01*
G01X1868204Y497504D02*
Y487666D01*
X1870138Y485732D01*
G01X1868204Y529000D02*
X1874476D01*
X1875971Y530495D01*
X1881907D01*
X1883953Y532541D01*
X1887327D01*
X1495325Y381800D03*
X1501175Y385180D03*
Y391940D03*
Y398700D03*
Y378420D03*
X1507025Y388560D03*
Y395320D03*
Y402080D03*
Y381800D03*
X1512875Y385180D03*
Y391940D03*
Y398700D03*
Y378420D03*
X1489475Y398700D03*
X1518725Y388560D03*
Y381800D03*
Y395320D03*
X1522625Y402080D03*
X1524575Y385180D03*
Y391940D03*
Y398700D03*
Y378420D03*
X1489475D03*
Y385180D03*
Y391940D03*
X1495325Y388560D03*
Y395320D03*
Y402080D03*
X1485575Y398700D03*
Y378420D03*
X1497275Y385180D03*
X1520675Y391940D03*
X1505075Y385180D03*
X1520675Y398700D03*
X1487525Y402080D03*
X1505075Y398700D03*
X1491425Y402080D03*
X1493375Y398700D03*
X1497275D03*
X1514825Y395320D03*
Y381800D03*
X1510925Y395320D03*
Y402080D03*
X1508975Y398700D03*
X1516775Y385180D03*
Y391940D03*
Y398700D03*
X1520675Y385180D03*
X1516775Y378420D03*
X1510925Y381800D03*
X1508975Y378420D03*
Y385180D03*
X1510925Y388560D03*
X1514825D03*
X1508975Y391940D03*
X1514825Y402080D03*
X1518725D03*
X1499225D03*
X1503125D03*
X1522625Y381800D03*
X1526525Y395320D03*
X1522625D03*
Y388560D03*
X1526525D03*
Y402080D03*
Y381800D03*
X1520675Y378420D03*
X1491425Y381800D03*
X1499225Y388560D03*
X1493375Y378420D03*
X1505075Y391940D03*
X1497275Y378420D03*
X1493375Y391940D03*
X1497275D03*
X1499225Y381800D03*
X1505075Y378420D03*
X1503125Y388560D03*
Y395320D03*
Y381800D03*
X1499225Y395320D03*
X1487525Y381800D03*
X1485575Y385180D03*
X1493375D03*
X1487525Y388560D03*
X1485575Y391940D03*
X1491425Y388560D03*
X1487525Y395320D03*
X1491425D03*
X1516775Y405460D03*
X1495325Y429120D03*
Y435880D03*
Y449400D03*
X1499225Y435880D03*
X1517075Y443525D03*
X1499225Y415600D03*
X1503125Y442640D03*
X1499225Y456160D03*
Y462920D03*
X1501175Y405460D03*
Y412220D03*
Y418980D03*
Y425740D03*
Y432500D03*
Y439260D03*
X1523375Y446675D03*
X1501175Y452780D03*
Y459540D03*
X1518725Y456160D03*
X1520225Y449825D03*
X1505073Y412220D03*
Y452780D03*
X1505075Y459540D03*
X1507025Y408840D03*
X1510925Y456160D03*
X1507625Y443525D03*
X1508975Y405460D03*
X1507625Y415175D03*
Y452975D03*
X1508975Y459540D03*
X1510775Y412025D03*
Y415175D03*
Y443525D03*
Y452975D03*
X1512875Y405460D03*
X1513925Y446675D03*
Y415175D03*
Y443525D03*
Y449825D03*
Y452975D03*
X1512875Y459540D03*
X1517075Y418325D03*
Y452975D03*
X1516775Y459540D03*
X1518725Y408840D03*
X1520225Y412025D03*
Y421475D03*
Y440375D03*
Y443525D03*
X1520675Y459540D03*
X1523375Y424625D03*
X1526525Y421475D03*
X1524575Y405460D03*
X1523375Y412025D03*
Y421475D03*
Y427775D03*
Y430925D03*
Y434075D03*
Y437225D03*
Y440375D03*
X1524575Y459540D03*
X1526525Y412025D03*
Y440375D03*
Y449825D03*
Y452975D03*
X1485575Y405460D03*
Y418980D03*
Y432500D03*
Y452780D03*
X1489475Y418980D03*
Y405460D03*
Y432500D03*
Y446020D03*
X1491425Y462920D03*
X1493375Y405460D03*
Y412220D03*
Y418980D03*
Y425740D03*
Y432500D03*
Y439260D03*
X1495325Y442640D03*
Y456160D03*
X1493375Y446020D03*
Y452780D03*
X1495325Y408840D03*
Y415600D03*
Y422360D03*
X1526525Y430925D03*
X1505075Y432500D03*
X1526525Y424625D03*
X1503125Y422360D03*
Y429120D03*
Y435880D03*
X1505075Y418980D03*
Y425740D03*
Y439260D03*
X1507625Y418325D03*
Y421475D03*
Y424625D03*
Y427775D03*
Y430925D03*
Y434075D03*
Y437225D03*
Y440375D03*
X1510775Y418325D03*
Y421475D03*
Y424625D03*
Y427775D03*
Y430925D03*
Y434075D03*
Y437225D03*
Y440375D03*
X1513925Y418325D03*
Y421475D03*
Y424625D03*
Y427775D03*
Y430925D03*
Y434075D03*
Y437225D03*
Y440375D03*
X1503125Y415600D03*
X1517075Y421475D03*
Y424625D03*
Y427775D03*
Y430925D03*
Y434075D03*
Y437225D03*
Y440375D03*
X1520225Y424625D03*
Y427775D03*
Y430925D03*
Y434075D03*
Y437225D03*
X1526525Y427775D03*
Y434075D03*
Y437225D03*
X1517075Y415175D03*
X1520675Y405460D03*
X1526525Y456160D03*
X1514825Y408840D03*
X1517075Y412025D03*
X1526525Y418325D03*
X1520225D03*
X1523375Y415175D03*
X1510775Y446675D03*
Y449825D03*
X1513925Y412025D03*
X1523375Y418325D03*
X1507625Y412025D03*
X1510925Y408840D03*
X1526525Y415175D03*
X1499225Y442640D03*
Y449400D03*
X1501175Y446020D03*
X1503125Y449400D03*
X1505075Y446020D03*
X1507625Y446675D03*
Y449825D03*
X1520225Y415175D03*
X1526525Y408840D03*
X1522625D03*
X1523375Y443525D03*
X1526525D03*
Y446675D03*
X1514825Y456160D03*
X1503125D03*
X1522625D03*
X1520225Y452975D03*
X1517075Y446675D03*
Y449825D03*
X1523375Y452975D03*
Y449825D03*
X1520225Y446675D03*
X1507025Y456160D03*
X1497275Y418980D03*
X1499225Y422360D03*
X1497275Y425740D03*
X1499225Y429120D03*
X1497275Y432500D03*
Y452780D03*
Y446020D03*
Y439260D03*
X1503125Y408840D03*
X1505075Y405460D03*
X1499225Y408840D03*
X1497275Y412220D03*
Y405460D03*
X1526525Y462920D03*
X1507025D03*
X1510925D03*
X1503125D03*
X1514825D03*
X1522625D03*
X1518725D03*
X1487525D03*
X1485575Y459540D03*
X1489475D03*
X1495325Y462920D03*
X1493375Y459540D03*
X1487525Y456160D03*
X1491425Y449400D03*
X1497275Y459540D03*
X1491425Y456160D03*
X1489475Y452780D03*
X1487525Y449400D03*
X1485575Y446020D03*
Y412220D03*
X1491425Y422360D03*
X1485575Y439260D03*
X1487525Y442640D03*
X1485575Y425740D03*
X1487525Y429120D03*
Y415600D03*
Y408840D03*
Y435880D03*
X1489475Y412220D03*
X1487525Y422360D03*
X1489475Y439260D03*
X1491425Y442640D03*
X1489475Y425740D03*
X1491425Y429120D03*
Y415600D03*
Y408840D03*
Y435880D03*
X1497275Y479820D03*
X1501175Y466300D03*
X1499225Y469680D03*
X1501175Y486580D03*
X1503125Y469680D03*
X1507025D03*
X1505075Y486580D03*
X1507025Y476440D03*
X1508975Y473060D03*
Y479820D03*
X1514825Y469680D03*
X1512875Y473060D03*
Y479820D03*
Y486580D03*
X1514825Y483200D03*
X1516775Y466300D03*
Y473060D03*
Y479820D03*
Y486580D03*
X1520675Y466300D03*
Y473060D03*
Y486580D03*
X1524575Y466300D03*
Y473060D03*
Y486580D03*
X1526525Y469680D03*
Y476440D03*
X1485575Y473060D03*
Y479820D03*
Y486580D03*
X1487525Y469680D03*
Y483200D03*
X1489475Y473060D03*
X1510925Y469680D03*
X1512875Y466300D03*
X1518725Y476440D03*
X1508975Y466300D03*
X1505075D03*
X1493375Y486580D03*
X1489475D03*
X1493375Y479820D03*
X1491425Y483200D03*
X1499225Y476440D03*
X1497275Y473060D03*
X1489475Y479820D03*
X1487525Y476440D03*
X1491425D03*
X1495325D03*
X1493375Y473060D03*
X1495325Y469680D03*
X1491425D03*
X1489475Y466300D03*
X1485575D03*
X1493375D03*
X1497275D03*
X1510925Y483200D03*
X1508975Y486580D03*
X1505075Y479820D03*
X1507025Y483200D03*
X1503125Y476440D03*
X1501175Y479820D03*
X1503125Y483200D03*
X1499225D03*
X1505075Y473060D03*
X1501175D03*
X1497275Y486580D03*
X1495325Y483200D03*
X1522625Y469680D03*
X1518725D03*
X1514825Y476440D03*
X1510925D03*
X1520675Y479820D03*
X1522625Y476440D03*
Y483200D03*
X1518725D03*
X1524575Y479820D03*
X1526525Y483200D03*
X1565525Y388560D03*
Y395320D03*
Y381800D03*
X1569425Y402080D03*
X1553825Y381800D03*
X1559675Y385180D03*
Y378420D03*
Y391940D03*
Y398700D03*
X1530425Y388560D03*
Y395320D03*
Y402080D03*
Y381800D03*
X1536275Y378420D03*
Y385180D03*
Y391940D03*
Y398700D03*
X1542125Y381800D03*
Y388560D03*
Y395320D03*
X1547975Y378420D03*
Y385180D03*
Y391940D03*
Y398700D03*
X1553825Y388560D03*
Y395320D03*
Y402080D03*
X1540175Y385180D03*
X1555775D03*
X1544075Y391940D03*
X1540175Y398700D03*
X1542125Y402080D03*
X1546025Y381800D03*
X1544075Y378420D03*
X1546025Y388560D03*
X1549925Y402080D03*
X1555775Y378420D03*
X1546025Y395320D03*
X1540175Y391940D03*
X1551875D03*
Y378420D03*
X1549925Y381800D03*
Y395320D03*
X1551875Y398700D03*
X1540175Y378420D03*
X1544075Y398700D03*
X1549925Y388560D03*
X1546025Y402080D03*
X1551875Y385180D03*
X1544075D03*
X1534325Y402080D03*
X1528475Y398700D03*
X1538225Y395320D03*
X1532375Y398700D03*
X1534325Y395320D03*
X1538225Y402080D03*
Y381800D03*
X1528475Y391940D03*
X1532375D03*
X1538225Y388560D03*
X1534325D03*
X1528475Y385180D03*
X1532375D03*
Y378420D03*
X1534325Y381800D03*
X1528475Y378420D03*
X1557725Y402080D03*
X1567475Y385180D03*
X1569425Y388560D03*
X1555775Y398700D03*
X1561625Y395320D03*
X1567475Y378420D03*
X1569425Y381800D03*
X1565525Y402080D03*
X1569425Y395320D03*
X1557725D03*
X1567475Y391940D03*
X1557725Y381800D03*
X1561625Y402080D03*
X1563575Y391940D03*
X1555775D03*
X1561625Y388560D03*
X1557725D03*
X1567475Y398700D03*
X1563575D03*
X1561625Y381800D03*
X1563575Y385180D03*
Y378420D03*
X1561625Y408840D03*
Y415600D03*
Y422360D03*
Y429120D03*
Y435880D03*
Y442640D03*
Y456160D03*
X1563575Y405460D03*
Y439260D03*
Y432500D03*
X1567475D03*
X1565525Y449400D03*
Y456160D03*
X1567475Y405460D03*
Y459540D03*
X1569425Y456160D03*
Y462920D03*
X1555775Y425740D03*
Y452780D03*
X1557725Y415600D03*
Y435880D03*
Y442640D03*
Y449400D03*
Y462920D03*
X1559675Y412220D03*
Y425740D03*
Y459540D03*
X1529675Y412025D03*
Y421475D03*
Y440375D03*
Y449825D03*
X1532375Y405460D03*
X1532825Y412025D03*
Y421475D03*
Y440375D03*
Y449825D03*
X1532375Y459540D03*
X1534325Y456160D03*
X1536275Y405460D03*
X1535975Y412025D03*
Y421475D03*
Y440375D03*
Y449825D03*
X1539125Y412025D03*
Y421475D03*
Y440375D03*
Y449825D03*
X1538225Y456160D03*
Y462920D03*
X1540175Y405460D03*
X1542275Y412025D03*
Y421475D03*
Y424625D03*
Y427775D03*
Y430925D03*
Y434075D03*
Y437225D03*
Y440375D03*
Y449825D03*
X1542125Y456160D03*
X1544075Y405460D03*
X1546025Y456160D03*
Y462920D03*
X1547975Y405460D03*
Y446020D03*
X1549925Y408840D03*
Y415600D03*
Y422360D03*
Y429120D03*
Y456160D03*
Y462920D03*
X1551875Y418980D03*
Y425740D03*
Y432500D03*
X1553825Y462920D03*
X1555775Y446020D03*
X1553825Y408840D03*
Y415600D03*
Y435880D03*
Y442640D03*
Y456160D03*
X1528475Y405460D03*
Y459540D03*
X1547977Y452780D03*
X1535975Y434075D03*
X1532825Y427775D03*
Y430925D03*
Y434075D03*
Y437225D03*
X1535975Y424625D03*
Y427775D03*
Y430925D03*
X1539125Y424625D03*
Y427775D03*
X1529675Y424625D03*
Y427775D03*
Y430925D03*
Y434075D03*
Y437225D03*
X1532825Y424625D03*
X1539125Y430925D03*
X1529675Y452975D03*
X1530425Y456160D03*
X1532825Y452975D03*
X1539125D03*
X1535975D03*
X1542275D03*
X1530425Y408840D03*
X1545425Y446675D03*
Y449825D03*
X1549925Y449400D03*
X1545425Y452975D03*
X1534325Y408840D03*
X1529675Y415175D03*
X1535975Y437225D03*
X1539125Y434075D03*
Y437225D03*
X1551875Y452780D03*
X1553825Y449400D03*
X1542275Y415175D03*
X1532825Y418325D03*
X1529675D03*
X1535975D03*
X1542275D03*
X1539125D03*
X1538225Y408840D03*
X1547977Y412220D03*
X1546025Y408840D03*
X1545425Y412025D03*
X1539125Y415175D03*
X1551875Y446020D03*
X1545425Y443525D03*
X1551875Y439260D03*
Y412220D03*
X1542125Y408840D03*
X1545425Y421475D03*
Y424625D03*
Y427775D03*
Y430925D03*
Y434075D03*
X1547975Y425740D03*
Y432500D03*
X1545425Y415175D03*
Y418325D03*
Y437225D03*
Y440375D03*
X1547975Y439260D03*
X1549925Y435880D03*
X1529675Y446675D03*
X1532825Y443525D03*
Y446675D03*
X1535975Y443525D03*
Y446675D03*
X1539125Y443525D03*
Y446675D03*
X1542275Y443525D03*
X1529675D03*
X1542275Y446675D03*
X1535975Y415175D03*
X1532825D03*
X1555775Y412220D03*
X1557725Y408840D03*
X1551875Y405460D03*
X1563575Y452780D03*
X1559675D03*
X1547975Y459540D03*
X1536275D03*
X1540175D03*
X1551875D03*
X1555775D03*
X1544075D03*
X1542125Y462920D03*
X1567475Y452780D03*
X1557725Y456160D03*
X1569425Y435880D03*
X1565525D03*
Y442640D03*
X1567475Y446020D03*
X1569425Y449400D03*
X1559675Y446020D03*
X1563575D03*
X1567475Y439260D03*
X1561625Y449400D03*
X1569425Y442640D03*
X1559675Y405460D03*
X1555775D03*
X1567475Y425740D03*
X1563575D03*
X1555775Y439260D03*
X1559675D03*
X1567475Y412220D03*
X1563575D03*
Y418980D03*
X1567475D03*
X1565525Y422360D03*
X1569425D03*
Y429120D03*
X1565525D03*
X1569425Y408840D03*
X1565525D03*
X1569425Y415600D03*
X1565525D03*
X1557725Y429120D03*
X1553825D03*
X1555775Y432500D03*
X1559675D03*
Y418980D03*
X1555775D03*
X1553825Y422360D03*
X1557725D03*
X1549925Y442640D03*
X1547975Y418980D03*
X1530425Y462920D03*
X1534325D03*
X1565525D03*
X1561625D03*
X1563575Y459540D03*
Y479820D03*
X1565525Y469680D03*
X1567475Y473060D03*
Y486580D03*
X1569425Y469680D03*
X1553825D03*
Y476440D03*
Y483200D03*
X1555775Y473060D03*
Y479820D03*
X1530425Y469680D03*
X1532375Y486580D03*
X1534325Y469680D03*
Y483200D03*
X1536275Y473060D03*
X1538225Y476440D03*
X1540175Y473060D03*
X1542125Y469680D03*
Y476440D03*
X1544075Y466300D03*
Y479820D03*
X1546025Y469680D03*
X1547975Y473060D03*
Y486580D03*
X1551875Y466300D03*
Y473060D03*
Y479820D03*
Y486580D03*
X1528475Y473060D03*
X1540175Y466300D03*
X1538225Y469680D03*
X1532375Y466300D03*
X1528475D03*
X1536275D03*
X1563575Y486580D03*
X1561625Y483200D03*
X1569425D03*
X1565525D03*
X1567475Y479820D03*
X1569425Y476440D03*
X1561625D03*
X1557725D03*
X1547975Y466300D03*
X1549925Y469680D03*
X1544075Y486580D03*
X1542125Y483200D03*
X1549925D03*
X1546025D03*
Y476440D03*
X1544075Y473060D03*
X1549925Y476440D03*
X1547975Y479820D03*
X1559675D03*
X1557725Y483200D03*
X1559675Y486580D03*
X1555775D03*
X1530425Y476440D03*
X1532375Y473060D03*
X1528475Y479820D03*
X1532375D03*
X1530425Y483200D03*
X1528475Y486580D03*
X1536275Y479820D03*
X1534325Y476440D03*
X1540175Y486580D03*
X1536275D03*
X1538225Y483200D03*
X1540175Y479820D03*
X1565525Y476440D03*
X1563575Y473060D03*
X1559675D03*
X1561625Y469680D03*
X1555775Y466300D03*
X1557725Y469680D03*
X1567475Y466300D03*
X1559675D03*
X1563575D03*
G54D13*
X-16420Y27510D03*
X-16320Y42550D03*
X-6380Y27510D03*
X-6280Y42550D03*
G54D304*
X1860500Y80585D03*
G54D340*
X1901804Y557807D03*
Y576807D03*
X1919504Y557807D03*
Y576807D03*
X1901804Y594001D03*
Y613001D03*
X1919504Y594001D03*
Y613001D03*
G54D124*
X405412Y201203D03*
X402032Y199254D03*
X398652Y197303D03*
X553387Y212190D03*
X550007Y210240D03*
X556767D03*
X553387Y208291D03*
X550007Y206341D03*
X546627Y204390D03*
X553387D03*
X543247Y202441D03*
X550007D03*
X1055020Y201203D03*
X1051640Y199254D03*
X1048260Y197303D03*
X1202995Y212190D03*
X1199615Y210240D03*
X1206375D03*
X1202995Y208291D03*
X1199615Y206341D03*
X1196235Y204390D03*
X1202995D03*
X1192855Y202441D03*
X1199615D03*
G54D205*
X1382500Y381270D03*
X1437930Y459805D03*
X1429229Y548455D03*
X1602520Y425800D03*
X1597400Y424761D03*
G54D350*
G01X1663662Y-41408D02*
X1470810D01*
G03Y-45109I0J-1850D01*
G01X1662493D01*
G02Y-52410I0J-3651D01*
G01X1463564D01*
X1459311Y-48157D01*
X1396358D01*
X1392258Y-52257D01*
G01X1663662Y-39608D02*
X1470809D01*
G03X1470811Y-46909I1J-3650D01*
G01X1662493D01*
G02Y-50610I0J-1851D01*
G01X1464310D01*
X1460057Y-46357D01*
X1396358D01*
X1392258Y-42257D01*
G01X1652186Y365600D02*
Y364299D01*
X1651883Y363996D01*
X1651074D01*
X1650220Y364850D01*
X1648800D01*
G01Y361350D02*
X1650261D01*
X1651101Y362190D01*
X1651860D01*
X1652186Y361864D01*
Y360600D01*
G01X1640266Y365500D02*
X1641760Y364006D01*
X1642860D01*
X1643704Y364850D01*
X1645300D01*
G01X1640266Y360500D02*
Y361093D01*
X1641373Y362200D01*
X1642854D01*
X1643704Y361350D01*
X1645300D01*
G54D152*
X700484Y41350D03*
X702453D03*
X704421D03*
X706390D03*
X708358D03*
X690642D03*
X692610D03*
X694579D03*
X696547D03*
X698516D03*
X700484Y527600D03*
X702453D03*
X704421D03*
X706390D03*
X708358D03*
X690642D03*
X692610D03*
X694579D03*
X696547D03*
X698516D03*
X1360684Y101300D03*
X1362653D03*
X1364621D03*
X1366590D03*
X1368558D03*
X1350842D03*
X1352810D03*
X1354779D03*
X1356747D03*
X1358716D03*
X1355484Y511900D03*
X1357453D03*
X1359421D03*
X1361390D03*
X1363358D03*
X1345642D03*
X1347610D03*
X1349579D03*
X1351547D03*
X1353516D03*
G54D161*
X715095Y244080D03*
Y236480D03*
X723604Y237024D03*
Y229424D03*
X693061Y228414D03*
Y236014D03*
X732344Y237043D03*
Y229443D03*
X741055Y241836D03*
Y234236D03*
X1384771Y79997D03*
Y87597D03*
X1376912Y79978D03*
Y87578D03*
X1372000Y414300D03*
Y406700D03*
X1364000Y414300D03*
Y406700D03*
X1441554Y578539D03*
Y586139D03*
X1456514Y618961D03*
Y611361D03*
X1448514Y618961D03*
Y611361D03*
X1440514Y618961D03*
Y611361D03*
X1519200Y253300D03*
Y260900D03*
X1526900Y253300D03*
Y260900D03*
X1520650Y275000D03*
Y267400D03*
X1528450Y275000D03*
Y267400D03*
X1603940Y223735D03*
Y231335D03*
X1596340Y223735D03*
Y231335D03*
X1874141Y84412D03*
Y92012D03*
X1881900Y84400D03*
Y92000D03*
X1896900Y79500D03*
Y87100D03*
X1861670Y110400D03*
Y102800D03*
X1929718Y216175D03*
X1938491Y216142D03*
X1929718Y223775D03*
X1938491Y223742D03*
X1938900Y239800D03*
Y232200D03*
X1930600Y239800D03*
Y232200D03*
G54D14*
X-13406Y73511D03*
Y59763D03*
X1427533Y572491D03*
Y586239D03*
G54D260*
X1632112Y252087D03*
Y256024D03*
Y259961D03*
X1615512Y242244D03*
Y246181D03*
Y250118D03*
Y254055D03*
Y257992D03*
X1632112Y244213D03*
Y248150D03*
X1615512Y261929D03*
G54D215*
X1446500Y382000D03*
Y394000D03*
G54D314*
X1887327Y511202D03*
X1929453Y532541D03*
G54D341*
X1970787Y139055D03*
Y196535D03*
G54D50*
X2940Y41740D03*
Y47240D03*
X116124Y112393D03*
Y106893D03*
X194600Y242848D03*
Y248348D03*
Y238348D03*
Y232848D03*
Y274000D03*
Y279500D03*
Y303000D03*
Y308500D03*
Y335730D03*
Y341230D03*
Y363600D03*
Y369100D03*
X411989Y274654D03*
Y269154D03*
X416889Y274654D03*
Y269154D03*
X407089Y274654D03*
Y269154D03*
X402148Y274841D03*
Y269341D03*
X397256Y274841D03*
Y269341D03*
X411060Y300154D03*
Y305654D03*
X415960Y300154D03*
Y305654D03*
X410860Y283000D03*
Y288500D03*
X415860Y283000D03*
Y288500D03*
X406160Y300154D03*
Y305654D03*
Y283154D03*
Y288654D03*
X416192Y318900D03*
Y313400D03*
X412407Y328713D03*
Y334213D03*
X417307Y328713D03*
Y334213D03*
X407507Y328713D03*
Y334213D03*
X406192Y318900D03*
Y313400D03*
X367360Y315654D03*
Y321154D03*
X372060Y315654D03*
Y321154D03*
X376760Y315654D03*
Y321154D03*
X382413Y324585D03*
Y330085D03*
X387892Y328000D03*
Y333500D03*
X402592Y328200D03*
Y333700D03*
X397692Y328200D03*
Y333700D03*
X392792Y328200D03*
Y333700D03*
X391492Y318900D03*
Y313400D03*
X386592Y318900D03*
Y313400D03*
X401292Y318900D03*
Y313400D03*
X396392Y318900D03*
Y313400D03*
X381692Y318900D03*
Y313400D03*
X391460Y300154D03*
Y305654D03*
X386560Y283154D03*
Y288654D03*
X376760Y300154D03*
Y305654D03*
X381660Y300154D03*
Y305654D03*
X366960Y300154D03*
Y305654D03*
X371860Y300154D03*
Y305654D03*
X381660Y283154D03*
Y288654D03*
X371860Y283154D03*
Y288654D03*
X366960Y283154D03*
Y288654D03*
X376760Y283154D03*
Y288654D03*
X386560Y300154D03*
Y305654D03*
X396360Y300154D03*
Y305654D03*
Y283154D03*
Y288654D03*
X401260Y300154D03*
Y305654D03*
Y283154D03*
Y288654D03*
X391460Y283154D03*
Y288654D03*
X411192Y318900D03*
Y313400D03*
X421789Y274654D03*
Y269154D03*
X446563Y299154D03*
Y304654D03*
X448298Y287841D03*
Y282341D03*
X420860Y300154D03*
Y305654D03*
Y283000D03*
Y288500D03*
X440860Y283154D03*
Y288654D03*
X430860Y283154D03*
Y288654D03*
X435860Y283154D03*
Y288654D03*
X426648Y299341D03*
Y304841D03*
X425860Y283154D03*
Y288654D03*
X451463Y299154D03*
Y304654D03*
X436648Y299341D03*
Y304841D03*
X453298Y287841D03*
Y282341D03*
X431648Y299341D03*
Y304841D03*
X441663Y299154D03*
Y304654D03*
X426192Y318900D03*
Y313400D03*
X451192Y318900D03*
Y313400D03*
X436192Y318900D03*
Y313400D03*
X431192Y318900D03*
Y313400D03*
X441192Y318900D03*
Y313400D03*
X446192Y318900D03*
Y313400D03*
X427115Y328713D03*
Y334213D03*
X422207Y328713D03*
Y334213D03*
X458148Y314841D03*
Y320341D03*
X421192Y318900D03*
Y313400D03*
X637000Y244000D03*
Y249500D03*
Y239000D03*
Y233500D03*
X665550Y516300D03*
Y521800D03*
X719100Y572000D03*
Y577500D03*
X824000Y196792D03*
Y202292D03*
X844500Y238480D03*
Y232980D03*
Y242980D03*
Y248480D03*
Y271500D03*
Y277000D03*
Y303200D03*
Y308700D03*
Y334750D03*
Y340250D03*
X845900Y366300D03*
Y371800D03*
X1031268Y300154D03*
Y305654D03*
Y283154D03*
Y288654D03*
X1021468Y315654D03*
Y321154D03*
X1026368Y315654D03*
Y321154D03*
X1016568Y315604D03*
Y321104D03*
X1031300Y318900D03*
Y313400D03*
X1032021Y324585D03*
Y330085D03*
X1021468Y283154D03*
Y288654D03*
X1016568Y300154D03*
Y305654D03*
Y283154D03*
Y288654D03*
X1026368Y300154D03*
Y305654D03*
X1021468Y300154D03*
Y305654D03*
X1026368Y283154D03*
Y288654D03*
X1061597Y274654D03*
Y269154D03*
X1071397Y274654D03*
Y269154D03*
X1066497Y274654D03*
Y269154D03*
X1056697Y274654D03*
Y269154D03*
X1051756Y274841D03*
Y269341D03*
X1046856Y274841D03*
Y269341D03*
X1091271Y299154D03*
Y304654D03*
X1096171Y299154D03*
Y304654D03*
X1090468Y283154D03*
Y288654D03*
X1081256Y299341D03*
Y304841D03*
X1086256Y299341D03*
Y304841D03*
X1085468Y283154D03*
Y288654D03*
X1080468Y283154D03*
Y288654D03*
X1076256Y299341D03*
Y304841D03*
X1075468Y283154D03*
Y288654D03*
X1075800Y318900D03*
Y313400D03*
X1080800Y318900D03*
Y313400D03*
X1085800Y318900D03*
Y313400D03*
X1095800Y318900D03*
Y313400D03*
X1090800Y318900D03*
Y313400D03*
X1080445Y328343D03*
Y333843D03*
X1065800Y318900D03*
Y313400D03*
X1046000Y318900D03*
Y313400D03*
X1041100Y318900D03*
Y313400D03*
X1036200Y318900D03*
Y313400D03*
X1055800Y318900D03*
Y313400D03*
X1050900Y318900D03*
Y313400D03*
X1062015Y328713D03*
Y334213D03*
X1066915Y328713D03*
Y334213D03*
X1071815Y328713D03*
Y334213D03*
X1052200Y328200D03*
Y333700D03*
X1057115Y328713D03*
Y334213D03*
X1047300Y328200D03*
Y333700D03*
X1037500Y328000D03*
Y333500D03*
X1042400Y328200D03*
Y333700D03*
X1070468Y283000D03*
Y288500D03*
X1065568Y300154D03*
Y305654D03*
X1065468Y283000D03*
Y288500D03*
X1070468Y300154D03*
Y305654D03*
X1045968Y300154D03*
Y305654D03*
Y283154D03*
Y288654D03*
X1041068Y300154D03*
Y305654D03*
Y283154D03*
Y288654D03*
X1036168Y300154D03*
Y305654D03*
Y283154D03*
Y288654D03*
X1060668Y300154D03*
Y305654D03*
X1050868Y300154D03*
Y305654D03*
X1055768Y300154D03*
Y305654D03*
X1060468Y283000D03*
Y288500D03*
X1055768Y283154D03*
Y288654D03*
X1050868Y283154D03*
Y288654D03*
X1060800Y318900D03*
Y313400D03*
X1070800Y318900D03*
Y313400D03*
X1101071Y299154D03*
Y304654D03*
X1102906Y287841D03*
Y282341D03*
X1097906Y287841D03*
Y282341D03*
X1100800Y318900D03*
Y313400D03*
X1109356Y313150D03*
Y318650D03*
X1341634Y100694D03*
Y106194D03*
X1335664Y514096D03*
Y519596D03*
X1320049Y504266D03*
Y509766D03*
X1383506Y22417D03*
Y16917D03*
X1453900Y385100D03*
Y390600D03*
X1455600Y422100D03*
Y427600D03*
X1464600Y524200D03*
Y518700D03*
X1455600Y519000D03*
Y513500D03*
X1450400Y519000D03*
Y513500D03*
X1469600Y524200D03*
Y518700D03*
X1478500Y525500D03*
Y520000D03*
X1487450Y534300D03*
Y539800D03*
X1579700Y517900D03*
Y512400D03*
X1589100Y499750D03*
Y505250D03*
X1574700Y517900D03*
Y512400D03*
X1584000Y606000D03*
Y600500D03*
X1611630Y74134D03*
Y79134D03*
X1607000Y491500D03*
Y497000D03*
X1612000Y491500D03*
Y497000D03*
X1594300Y499750D03*
Y505250D03*
X1599500Y499750D03*
Y505250D03*
X1832000Y157000D03*
Y162500D03*
X1847650Y104640D03*
Y99140D03*
G54D242*
X1473888Y615130D03*
X1475660D03*
X1477431D03*
X1479203D03*
X1480975D03*
X1482746D03*
X1484518D03*
X1486290D03*
X1488061D03*
X1489833D03*
X1509426Y616398D03*
X1511198D03*
X1512969D03*
X1514741D03*
X1516513D03*
X1518284D03*
X1520056D03*
X1521828D03*
X1523599D03*
X1525371D03*
G54D23*
X-15831Y547265D03*
X-15361Y583807D03*
X4400Y71700D03*
X-1100D03*
X-10331Y547265D03*
X-9861Y583807D03*
X47070Y607000D03*
X69652Y4240D03*
X75152D03*
X108500Y259500D03*
Y227500D03*
X107966Y290332D03*
X108200Y322500D03*
X52570Y607000D03*
X168200Y207870D03*
X114000Y259500D03*
Y227500D03*
X113466Y290332D03*
X113700Y322500D03*
X116250Y356500D03*
X110750D03*
X116120Y388180D03*
X110620D03*
X173700Y207870D03*
X179150Y202100D03*
X173650D03*
X386048Y275141D03*
X391548D03*
X386056Y270241D03*
X391556D03*
X599000Y13000D03*
Y51000D03*
X598950Y89550D03*
X598900Y513200D03*
X598800Y551200D03*
Y589000D03*
X616500Y13000D03*
X611000D03*
X604500D03*
X660112Y39650D03*
X654612D03*
X616900Y51000D03*
X611400D03*
X616150Y89550D03*
X610650D03*
X604500Y51000D03*
X604450Y89550D03*
X643300Y295200D03*
X637800D03*
X615900Y513200D03*
X610400D03*
X604400D03*
X618000Y589000D03*
X612500D03*
X618500Y551200D03*
X613000D03*
X604300D03*
Y589000D03*
X720596Y84030D03*
X726096D03*
X675972Y40376D03*
X681472D03*
X671261Y40403D03*
X665761D03*
X718000Y211000D03*
X723500D03*
X677600Y526000D03*
X683100D03*
X672895Y526398D03*
X667395D03*
X689680Y582490D03*
X684180D03*
X670700Y569400D03*
X665200D03*
X763500Y228000D03*
X758000D03*
X764500Y260105D03*
X759000D03*
X763950Y323658D03*
X758450D03*
X761700Y292000D03*
X756200D03*
X763875Y355850D03*
X758375D03*
X765400Y388700D03*
X759900D03*
X818500Y207870D03*
X824000D03*
X1035656Y270241D03*
X1041156D03*
X1035656Y275141D03*
X1041156D03*
X1248608Y13000D03*
X1254108D03*
X1266108D03*
X1260608D03*
X1248608Y51000D03*
X1254108D03*
X1266508D03*
X1261008D03*
X1248608Y89528D03*
X1254108D03*
X1266108D03*
X1260608D03*
X1249000Y513200D03*
X1254500D03*
X1265500D03*
X1260000D03*
X1248608Y552000D03*
X1254108D03*
X1266508D03*
X1261008D03*
X1248608Y590000D03*
X1254108D03*
X1266108D03*
X1260608D03*
X1319200Y99450D03*
X1313700D03*
X1337134Y99469D03*
X1331634D03*
X1341700Y409200D03*
X1336200D03*
X1341700Y404300D03*
X1336200D03*
X1330342Y513603D03*
X1324842D03*
X1382247Y-9885D03*
X1387747D03*
X1385946Y379926D03*
X1391446D03*
X1385116Y568907D03*
X1390616D03*
X1385250Y599500D03*
X1390750D03*
X1444047Y402785D03*
X1449547D03*
X1507300Y552900D03*
X1501800D03*
X1507300Y558050D03*
X1501800D03*
X1515829Y556974D03*
X1521329D03*
X1515970Y551760D03*
X1521470D03*
X1485000Y622600D03*
X1490500D03*
X1521094Y622646D03*
X1526594D03*
X1559545Y274225D03*
X1554045D03*
X1585170Y571204D03*
X1558950Y578800D03*
X1553450D03*
X1606500Y371948D03*
X1601000D03*
X1606500Y367248D03*
X1601000D03*
X1600750Y460500D03*
X1595250D03*
X1600750Y465500D03*
X1595250D03*
X1624000Y502200D03*
X1618500D03*
X1590670Y571204D03*
X1596004Y601196D03*
X1590504D03*
X1765753Y115662D03*
X1760253D03*
X1784500Y105700D03*
X1779000D03*
X1791750Y97800D03*
X1797250D03*
X1836630Y138000D03*
X1797348Y166937D03*
X1802848D03*
X1842130Y138000D03*
X1887100Y546100D03*
X1881600D03*
G54D170*
X1267805Y253386D03*
G54D251*
X1550750Y270437D03*
Y268469D03*
Y266500D03*
Y264531D03*
Y262563D03*
X1537250D03*
Y264531D03*
Y266500D03*
Y268469D03*
Y270437D03*
G54D134*
X655500Y57400D03*
X655600Y543750D03*
X677000Y57400D03*
X677100Y543750D03*
X1314300Y116800D03*
X1335800D03*
X1308150Y529500D03*
X1329650D03*
X1589980Y270040D03*
X1568480D03*
G54D116*
X276763Y400315D03*
X283523D03*
X286903Y398366D03*
X283523Y396415D03*
X280143Y394465D03*
X276763Y392516D03*
X273383Y390566D03*
X270003Y388615D03*
X424738Y403502D03*
X421358Y401553D03*
X428118Y405453D03*
X926371Y400315D03*
X933131D03*
X936511Y398366D03*
X933131Y396415D03*
X929751Y394465D03*
X926371Y392516D03*
X922991Y390566D03*
X919611Y388615D03*
X1074346Y403502D03*
X1070966Y401553D03*
X1077726Y405453D03*
G54D125*
X405412Y400315D03*
X408792Y398366D03*
X539867Y403502D03*
X536487Y405453D03*
X546627Y403502D03*
X543247Y401553D03*
X550007D03*
X546627Y399602D03*
X553387D03*
X550007Y397652D03*
X553387Y395703D03*
X543247Y405453D03*
X1055020Y400315D03*
X1058400Y398366D03*
X1189475Y403502D03*
X1196235D03*
X1192855Y401553D03*
X1199615D03*
X1196235Y399602D03*
X1202995D03*
X1199615Y397652D03*
X1202995Y395703D03*
X1186095Y405453D03*
X1192855D03*
G54D41*
X24047Y37443D03*
X24372Y68810D03*
X13947Y544099D03*
Y580099D03*
X138071Y224632D03*
Y288632D03*
Y256632D03*
Y320632D03*
Y352632D03*
Y384632D03*
X787679Y224632D03*
Y256632D03*
Y288632D03*
Y320632D03*
Y352632D03*
X787629Y384632D03*
G54D233*
X1519626Y368287D03*
X1492067D03*
X1527500D03*
X1523563D03*
X1511752D03*
X1507815D03*
X1496004D03*
X1503878D03*
X1515689D03*
X1499941D03*
X1527500Y496713D03*
X1511752D03*
X1507815D03*
X1519626D03*
X1523563D03*
X1492067D03*
X1496004D03*
X1499941D03*
X1503878D03*
X1515689D03*
X1558996Y368287D03*
X1531437D03*
X1562933D03*
X1539311D03*
X1535374D03*
X1555059D03*
X1543248D03*
X1547185D03*
X1551122D03*
X1562933Y496713D03*
X1535374D03*
X1547185D03*
X1543248D03*
X1539311D03*
X1531437D03*
X1551122D03*
X1555059D03*
X1558996D03*
G54D32*
X21464Y-11490D03*
X2661Y485075D03*
X-4896Y485081D03*
X1347816Y43361D03*
G54D143*
X666327Y387100D03*
Y415100D03*
X1317000Y72800D03*
Y44800D03*
X1295200Y133050D03*
Y105050D03*
X1454600Y584100D03*
Y556100D03*
G54D224*
X1424210Y551042D03*
Y549467D03*
Y547892D03*
Y546317D03*
Y544742D03*
Y543168D03*
Y541593D03*
Y540018D03*
Y538443D03*
Y536868D03*
X1567850Y612587D03*
Y611012D03*
Y609437D03*
Y607862D03*
Y606287D03*
Y604713D03*
Y603138D03*
Y601563D03*
Y599988D03*
Y598413D03*
G54D332*
X1899900Y206900D03*
X1898800Y195344D03*
G54D107*
X57684Y647714D03*
Y651654D03*
X206696Y647686D03*
Y651626D03*
X246406Y647814D03*
Y651754D03*
X394280Y647566D03*
Y651506D03*
X433874Y647544D03*
Y651484D03*
X581748Y647296D03*
Y651236D03*
X621422Y647275D03*
Y651215D03*
X897391Y647275D03*
Y651215D03*
X937076Y647264D03*
Y651204D03*
X1210917Y647264D03*
Y651204D03*
X1250574Y647294D03*
Y651234D03*
X1524415Y647294D03*
Y651234D03*
X1570023Y104172D03*
X1611500Y401437D03*
X1731124Y583524D03*
X1729700Y564500D03*
G54D305*
X1860500Y87800D03*
G54D323*
X1939509Y89356D03*
G54D206*
X1391987Y482515D03*
X1404310Y492405D03*
G54D360*
G01X1462896Y431162D02*
X1460251Y428517D01*
G01X1436000Y551500D02*
X1441502Y545998D01*
Y535602D01*
X1440500Y534600D01*
X1439200D01*
G01X1640512Y110766D02*
X1641849Y109429D01*
Y99324D01*
X1643478Y97695D01*
Y91473D01*
G01X1621615Y104467D02*
Y101207D01*
X1619042Y98634D01*
Y93783D01*
X1618185Y92926D01*
X1617550D01*
X1616436Y91812D01*
Y89264D01*
X1616660Y89040D01*
Y82791D01*
X1619498Y79953D01*
X1619891D01*
X1620241Y79603D01*
X1621882D01*
X1624403Y82124D01*
X1625727D01*
X1627743Y80108D01*
Y77757D01*
X1632000Y73500D01*
G01X1615749Y96720D02*
Y93967D01*
X1614366Y92584D01*
Y90829D01*
G01X1615316Y123365D02*
X1613741Y121790D01*
G01X1616890Y118641D02*
X1620040D01*
X1621615Y117066D01*
G01X1609016Y126514D02*
X1610591Y124939D01*
G01X1615316Y139113D02*
X1613741Y140688D01*
G01X1607441Y124939D02*
X1605867Y126513D01*
Y126514D01*
G01X1615749Y96720D02*
Y98204D01*
X1618465Y100920D01*
Y104467D01*
G01X1649961Y154861D02*
X1649960D01*
X1648386Y156435D01*
G01X1594565Y148720D02*
X1597880D01*
X1599700Y146900D01*
X1604379D01*
X1605867Y145412D01*
G01X1611500Y172900D02*
X1611900D01*
X1613800Y171000D01*
Y168975D01*
X1615316Y167459D01*
G01X1612166Y164310D02*
X1610591Y162735D01*
G01X1649961Y167459D02*
X1651536Y165884D01*
G01X1622217Y177809D02*
X1622200D01*
Y177700D01*
X1623062Y176838D01*
X1624349D01*
X1626449Y174738D01*
Y169144D01*
X1624764Y167459D01*
G01X1615316Y164310D02*
X1613741Y165885D01*
G01X1618465Y164310D02*
Y164311D01*
X1616891Y165885D01*
G01X1621615Y167459D02*
X1620118Y168956D01*
X1620006D01*
G01X1615316Y158010D02*
X1613741Y159585D01*
G01X1618465Y161160D02*
X1616890Y162735D01*
G01X1612166Y167459D02*
X1612165D01*
X1610591Y165885D01*
G01X1618465Y158010D02*
X1616890Y159585D01*
G01X1595042Y172184D02*
X1596235Y170991D01*
Y170233D01*
X1597744Y168724D01*
Y167143D01*
X1599132Y165755D01*
X1603801D01*
X1605246Y164310D01*
X1605867D01*
G01X1643662Y170609D02*
Y172609D01*
G01X1653111Y154861D02*
X1653110D01*
X1651536Y156435D01*
G01X1659410Y135963D02*
X1659411D01*
X1660986Y137538D01*
G01X1662560Y145412D02*
X1664186Y147038D01*
G01X1662560Y135963D02*
X1662561D01*
X1664136Y137538D01*
G01X1653111Y132814D02*
X1654686Y134389D01*
G01X1662560Y123365D02*
X1664135Y121790D01*
G01X1659410Y123365D02*
X1660985Y121790D01*
G01X1656260Y123365D02*
X1657835Y121790D01*
G01X1653111Y123365D02*
Y123364D01*
X1654685Y121790D01*
G01X1662560Y132814D02*
X1664135Y131239D01*
G01X1662560Y129664D02*
X1664135Y128089D01*
G01X1656260Y135963D02*
X1656261D01*
X1657836Y137538D01*
G01X1659410Y139113D02*
Y139114D01*
X1657836Y140688D01*
G01X1679250Y100886D02*
X1677506D01*
G01X1656260Y164310D02*
X1656261D01*
X1657835Y165884D01*
G01X1659410Y161160D02*
X1657835Y162735D01*
G01X1706620Y172616D02*
X1694715D01*
X1692845Y170746D01*
G01X1679062Y165416D02*
X1678097Y164451D01*
G01D02*
X1671656Y158010D01*
X1668859D01*
G01X1662560D02*
X1660985Y159585D01*
G01X1665709Y170609D02*
Y171962D01*
X1665063Y172608D01*
G01X1653111Y158010D02*
Y158158D01*
X1654638Y159685D01*
G01X1659410Y158010D02*
X1660985Y156435D01*
G01X1656949Y186868D02*
Y186388D01*
X1658000Y185337D01*
G01X1674455Y172658D02*
X1675088D01*
X1676030Y171716D01*
Y167330D01*
X1669860Y161160D01*
X1668859D01*
G01X1656260Y158010D02*
X1654686Y156436D01*
G01X1653111Y170609D02*
Y175777D01*
X1653709Y176375D01*
Y180261D01*
X1655209Y181761D01*
G01X1662560Y161160D02*
X1660985Y162735D01*
G01X1656260Y161160D02*
X1657835Y159585D01*
G54D351*
G01X548049Y-193422D02*
Y-210922D01*
G01X543027Y-193422D02*
X553071D01*
G01X565549Y-199256D02*
Y-210922D01*
G01Y-194589D02*
X565112Y-194297D01*
Y-193714D01*
X565549Y-193422D01*
X565986Y-193714D01*
Y-194297D01*
X565549Y-194589D01*
G01X583049Y-210922D02*
X581739Y-210630D01*
X580429Y-209464D01*
X579555Y-207422D01*
X579119Y-205089D01*
X579555Y-202755D01*
X580429Y-200714D01*
X581739Y-199547D01*
X583049Y-199256D01*
X584359Y-199547D01*
X585669Y-200714D01*
X586542Y-202755D01*
X586761Y-205089D01*
X586542Y-207422D01*
X585669Y-209464D01*
X584359Y-210630D01*
X583049Y-210922D01*
G01X597492Y-215297D02*
X599021Y-216464D01*
X600767Y-216755D01*
X602295Y-216464D01*
X603606Y-215006D01*
X604479Y-212964D01*
Y-199256D01*
G01Y-201589D02*
X603606Y-200422D01*
X602295Y-199547D01*
X600767Y-199256D01*
X599021Y-199839D01*
X597929Y-201005D01*
X597055Y-203047D01*
X596619Y-205089D01*
X596837Y-206839D01*
X597711Y-208881D01*
X599021Y-210339D01*
X600767Y-210922D01*
X602077Y-210630D01*
X603606Y-209464D01*
X604479Y-208298D01*
G01X621979Y-210922D02*
Y-199256D01*
G01Y-201297D02*
X621106Y-200131D01*
X619795Y-199547D01*
X618267Y-199256D01*
X616739Y-199839D01*
X615429Y-201005D01*
X614555Y-202755D01*
X614119Y-205089D01*
X614555Y-207422D01*
X615429Y-209172D01*
X616739Y-210339D01*
X618267Y-210922D01*
X619795Y-210630D01*
X621106Y-209756D01*
X621979Y-208589D01*
G01X648682Y-210922D02*
Y-193422D01*
X653922D01*
X655669Y-194297D01*
X656979Y-196339D01*
X657416Y-198672D01*
X656979Y-201005D01*
X655887Y-202755D01*
X653922Y-203631D01*
X648682D01*
G01X674479Y-210922D02*
Y-199256D01*
G01Y-201297D02*
X673606Y-200131D01*
X672295Y-199547D01*
X670767Y-199256D01*
X669239Y-199839D01*
X667929Y-201005D01*
X667055Y-202755D01*
X666619Y-205089D01*
X667055Y-207422D01*
X667929Y-209172D01*
X669239Y-210339D01*
X670767Y-210922D01*
X672295Y-210630D01*
X673606Y-209756D01*
X674479Y-208589D01*
G01X684774Y-208881D02*
X685866Y-210047D01*
X687394Y-210922D01*
X688704D01*
X690014Y-210339D01*
X690887Y-209464D01*
X691324Y-208298D01*
X691106Y-206547D01*
X690232Y-205672D01*
X686302Y-203922D01*
X685429Y-201880D01*
X685866Y-200422D01*
X686739Y-199547D01*
X688049Y-199256D01*
X689359Y-199547D01*
X690669Y-200422D01*
G01X702274Y-208881D02*
X703366Y-210047D01*
X704894Y-210922D01*
X706204D01*
X707514Y-210339D01*
X708387Y-209464D01*
X708824Y-208298D01*
X708606Y-206547D01*
X707732Y-205672D01*
X703802Y-203922D01*
X702929Y-201880D01*
X703366Y-200422D01*
X704239Y-199547D01*
X705549Y-199256D01*
X706859Y-199547D01*
X708169Y-200422D01*
G01X735746Y-210922D02*
Y-193422D01*
X740112D01*
X741859Y-194297D01*
X743169Y-195464D01*
X744261Y-197213D01*
X745134Y-199256D01*
X745352Y-202172D01*
X745134Y-205089D01*
X744261Y-207131D01*
X743169Y-208881D01*
X741859Y-210047D01*
X740112Y-210922D01*
X735746D01*
G01X752590Y-193422D02*
X758049Y-210922D01*
X763508Y-193422D01*
G01X775549D02*
Y-210922D01*
G01X770527Y-193422D02*
X780571D01*
G01X804872Y-210922D02*
Y-193422D01*
X810549Y-208005D01*
X816226Y-193422D01*
Y-210922D01*
G01X829795Y-201589D02*
X830669Y-200714D01*
X831324Y-199256D01*
X831761Y-197213D01*
X831324Y-195464D01*
X830451Y-194297D01*
X828922Y-193422D01*
X823027D01*
Y-210922D01*
X830232D01*
X831761Y-209756D01*
X832634Y-208005D01*
X833071Y-205964D01*
X832634Y-203922D01*
X831324Y-202172D01*
X829795Y-201589D01*
X823027D01*
G01X647372Y-165922D02*
Y-148422D01*
X653049Y-163005D01*
X658726Y-148422D01*
Y-165922D01*
G01X670549D02*
X669239Y-165630D01*
X667929Y-164464D01*
X667055Y-162422D01*
X666619Y-160089D01*
X667055Y-157755D01*
X667929Y-155714D01*
X669239Y-154547D01*
X670549Y-154256D01*
X671859Y-154547D01*
X673169Y-155714D01*
X674042Y-157755D01*
X674261Y-160089D01*
X674042Y-162422D01*
X673169Y-164464D01*
X671859Y-165630D01*
X670549Y-165922D01*
G01X691979Y-148422D02*
Y-165922D01*
G01Y-163298D02*
X691106Y-164756D01*
X689795Y-165630D01*
X688267Y-165922D01*
X686521Y-165339D01*
X685211Y-163881D01*
X684337Y-162131D01*
X684119Y-160089D01*
X684337Y-158047D01*
X685211Y-156297D01*
X686521Y-154839D01*
X688267Y-154256D01*
X689795Y-154547D01*
X690887Y-155131D01*
X691979Y-156297D01*
G01X702274Y-158047D02*
X709261D01*
X708606Y-156005D01*
X707514Y-154839D01*
X705986Y-154256D01*
X704457Y-154547D01*
X703147Y-155422D01*
X702274Y-157464D01*
X701837Y-159214D01*
Y-160964D01*
X702274Y-162714D01*
X703366Y-164464D01*
X704676Y-165630D01*
X706204Y-165922D01*
X707732Y-165339D01*
X709261Y-163589D01*
G01X723049Y-165922D02*
Y-148422D01*
G01X975549Y-210922D02*
Y-193422D01*
X972929Y-196922D01*
G01Y-210922D02*
X978169D01*
G01X988246Y-208298D02*
X989555Y-209756D01*
X991084Y-210630D01*
X993049Y-210922D01*
X995014Y-210339D01*
X996542Y-209172D01*
X997634Y-207131D01*
X997852Y-204797D01*
X997416Y-202464D01*
X996324Y-201005D01*
X994795Y-199839D01*
X993267Y-199547D01*
X991739Y-199839D01*
X989774Y-201005D01*
X990429Y-193422D01*
X996324D01*
G01X1010549Y-210922D02*
Y-193422D01*
X1007929Y-196922D01*
G01Y-210922D02*
X1013169D01*
G01X1023901Y-196339D02*
X1025211Y-194589D01*
X1026739Y-193714D01*
X1028486Y-193422D01*
X1030669Y-194005D01*
X1032197Y-195464D01*
X1032634Y-197213D01*
X1032416Y-198964D01*
X1031542Y-200422D01*
X1027176Y-203339D01*
X1025211Y-205380D01*
X1023901Y-208298D01*
X1023464Y-210922D01*
X1032634D01*
G01X1041401Y-203631D02*
X1042929Y-201589D01*
X1044239Y-200422D01*
X1045986Y-199839D01*
X1047514Y-200422D01*
X1048606Y-201589D01*
X1049479Y-203339D01*
X1049697Y-205380D01*
X1049479Y-207131D01*
X1048606Y-208881D01*
X1047295Y-210339D01*
X1045767Y-210922D01*
X1044021Y-210339D01*
X1042492Y-208589D01*
X1041619Y-205964D01*
X1041401Y-203047D01*
X1041837Y-199256D01*
X1042492Y-197213D01*
X1043584Y-195172D01*
X1045112Y-193714D01*
X1046641Y-193422D01*
X1048169Y-194005D01*
X1049261Y-195464D01*
G01X962432Y-165922D02*
Y-148422D01*
X967672D01*
X969419Y-149297D01*
X970729Y-151339D01*
X971166Y-153672D01*
X970729Y-156005D01*
X969637Y-157755D01*
X967672Y-158631D01*
X962432D01*
G01X989102Y-149881D02*
X987792Y-149005D01*
X986264Y-148422D01*
X984517D01*
X982552Y-149297D01*
X981024Y-150755D01*
X979932Y-152506D01*
X979059Y-155422D01*
X978840Y-158047D01*
X979277Y-160672D01*
X979932Y-162422D01*
X981242Y-164172D01*
X982771Y-165339D01*
X984299Y-165922D01*
X985827D01*
X987356Y-165339D01*
X988666Y-164464D01*
X989758Y-163298D01*
G01X1003545Y-156589D02*
X1004419Y-155714D01*
X1005074Y-154256D01*
X1005511Y-152213D01*
X1005074Y-150464D01*
X1004201Y-149297D01*
X1002672Y-148422D01*
X996777D01*
Y-165922D01*
X1003982D01*
X1005511Y-164756D01*
X1006384Y-163005D01*
X1006821Y-160964D01*
X1006384Y-158922D01*
X1005074Y-157172D01*
X1003545Y-156589D01*
X996777D01*
G01X1012749Y-171755D02*
X1025849D01*
G01X1031777Y-165922D02*
Y-148422D01*
X1041821Y-165922D01*
Y-148422D01*
G01X1054299Y-165922D02*
X1052552Y-165630D01*
X1051024Y-164464D01*
X1049714Y-162714D01*
X1048840Y-160672D01*
X1048404Y-158339D01*
Y-156005D01*
X1048840Y-153672D01*
X1049714Y-151630D01*
X1051024Y-149881D01*
X1052552Y-148714D01*
X1054299Y-148422D01*
X1056045Y-148714D01*
X1057574Y-149881D01*
X1058884Y-151630D01*
X1059758Y-153672D01*
X1060194Y-156005D01*
Y-158339D01*
X1059758Y-160672D01*
X1058884Y-162714D01*
X1057574Y-164464D01*
X1056045Y-165630D01*
X1054299Y-165922D01*
G01X1128099Y-210922D02*
Y-193422D01*
X1125479Y-196922D01*
G01Y-210922D02*
X1130719D01*
G01X1147345Y-201589D02*
X1148219Y-200714D01*
X1148874Y-199256D01*
X1149311Y-197213D01*
X1148874Y-195464D01*
X1148001Y-194297D01*
X1146472Y-193422D01*
X1140577D01*
Y-210922D01*
X1147782D01*
X1149311Y-209756D01*
X1150184Y-208005D01*
X1150621Y-205964D01*
X1150184Y-203922D01*
X1148874Y-202172D01*
X1147345Y-201589D01*
X1140577D01*
G01X1105140Y-148422D02*
X1110599Y-165922D01*
X1116058Y-148422D01*
G01X1132466Y-165922D02*
X1123732D01*
Y-148422D01*
X1132466D01*
G01X1128972Y-156880D02*
X1123732D01*
G01X1141232Y-165922D02*
Y-148422D01*
X1146691D01*
X1148437Y-149297D01*
X1149529Y-150464D01*
X1149966Y-152797D01*
X1149529Y-155131D01*
X1148219Y-156589D01*
X1146691Y-157464D01*
X1141232D01*
G01X1146691D02*
X1149966Y-165922D01*
G01X1163099Y-166505D02*
X1162662Y-166214D01*
Y-165630D01*
X1163099Y-165339D01*
X1163536Y-165630D01*
Y-166214D01*
X1163099Y-166505D01*
G01X1264932Y-193422D02*
Y-210922D01*
X1273666D01*
G01X1286799D02*
Y-193422D01*
X1284179Y-196922D01*
G01Y-210922D02*
X1289419D01*
G01X1238682Y-148422D02*
Y-165922D01*
X1247416D01*
G01X1264479D02*
Y-154256D01*
G01Y-156297D02*
X1263606Y-155131D01*
X1262295Y-154547D01*
X1260767Y-154256D01*
X1259239Y-154839D01*
X1257929Y-156005D01*
X1257055Y-157755D01*
X1256619Y-160089D01*
X1257055Y-162422D01*
X1257929Y-164172D01*
X1259239Y-165339D01*
X1260767Y-165922D01*
X1262295Y-165630D01*
X1263606Y-164756D01*
X1264479Y-163589D01*
G01X1273464Y-171172D02*
X1274774Y-171755D01*
X1276521Y-171172D01*
X1277612Y-170006D01*
X1278486Y-168547D01*
X1279795Y-163881D01*
X1282634Y-154256D01*
G01X1275647D02*
X1279795Y-163881D01*
G01X1292274Y-158047D02*
X1299261D01*
X1298606Y-156005D01*
X1297514Y-154839D01*
X1295986Y-154256D01*
X1294457Y-154547D01*
X1293147Y-155422D01*
X1292274Y-157464D01*
X1291837Y-159214D01*
Y-160964D01*
X1292274Y-162714D01*
X1293366Y-164464D01*
X1294676Y-165630D01*
X1296204Y-165922D01*
X1297732Y-165339D01*
X1299261Y-163589D01*
G01X1309992Y-165922D02*
Y-154256D01*
G01Y-156589D02*
X1311084Y-155422D01*
X1312176Y-154547D01*
X1313704Y-154256D01*
X1314795Y-154547D01*
X1316106Y-155422D01*
G01X1380796Y-165922D02*
Y-148422D01*
X1385162D01*
X1386909Y-149297D01*
X1388219Y-150464D01*
X1389311Y-152213D01*
X1390184Y-154256D01*
X1390402Y-157172D01*
X1390184Y-160089D01*
X1389311Y-162131D01*
X1388219Y-163881D01*
X1386909Y-165047D01*
X1385162Y-165922D01*
X1380796D01*
G01X1399824Y-158047D02*
X1406811D01*
X1406156Y-156005D01*
X1405064Y-154839D01*
X1403536Y-154256D01*
X1402007Y-154547D01*
X1400697Y-155422D01*
X1399824Y-157464D01*
X1399387Y-159214D01*
Y-160964D01*
X1399824Y-162714D01*
X1400916Y-164464D01*
X1402226Y-165630D01*
X1403754Y-165922D01*
X1405282Y-165339D01*
X1406811Y-163589D01*
G01X1417324Y-163881D02*
X1418416Y-165047D01*
X1419944Y-165922D01*
X1421254D01*
X1422564Y-165339D01*
X1423437Y-164464D01*
X1423874Y-163298D01*
X1423656Y-161547D01*
X1422782Y-160672D01*
X1418852Y-158922D01*
X1417979Y-156880D01*
X1418416Y-155422D01*
X1419289Y-154547D01*
X1420599Y-154256D01*
X1421909Y-154547D01*
X1423219Y-155422D01*
G01X1438099Y-154256D02*
Y-165922D01*
G01Y-149589D02*
X1437662Y-149297D01*
Y-148714D01*
X1438099Y-148422D01*
X1438536Y-148714D01*
Y-149297D01*
X1438099Y-149589D01*
G01X1452542Y-170297D02*
X1454071Y-171464D01*
X1455817Y-171755D01*
X1457345Y-171464D01*
X1458656Y-170006D01*
X1459529Y-167964D01*
Y-154256D01*
G01Y-156589D02*
X1458656Y-155422D01*
X1457345Y-154547D01*
X1455817Y-154256D01*
X1454071Y-154839D01*
X1452979Y-156005D01*
X1452105Y-158047D01*
X1451669Y-160089D01*
X1451887Y-161839D01*
X1452761Y-163881D01*
X1454071Y-165339D01*
X1455817Y-165922D01*
X1457127Y-165630D01*
X1458656Y-164464D01*
X1459529Y-163298D01*
G01X1469387Y-165922D02*
Y-154256D01*
G01Y-157172D02*
X1470261Y-155714D01*
X1471571Y-154547D01*
X1473317Y-154256D01*
X1474845Y-154547D01*
X1476156Y-155714D01*
X1476811Y-157755D01*
Y-165922D01*
G01X1487324Y-158047D02*
X1494311D01*
X1493656Y-156005D01*
X1492564Y-154839D01*
X1491036Y-154256D01*
X1489507Y-154547D01*
X1488197Y-155422D01*
X1487324Y-157464D01*
X1486887Y-159214D01*
Y-160964D01*
X1487324Y-162714D01*
X1488416Y-164464D01*
X1489726Y-165630D01*
X1491254Y-165922D01*
X1492782Y-165339D01*
X1494311Y-163589D01*
G01X1505042Y-165922D02*
Y-154256D01*
G01Y-156589D02*
X1506134Y-155422D01*
X1507226Y-154547D01*
X1508754Y-154256D01*
X1509845Y-154547D01*
X1511156Y-155422D01*
G01X1426729Y-193422D02*
X1431969D01*
G01X1429349D02*
Y-210922D01*
G01X1426729D02*
X1431969D01*
G01X1441390Y-193422D02*
X1446849Y-210922D01*
X1452308Y-193422D01*
G01X1464349Y-210922D02*
Y-203047D01*
X1459982Y-193422D01*
G01X1468716D02*
X1464349Y-203047D01*
G01X1551799Y-193422D02*
X1550052Y-194005D01*
X1548742Y-195464D01*
X1547869Y-197213D01*
X1547214Y-199547D01*
X1546996Y-202172D01*
X1547214Y-204797D01*
X1547869Y-207131D01*
X1548742Y-208881D01*
X1550052Y-210339D01*
X1551799Y-210922D01*
X1553545Y-210339D01*
X1554856Y-208881D01*
X1555729Y-207131D01*
X1556384Y-204797D01*
X1556602Y-202172D01*
X1556384Y-199547D01*
X1555729Y-197213D01*
X1554856Y-195464D01*
X1553545Y-194005D01*
X1551799Y-193422D01*
G01X1565151Y-196339D02*
X1566461Y-194589D01*
X1567989Y-193714D01*
X1569736Y-193422D01*
X1571919Y-194005D01*
X1573447Y-195464D01*
X1573884Y-197213D01*
X1573666Y-198964D01*
X1572792Y-200422D01*
X1568426Y-203339D01*
X1566461Y-205380D01*
X1565151Y-208298D01*
X1564714Y-210922D01*
X1573884D01*
G01X1582869Y-211505D02*
X1590729Y-193422D01*
G01X1604299Y-210922D02*
Y-193422D01*
X1601679Y-196922D01*
G01Y-210922D02*
X1606919D01*
G01X1621799Y-193422D02*
X1620052Y-194005D01*
X1618742Y-195464D01*
X1617869Y-197213D01*
X1617214Y-199547D01*
X1616996Y-202172D01*
X1617214Y-204797D01*
X1617869Y-207131D01*
X1618742Y-208881D01*
X1620052Y-210339D01*
X1621799Y-210922D01*
X1623545Y-210339D01*
X1624856Y-208881D01*
X1625729Y-207131D01*
X1626384Y-204797D01*
X1626602Y-202172D01*
X1626384Y-199547D01*
X1625729Y-197213D01*
X1624856Y-195464D01*
X1623545Y-194005D01*
X1621799Y-193422D01*
G01X1635369Y-211505D02*
X1643229Y-193422D01*
G01X1652651Y-196339D02*
X1653961Y-194589D01*
X1655489Y-193714D01*
X1657236Y-193422D01*
X1659419Y-194005D01*
X1660947Y-195464D01*
X1661384Y-197213D01*
X1661166Y-198964D01*
X1660292Y-200422D01*
X1655926Y-203339D01*
X1653961Y-205380D01*
X1652651Y-208298D01*
X1652214Y-210922D01*
X1661384D01*
G01X1674299Y-193422D02*
X1672552Y-194005D01*
X1671242Y-195464D01*
X1670369Y-197213D01*
X1669714Y-199547D01*
X1669496Y-202172D01*
X1669714Y-204797D01*
X1670369Y-207131D01*
X1671242Y-208881D01*
X1672552Y-210339D01*
X1674299Y-210922D01*
X1676045Y-210339D01*
X1677356Y-208881D01*
X1678229Y-207131D01*
X1678884Y-204797D01*
X1679102Y-202172D01*
X1678884Y-199547D01*
X1678229Y-197213D01*
X1677356Y-195464D01*
X1676045Y-194005D01*
X1674299Y-193422D01*
G01X1691799Y-210922D02*
Y-193422D01*
X1689179Y-196922D01*
G01Y-210922D02*
X1694419D01*
G01X1708862D02*
X1709299Y-207131D01*
X1709954Y-203922D01*
X1710827Y-201005D01*
X1711919Y-197797D01*
X1713666Y-193422D01*
X1704932D01*
G01X1599496Y-165922D02*
Y-148422D01*
X1603862D01*
X1605609Y-149297D01*
X1606919Y-150464D01*
X1608011Y-152213D01*
X1608884Y-154256D01*
X1609102Y-157172D01*
X1608884Y-160089D01*
X1608011Y-162131D01*
X1606919Y-163881D01*
X1605609Y-165047D01*
X1603862Y-165922D01*
X1599496D01*
G01X1625729D02*
Y-154256D01*
G01Y-156297D02*
X1624856Y-155131D01*
X1623545Y-154547D01*
X1622017Y-154256D01*
X1620489Y-154839D01*
X1619179Y-156005D01*
X1618305Y-157755D01*
X1617869Y-160089D01*
X1618305Y-162422D01*
X1619179Y-164172D01*
X1620489Y-165339D01*
X1622017Y-165922D01*
X1623545Y-165630D01*
X1624856Y-164756D01*
X1625729Y-163589D01*
G01X1639299Y-148422D02*
Y-165922D01*
G01X1636242Y-154256D02*
X1642356D01*
G01X1653524Y-158047D02*
X1660511D01*
X1659856Y-156005D01*
X1658764Y-154839D01*
X1657236Y-154256D01*
X1655707Y-154547D01*
X1654397Y-155422D01*
X1653524Y-157464D01*
X1653087Y-159214D01*
Y-160964D01*
X1653524Y-162714D01*
X1654616Y-164464D01*
X1655926Y-165630D01*
X1657454Y-165922D01*
X1658982Y-165339D01*
X1660511Y-163589D01*
G01X41862Y-10625D02*
Y-12179D01*
X45113Y-15430D01*
Y-16137D01*
G01X4262Y75650D02*
X4800D01*
X7178Y73272D01*
X8466D01*
G01X445123Y399496D02*
Y399499D01*
X443993Y397546D01*
G01X697094Y506828D02*
X698750Y508484D01*
Y518150D01*
X699350Y518750D01*
X700500D01*
G01X977176Y265660D02*
X974926D01*
G01X1093601Y397546D02*
X1094731Y399499D01*
Y399496D01*
G01X1192749Y397546D02*
Y401447D01*
G01X1588864Y395630D02*
X1582620D01*
X1582000Y396250D01*
G01X1585791Y393509D02*
X1586400Y392900D01*
G54D33*
X21522Y11815D03*
X737700Y295500D03*
G54D180*
X1274699Y333959D03*
G54D207*
X1351800Y491619D03*
X1565079Y129375D03*
X1628655Y424800D03*
X1642515D03*
X1702140Y146363D03*
X1691776Y144438D03*
X1701890Y113250D03*
X1695119Y111254D03*
X1760339Y153550D03*
X1758228Y148550D03*
X1759589Y138950D03*
X1763217Y134550D03*
X1760240Y130050D03*
X1761298Y143850D03*
X1756589Y121000D03*
G54D261*
X1613069Y302692D03*
G54D342*
X1969883Y207007D03*
Y242441D03*
G54D51*
X23900Y87700D03*
X16300D03*
X36224Y491552D03*
X43824D03*
X36282Y499319D03*
X43882D03*
X722268Y35902D03*
X721192Y528243D03*
X729868Y35902D03*
X728792Y528243D03*
X1390595Y101089D03*
X1382995D03*
X1385800Y512000D03*
X1378200D03*
X1464300Y598500D03*
X1456700D03*
G54D144*
X634930Y487050D03*
X616930D03*
X634930Y481930D03*
X616930D03*
X634930Y484490D03*
X616930D03*
X634930Y479370D03*
X616930D03*
G54D216*
X1445300Y419350D03*
X1439000Y427618D03*
Y419350D03*
X1445300Y427618D03*
X1863750Y168234D03*
X1870050Y159966D03*
Y168234D03*
X1863750Y159966D03*
X1905450Y133010D03*
X1911750Y124742D03*
Y133010D03*
X1905450Y124742D03*
G54D171*
X1254526Y258759D03*
G54D243*
X1472332Y603850D03*
Y605622D03*
Y607393D03*
Y609165D03*
Y610937D03*
Y612708D03*
X1507870Y605118D03*
Y606890D03*
Y608661D03*
Y610433D03*
Y612205D03*
Y613976D03*
G54D324*
X1955426Y104548D03*
Y100612D03*
Y102580D03*
Y98644D03*
X1963526Y100612D03*
Y104548D03*
Y102580D03*
Y98644D03*
G54D333*
X1952250Y240355D03*
G54D108*
X167124Y3233D03*
X163777D03*
X160431D03*
X157084D03*
X153738D03*
X150392D03*
X147045D03*
X143699D03*
X140352D03*
X137006D03*
X133659D03*
X130313D03*
X126966D03*
X123620D03*
X120273D03*
X116927D03*
X167124Y-14877D03*
X163777D03*
X160431D03*
X157084D03*
X153738D03*
X150392D03*
X147045D03*
X143699D03*
X140352D03*
X137006D03*
X133659D03*
X130313D03*
X126966D03*
X123620D03*
X120273D03*
X116927D03*
X167124Y22923D03*
X163777D03*
X160431D03*
X157084D03*
X153738D03*
X150392D03*
X147045D03*
X143699D03*
X140352D03*
X137006D03*
X133659D03*
X130313D03*
X126966D03*
X123620D03*
X120273D03*
X116927D03*
X167124Y78833D03*
X163777D03*
X160431D03*
X157084D03*
X153738D03*
X150392D03*
X147045D03*
X143699D03*
X140352D03*
X137006D03*
X133659D03*
X130313D03*
X126966D03*
X123620D03*
X120273D03*
X116927D03*
X167124Y60723D03*
X163777D03*
X160431D03*
X157084D03*
X153738D03*
X150392D03*
X147045D03*
X143699D03*
X140352D03*
X137006D03*
X133659D03*
X130313D03*
X126966D03*
X123620D03*
X120273D03*
X116927D03*
X167124Y41033D03*
X163777D03*
X160431D03*
X157084D03*
X153738D03*
X150392D03*
X147045D03*
X143699D03*
X140352D03*
X137006D03*
X133659D03*
X130313D03*
X126966D03*
X123620D03*
X120273D03*
X116927D03*
X167124Y523900D03*
X163777D03*
X160431D03*
X157084D03*
X153738D03*
X150392D03*
X147045D03*
X143699D03*
X140352D03*
X137006D03*
X133659D03*
X130313D03*
X126966D03*
X123620D03*
X120273D03*
X116927D03*
X167124Y542010D03*
X163777D03*
X160431D03*
X157084D03*
X153738D03*
X150392D03*
X147045D03*
X143699D03*
X140352D03*
X137006D03*
X133659D03*
X130313D03*
X126966D03*
X123620D03*
X120273D03*
X116927D03*
Y561700D03*
Y579810D03*
X120273Y561700D03*
X126966D03*
X133659D03*
X143699D03*
X150392D03*
X157084D03*
X163777D03*
X123620Y579810D03*
X130313D03*
X137006D03*
X147045D03*
X153738D03*
X160431D03*
X167124D03*
X137006Y561700D03*
X140352D03*
X143699Y579810D03*
X140352D03*
X120273D03*
X167124Y561700D03*
X150392Y579810D03*
X147045Y561700D03*
X126966Y579810D03*
X123620Y561700D03*
X157084Y579810D03*
X153738Y561700D03*
X133659Y579810D03*
X163777D03*
X160431Y561700D03*
X130313D03*
X167124Y617610D03*
X163777D03*
X160431D03*
X157084D03*
X153738D03*
X150392D03*
X147045D03*
X143699D03*
X140352D03*
X137006D03*
X133659D03*
X130313D03*
X126966D03*
X123620D03*
X120273D03*
X116927D03*
X167124Y599500D03*
X163777D03*
X160431D03*
X157084D03*
X153738D03*
X150392D03*
X147045D03*
X143699D03*
X140352D03*
X137006D03*
X133659D03*
X130313D03*
X126966D03*
X123620D03*
X120273D03*
X116927D03*
X230707Y3233D03*
X227360D03*
X224014D03*
X220667D03*
X217321D03*
X213974D03*
X210628D03*
X207281D03*
X203935D03*
X200588D03*
X197242D03*
X193896D03*
X190549D03*
X187203D03*
X183856D03*
X180510D03*
X177163D03*
X173817D03*
X170470D03*
X230707Y-14877D03*
X227360D03*
X224014D03*
X220667D03*
X217321D03*
X213974D03*
X210628D03*
X207281D03*
X203935D03*
X200588D03*
X197242D03*
X193896D03*
X190549D03*
X187203D03*
X183856D03*
X180510D03*
X177163D03*
X173817D03*
X170470D03*
X230707Y22923D03*
X227360D03*
X224014D03*
X220667D03*
X217321D03*
X213974D03*
X210628D03*
X207281D03*
X203935D03*
X200588D03*
X197242D03*
X193896D03*
X190549D03*
X187203D03*
X183856D03*
X180510D03*
X177163D03*
X173817D03*
X170470D03*
X230707Y78833D03*
X227360D03*
X224014D03*
X220667D03*
X217321D03*
X213974D03*
X210628D03*
X207281D03*
X203935D03*
X200588D03*
X197242D03*
X193896D03*
X190549D03*
X187203D03*
X183856D03*
X180510D03*
X177163D03*
X173817D03*
X170470D03*
X230707Y60723D03*
X227360D03*
X224014D03*
X220667D03*
X217321D03*
X213974D03*
X210628D03*
X207281D03*
X203935D03*
X200588D03*
X197242D03*
X193896D03*
X190549D03*
X187203D03*
X183856D03*
X180510D03*
X177163D03*
X173817D03*
X170470D03*
X230707Y41033D03*
X227360D03*
X224014D03*
X220667D03*
X217321D03*
X213974D03*
X210628D03*
X207281D03*
X203935D03*
X200588D03*
X197242D03*
X193896D03*
X190549D03*
X187203D03*
X183856D03*
X180510D03*
X177163D03*
X173817D03*
X170470D03*
X230707Y523900D03*
X227360D03*
X224014D03*
X220667D03*
X217321D03*
X213974D03*
X210628D03*
X207281D03*
X203935D03*
X200588D03*
X197242D03*
X193896D03*
X190549D03*
X187203D03*
X183856D03*
X180510D03*
X177163D03*
X173817D03*
X170470D03*
X230707Y542010D03*
X227360D03*
X224014D03*
X220667D03*
X217321D03*
X213974D03*
X210628D03*
X207281D03*
X203935D03*
X200588D03*
X197242D03*
X193896D03*
X190549D03*
X187203D03*
X183856D03*
X180510D03*
X177163D03*
X173817D03*
X170470D03*
Y561700D03*
X180510D03*
X187203D03*
X193896D03*
X200588D03*
X207281D03*
X217321D03*
X224014D03*
X230707D03*
X173817Y579810D03*
X183856D03*
X190549D03*
X197242D03*
X203935D03*
X210628D03*
X220667D03*
X227360D03*
X217321D03*
X213974D03*
X180510D03*
X177163D03*
X210628Y561700D03*
X213974D03*
X173817D03*
X177163D03*
X170470Y579810D03*
X224014D03*
X220667Y561700D03*
X200588Y579810D03*
X197242Y561700D03*
X230707Y579810D03*
X227360Y561700D03*
X207281Y579810D03*
X203935Y561700D03*
X187203Y579810D03*
X183856Y561700D03*
X193896Y579810D03*
X190549Y561700D03*
X230707Y617610D03*
X227360D03*
X224014D03*
X220667D03*
X217321D03*
X213974D03*
X210628D03*
X207281D03*
X203935D03*
X200588D03*
X197242D03*
X193896D03*
X190549D03*
X187203D03*
X183856D03*
X180510D03*
X177163D03*
X173817D03*
X170470D03*
X230707Y599500D03*
X227360D03*
X224014D03*
X220667D03*
X217321D03*
X213974D03*
X210628D03*
X207281D03*
X203935D03*
X200588D03*
X197242D03*
X193896D03*
X190549D03*
X187203D03*
X183856D03*
X180510D03*
X177163D03*
X173817D03*
X170470D03*
X290943Y3233D03*
X287596D03*
X284250D03*
X280903D03*
X277557D03*
X274210D03*
X270864D03*
X267518D03*
X264171D03*
X260825D03*
X257478D03*
X254132D03*
X250785D03*
X247439D03*
X244092D03*
X240746D03*
X237399D03*
X234053D03*
X290943Y-14877D03*
X287596D03*
X284250D03*
X280903D03*
X277557D03*
X274210D03*
X270864D03*
X267518D03*
X264171D03*
X260825D03*
X257478D03*
X254132D03*
X250785D03*
X247439D03*
X244092D03*
X240746D03*
X237399D03*
X234053D03*
X290943Y22923D03*
X287596D03*
X284250D03*
X280903D03*
X277557D03*
X274210D03*
X270864D03*
X267518D03*
X264171D03*
X260825D03*
X257478D03*
X254132D03*
X250785D03*
X247439D03*
X244092D03*
X240746D03*
X237399D03*
X234053D03*
X290943Y78833D03*
X287596D03*
X284250D03*
X280903D03*
X277557D03*
X274210D03*
X270864D03*
X267518D03*
X264171D03*
X260825D03*
X257478D03*
X254132D03*
X250785D03*
X247439D03*
X244092D03*
X240746D03*
X237399D03*
X234053D03*
X290943Y60723D03*
X287596D03*
X284250D03*
X280903D03*
X277557D03*
X274210D03*
X270864D03*
X267518D03*
X264171D03*
X260825D03*
X257478D03*
X254132D03*
X250785D03*
X247439D03*
X244092D03*
X240746D03*
X237399D03*
X234053D03*
X290943Y41033D03*
X287596D03*
X284250D03*
X280903D03*
X277557D03*
X274210D03*
X270864D03*
X267518D03*
X264171D03*
X260825D03*
X257478D03*
X254132D03*
X250785D03*
X247439D03*
X244092D03*
X240746D03*
X237399D03*
X234053D03*
X290943Y523900D03*
X287596D03*
X284250D03*
X280903D03*
X277557D03*
X274210D03*
X270864D03*
X267518D03*
X264171D03*
X260825D03*
X257478D03*
X254132D03*
X250785D03*
X247439D03*
X244092D03*
X240746D03*
X237399D03*
X234053D03*
X290943Y542010D03*
X287596D03*
X284250D03*
X280903D03*
X277557D03*
X274210D03*
X270864D03*
X267518D03*
X264171D03*
X260825D03*
X257478D03*
X254132D03*
X250785D03*
X247439D03*
X244092D03*
X240746D03*
X237399D03*
X234053D03*
X237399Y561700D03*
X244092D03*
X254132D03*
X260825D03*
X267518D03*
X274210D03*
X280903D03*
X290943D03*
X234053Y579810D03*
X240746D03*
X247439D03*
X257478D03*
X264171D03*
X270864D03*
X277557D03*
X284250D03*
X290943D03*
X287596D03*
X254132D03*
X250785D03*
X284250Y561700D03*
X287596D03*
X247439D03*
X250785D03*
X260825Y579810D03*
X257478Y561700D03*
X237399Y579810D03*
X234053Y561700D03*
X267518Y579810D03*
X264171Y561700D03*
X244092Y579810D03*
X240746Y561700D03*
X274210Y579810D03*
X270864Y561700D03*
X280903Y579810D03*
X277557Y561700D03*
X290943Y617610D03*
X287596D03*
X284250D03*
X280903D03*
X277557D03*
X274210D03*
X270864D03*
X267518D03*
X264171D03*
X260825D03*
X257478D03*
X254132D03*
X250785D03*
X247439D03*
X244092D03*
X240746D03*
X237399D03*
X234053D03*
X290943Y599500D03*
X287596D03*
X284250D03*
X280903D03*
X277557D03*
X274210D03*
X270864D03*
X267518D03*
X264171D03*
X260825D03*
X257478D03*
X254132D03*
X250785D03*
X247439D03*
X244092D03*
X240746D03*
X237399D03*
X234053D03*
X354525Y3233D03*
X351179D03*
X347833D03*
X344486D03*
X341140D03*
X337793D03*
X334447D03*
X331100D03*
X327754D03*
X324407D03*
X321061D03*
X317714D03*
X314368D03*
X311021D03*
X307675D03*
X304329D03*
X300982D03*
X297636D03*
X294289D03*
X354525Y-14877D03*
X351179D03*
X347833D03*
X344486D03*
X341140D03*
X337793D03*
X334447D03*
X331100D03*
X327754D03*
X324407D03*
X321061D03*
X317714D03*
X314368D03*
X311021D03*
X307675D03*
X304329D03*
X300982D03*
X297636D03*
X294289D03*
X354525Y22923D03*
X351179D03*
X347833D03*
X344486D03*
X341140D03*
X337793D03*
X334447D03*
X331100D03*
X327754D03*
X324407D03*
X321061D03*
X317714D03*
X314368D03*
X311021D03*
X307675D03*
X304329D03*
X300982D03*
X297636D03*
X294289D03*
X354525Y78833D03*
X351179D03*
X347833D03*
X344486D03*
X341140D03*
X337793D03*
X334447D03*
X331100D03*
X327754D03*
X324407D03*
X321061D03*
X317714D03*
X314368D03*
X311021D03*
X307675D03*
X304329D03*
X300982D03*
X297636D03*
X294289D03*
X354525Y60723D03*
X351179D03*
X347833D03*
X344486D03*
X341140D03*
X337793D03*
X334447D03*
X331100D03*
X327754D03*
X324407D03*
X321061D03*
X317714D03*
X314368D03*
X311021D03*
X307675D03*
X304329D03*
X300982D03*
X297636D03*
X294289D03*
X354525Y41033D03*
X351179D03*
X347833D03*
X344486D03*
X341140D03*
X337793D03*
X334447D03*
X331100D03*
X327754D03*
X324407D03*
X321061D03*
X317714D03*
X314368D03*
X311021D03*
X307675D03*
X304329D03*
X300982D03*
X297636D03*
X294289D03*
X354525Y523900D03*
X351179D03*
X347833D03*
X344486D03*
X341140D03*
X337793D03*
X334447D03*
X331100D03*
X327754D03*
X324407D03*
X321061D03*
X317714D03*
X314368D03*
X311021D03*
X307675D03*
X304329D03*
X300982D03*
X297636D03*
X294289D03*
X354525Y542010D03*
X351179D03*
X347833D03*
X344486D03*
X341140D03*
X337793D03*
X334447D03*
X331100D03*
X327754D03*
X324407D03*
X321061D03*
X317714D03*
X314368D03*
X311021D03*
X307675D03*
X304329D03*
X300982D03*
X297636D03*
X294289D03*
X341140Y579810D03*
X351179D03*
X311021Y561700D03*
X317714D03*
X327754D03*
X337793D03*
X347833D03*
X314368Y579810D03*
X321061D03*
X331100D03*
X297636Y561700D03*
X304329D03*
X294289Y579810D03*
X300982D03*
X307675D03*
X317714D03*
X307675Y561700D03*
X311021Y579810D03*
X314368Y561700D03*
X297636Y579810D03*
X294289Y561700D03*
X304329Y579810D03*
X300982Y561700D03*
X324407Y579810D03*
Y561700D03*
X327754Y579810D03*
X321061Y561700D03*
X334447D03*
X341140D03*
X337793Y579810D03*
X344486Y561700D03*
Y579810D03*
X347833D03*
X351179Y561700D03*
X354525Y579810D03*
X331100Y561700D03*
X334447Y579810D03*
X354525Y561700D03*
Y617610D03*
X351179D03*
X347833D03*
X344486D03*
X341140D03*
X337793D03*
X334447D03*
X331100D03*
X327754D03*
X324407D03*
X321061D03*
X317714D03*
X314368D03*
X311021D03*
X307675D03*
X304329D03*
X300982D03*
X297636D03*
X294289D03*
X354525Y599500D03*
X351179D03*
X347833D03*
X344486D03*
X341140D03*
X337793D03*
X334447D03*
X331100D03*
X327754D03*
X324407D03*
X321061D03*
X317714D03*
X314368D03*
X311021D03*
X307675D03*
X304329D03*
X300982D03*
X297636D03*
X294289D03*
X414762Y3233D03*
X411415D03*
X408069D03*
X404722D03*
X401376D03*
X398029D03*
X394683D03*
X371258D03*
X367911D03*
X364565D03*
X361218D03*
X357872D03*
X414762Y-14877D03*
X411415D03*
X408069D03*
X404722D03*
X401376D03*
X398029D03*
X394683D03*
X371258D03*
X367911D03*
X364565D03*
X361218D03*
X357872D03*
X414762Y22923D03*
X411415D03*
X408069D03*
X404722D03*
X401376D03*
X398029D03*
X394683D03*
X371258D03*
X367911D03*
X364565D03*
X361218D03*
X357872D03*
X414762Y78833D03*
X411415D03*
X408069D03*
X404722D03*
X401376D03*
X398029D03*
X394683D03*
X371258D03*
X367911D03*
X364565D03*
X361218D03*
X357872D03*
X414762Y60723D03*
X411415D03*
X408069D03*
X404722D03*
X401376D03*
X398029D03*
X394683D03*
X371258D03*
X367911D03*
X364565D03*
X361218D03*
X357872D03*
X414762Y41033D03*
X411415D03*
X408069D03*
X404722D03*
X401376D03*
X398029D03*
X394683D03*
X371258D03*
X367911D03*
X364565D03*
X361218D03*
X357872D03*
X414762Y523900D03*
X411415D03*
X408069D03*
X404722D03*
X401376D03*
X398029D03*
X394683D03*
X371258D03*
X367911D03*
X364565D03*
X361218D03*
X357872D03*
X414762Y542010D03*
X411415D03*
X408069D03*
X404722D03*
X401376D03*
X398029D03*
X394683D03*
X371258D03*
X367911D03*
X364565D03*
X361218D03*
X357872D03*
X371258Y561700D03*
Y579810D03*
X357872D03*
X367911D03*
X398029D03*
X408069D03*
X357872Y561700D03*
X367911D03*
X401376D03*
X411415D03*
X414762D03*
X411415Y579810D03*
X394683D03*
Y561700D03*
X361218Y579810D03*
X364565D03*
X361218Y561700D03*
X364565D03*
X401376Y579810D03*
X404722Y561700D03*
X408069D03*
X414762Y579810D03*
X404722D03*
X398029Y561700D03*
X414762Y617610D03*
X411415D03*
X408069D03*
X404722D03*
X401376D03*
X398029D03*
X394683D03*
X371258D03*
X367911D03*
X364565D03*
X361218D03*
X357872D03*
X414762Y599500D03*
X411415D03*
X408069D03*
X404722D03*
X401376D03*
X398029D03*
X394683D03*
X371258D03*
X367911D03*
X364565D03*
X361218D03*
X357872D03*
X478344Y3233D03*
X474998D03*
X471651D03*
X468305D03*
X464958D03*
X461612D03*
X458266D03*
X454919D03*
X451573D03*
X448226D03*
X444880D03*
X441533D03*
X438187D03*
X434840D03*
X431494D03*
X428147D03*
X424801D03*
X421455D03*
X418108D03*
X478344Y-14877D03*
X474998D03*
X471651D03*
X468305D03*
X464958D03*
X461612D03*
X458266D03*
X454919D03*
X451573D03*
X448226D03*
X444880D03*
X441533D03*
X438187D03*
X434840D03*
X431494D03*
X428147D03*
X424801D03*
X421455D03*
X418108D03*
X478344Y22923D03*
X474998D03*
X471651D03*
X468305D03*
X464958D03*
X461612D03*
X458266D03*
X454919D03*
X451573D03*
X448226D03*
X444880D03*
X441533D03*
X438187D03*
X434840D03*
X431494D03*
X428147D03*
X424801D03*
X421455D03*
X418108D03*
X478344Y78833D03*
X474998D03*
X471651D03*
X468305D03*
X464958D03*
X461612D03*
X458266D03*
X454919D03*
X451573D03*
X448226D03*
X444880D03*
X441533D03*
X438187D03*
X434840D03*
X431494D03*
X428147D03*
X424801D03*
X421455D03*
X418108D03*
X478344Y60723D03*
X474998D03*
X471651D03*
X468305D03*
X464958D03*
X461612D03*
X458266D03*
X454919D03*
X451573D03*
X448226D03*
X444880D03*
X441533D03*
X438187D03*
X434840D03*
X431494D03*
X428147D03*
X424801D03*
X421455D03*
X418108D03*
X478344Y41033D03*
X474998D03*
X471651D03*
X468305D03*
X464958D03*
X461612D03*
X458266D03*
X454919D03*
X451573D03*
X448226D03*
X444880D03*
X441533D03*
X438187D03*
X434840D03*
X431494D03*
X428147D03*
X424801D03*
X421455D03*
X418108D03*
X478344Y523900D03*
X474998D03*
X471651D03*
X468305D03*
X464958D03*
X461612D03*
X458266D03*
X454919D03*
X451573D03*
X448226D03*
X444880D03*
X441533D03*
X438187D03*
X434840D03*
X431494D03*
X428147D03*
X424801D03*
X421455D03*
X418108D03*
X478344Y542010D03*
X474998D03*
X471651D03*
X468305D03*
X464958D03*
X461612D03*
X458266D03*
X454919D03*
X451573D03*
X448226D03*
X444880D03*
X441533D03*
X438187D03*
X434840D03*
X431494D03*
X428147D03*
X424801D03*
X421455D03*
X418108D03*
Y579810D03*
X424801D03*
X431494D03*
X418108Y561700D03*
X428147D03*
X434840D03*
X441533D03*
Y579810D03*
X448226Y561700D03*
X454919D03*
X461612D03*
X471651D03*
X478344D03*
X451573Y579810D03*
X458266D03*
X464958D03*
X474998D03*
X471651D03*
X468305D03*
X464958Y561700D03*
X468305D03*
X421455Y579810D03*
X448226D03*
X444880D03*
Y561700D03*
X431494D03*
X438187D03*
X424801D03*
X478344Y579810D03*
X474998Y561700D03*
X454919Y579810D03*
X451573Y561700D03*
X461612Y579810D03*
X458266Y561700D03*
X438187Y579810D03*
X434840D03*
X421455Y561700D03*
X428147Y579810D03*
X478344Y617610D03*
X474998D03*
X471651D03*
X468305D03*
X464958D03*
X461612D03*
X458266D03*
X454919D03*
X451573D03*
X448226D03*
X444880D03*
X441533D03*
X438187D03*
X434840D03*
X431494D03*
X428147D03*
X424801D03*
X421455D03*
X418108D03*
X478344Y599500D03*
X474998D03*
X471651D03*
X468305D03*
X464958D03*
X461612D03*
X458266D03*
X454919D03*
X451573D03*
X448226D03*
X444880D03*
X441533D03*
X438187D03*
X434840D03*
X431494D03*
X428147D03*
X424801D03*
X421455D03*
X418108D03*
X538581Y3233D03*
X535234D03*
X531888D03*
X528541D03*
X525195D03*
X521848D03*
X518502D03*
X515155D03*
X511809D03*
X508462D03*
X505116D03*
X501770D03*
X498423D03*
X495077D03*
X491730D03*
X488384D03*
X485037D03*
X481691D03*
X538581Y-14877D03*
X535234D03*
X531888D03*
X528541D03*
X525195D03*
X521848D03*
X518502D03*
X515155D03*
X511809D03*
X508462D03*
X505116D03*
X501770D03*
X498423D03*
X495077D03*
X491730D03*
X488384D03*
X485037D03*
X481691D03*
X538581Y22923D03*
X535234D03*
X531888D03*
X528541D03*
X525195D03*
X521848D03*
X518502D03*
X515155D03*
X511809D03*
X508462D03*
X505116D03*
X501770D03*
X498423D03*
X495077D03*
X491730D03*
X488384D03*
X485037D03*
X481691D03*
X538581Y78833D03*
X535234D03*
X531888D03*
X528541D03*
X525195D03*
X521848D03*
X518502D03*
X515155D03*
X511809D03*
X508462D03*
X505116D03*
X501770D03*
X498423D03*
X495077D03*
X491730D03*
X488384D03*
X485037D03*
X481691D03*
X538581Y60723D03*
X535234D03*
X531888D03*
X528541D03*
X525195D03*
X521848D03*
X518502D03*
X515155D03*
X511809D03*
X508462D03*
X505116D03*
X501770D03*
X498423D03*
X495077D03*
X491730D03*
X488384D03*
X485037D03*
X481691D03*
X538581Y41033D03*
X535234D03*
X531888D03*
X528541D03*
X525195D03*
X521848D03*
X518502D03*
X515155D03*
X511809D03*
X508462D03*
X505116D03*
X501770D03*
X498423D03*
X495077D03*
X491730D03*
X488384D03*
X485037D03*
X481691D03*
X538581Y523900D03*
X535234D03*
X531888D03*
X528541D03*
X525195D03*
X521848D03*
X518502D03*
X515155D03*
X511809D03*
X508462D03*
X505116D03*
X501770D03*
X498423D03*
X495077D03*
X491730D03*
X488384D03*
X485037D03*
X481691D03*
X538581Y542010D03*
X535234D03*
X531888D03*
X528541D03*
X525195D03*
X521848D03*
X518502D03*
X515155D03*
X511809D03*
X508462D03*
X505116D03*
X501770D03*
X498423D03*
X495077D03*
X491730D03*
X488384D03*
X485037D03*
X481691D03*
X531888Y579810D03*
X538581D03*
X485037Y561700D03*
X491730D03*
X498423D03*
X508462D03*
X515155D03*
X521848D03*
X528541D03*
X535234D03*
X481691Y579810D03*
X488384D03*
X495077D03*
X501770D03*
X511809D03*
X518502D03*
X525195D03*
X508462D03*
X505116D03*
X538581Y561700D03*
X501770D03*
X505116D03*
X528541Y579810D03*
X525195Y561700D03*
X535234Y579810D03*
X531888Y561700D03*
X515155Y579810D03*
X511809Y561700D03*
X491730Y579810D03*
X488384Y561700D03*
X521848Y579810D03*
X518502Y561700D03*
X498423Y579810D03*
X495077Y561700D03*
X485037Y579810D03*
X481691Y561700D03*
X538581Y617610D03*
X535234D03*
X531888D03*
X528541D03*
X525195D03*
X521848D03*
X518502D03*
X515155D03*
X511809D03*
X508462D03*
X505116D03*
X501770D03*
X498423D03*
X495077D03*
X491730D03*
X488384D03*
X485037D03*
X481691D03*
X538581Y599500D03*
X535234D03*
X531888D03*
X528541D03*
X525195D03*
X521848D03*
X518502D03*
X515155D03*
X511809D03*
X508462D03*
X505116D03*
X501770D03*
X498423D03*
X495077D03*
X491730D03*
X488384D03*
X485037D03*
X481691D03*
X602163Y3233D03*
X598817D03*
X595470D03*
X592124D03*
X588777D03*
X585431D03*
X582084D03*
X578738D03*
X575392D03*
X572045D03*
X568699D03*
X565352D03*
X562006D03*
X558659D03*
X555313D03*
X551966D03*
X548620D03*
X545273D03*
X541927D03*
X602163Y-14877D03*
X598817D03*
X595470D03*
X592124D03*
X588777D03*
X585431D03*
X582084D03*
X578738D03*
X575392D03*
X572045D03*
X568699D03*
X565352D03*
X562006D03*
X558659D03*
X555313D03*
X551966D03*
X548620D03*
X545273D03*
X541927D03*
X602163Y22923D03*
X598817D03*
X595470D03*
X592124D03*
X588777D03*
X585431D03*
X582084D03*
X578738D03*
X575392D03*
X572045D03*
X568699D03*
X565352D03*
X562006D03*
X558659D03*
X555313D03*
X551966D03*
X548620D03*
X545273D03*
X541927D03*
X602163Y78833D03*
X598817D03*
X595470D03*
X592124D03*
X588777D03*
X585431D03*
X582084D03*
X578738D03*
X575392D03*
X572045D03*
X568699D03*
X565352D03*
X562006D03*
X558659D03*
X555313D03*
X551966D03*
X548620D03*
X545273D03*
X541927D03*
X602163Y60723D03*
X598817D03*
X595470D03*
X592124D03*
X588777D03*
X585431D03*
X582084D03*
X578738D03*
X575392D03*
X572045D03*
X568699D03*
X565352D03*
X562006D03*
X558659D03*
X555313D03*
X551966D03*
X548620D03*
X545273D03*
X541927D03*
X602163Y41033D03*
X598817D03*
X595470D03*
X592124D03*
X588777D03*
X585431D03*
X582084D03*
X578738D03*
X575392D03*
X572045D03*
X568699D03*
X565352D03*
X562006D03*
X558659D03*
X555313D03*
X551966D03*
X548620D03*
X545273D03*
X541927D03*
X602163Y523900D03*
X598817D03*
X595470D03*
X592124D03*
X588777D03*
X585431D03*
X582084D03*
X578738D03*
X575392D03*
X572045D03*
X568699D03*
X565352D03*
X562006D03*
X558659D03*
X555313D03*
X551966D03*
X548620D03*
X545273D03*
X541927D03*
X602163Y542010D03*
X598817D03*
X595470D03*
X592124D03*
X588777D03*
X585431D03*
X582084D03*
X578738D03*
X575392D03*
X572045D03*
X568699D03*
X565352D03*
X562006D03*
X558659D03*
X555313D03*
X551966D03*
X548620D03*
X545273D03*
X541927D03*
X548620Y579810D03*
X555313D03*
X562006D03*
X545273Y561700D03*
X551966D03*
X558659D03*
X565352D03*
X572045D03*
X568699Y579810D03*
X582084Y561700D03*
X588777D03*
X595470D03*
X575392Y579810D03*
X585431D03*
X592124D03*
X598817D03*
X582084D03*
X578738D03*
X545273D03*
X541927D03*
X575392Y561700D03*
X578738D03*
X541927D03*
X602163Y579810D03*
Y561700D03*
X598817D03*
X588777Y579810D03*
X585431Y561700D03*
X565352Y579810D03*
X562006Y561700D03*
X595470Y579810D03*
X592124Y561700D03*
X572045Y579810D03*
X568699Y561700D03*
X551966Y579810D03*
X548620Y561700D03*
X558659Y579810D03*
X555313Y561700D03*
X602163Y617610D03*
X598817D03*
X595470D03*
X592124D03*
X588777D03*
X585431D03*
X582084D03*
X578738D03*
X575392D03*
X572045D03*
X568699D03*
X565352D03*
X562006D03*
X558659D03*
X555313D03*
X551966D03*
X548620D03*
X545273D03*
X541927D03*
X602163Y599500D03*
X598817D03*
X595470D03*
X592124D03*
X588777D03*
X585431D03*
X582084D03*
X578738D03*
X575392D03*
X572045D03*
X568699D03*
X565352D03*
X562006D03*
X558659D03*
X555313D03*
X551966D03*
X548620D03*
X545273D03*
X541927D03*
X615549Y3233D03*
X612203D03*
X608856D03*
X605510D03*
X615549Y-14877D03*
X612203D03*
X608856D03*
X605510D03*
X615549Y22923D03*
X612203D03*
X608856D03*
X605510D03*
X615549Y78833D03*
X612203D03*
X608856D03*
X605510D03*
X615549Y60723D03*
X612203D03*
X608856D03*
X605510D03*
X615549Y41033D03*
X612203D03*
X608856D03*
X605510D03*
X615549Y523900D03*
X612203D03*
X608856D03*
X605510D03*
X615549Y542010D03*
X612203D03*
X608856D03*
X605510D03*
X608856Y561700D03*
X612203D03*
X615549Y579810D03*
X608856D03*
X612203D03*
X605510D03*
Y561700D03*
X615549D03*
Y617610D03*
X612203D03*
X608856D03*
X605510D03*
X615549Y599500D03*
X612203D03*
X608856D03*
X605510D03*
X786616Y3233D03*
X783269D03*
X779923D03*
X776576D03*
X773230D03*
X769883D03*
X766537D03*
X786616Y-14877D03*
X783269D03*
X779923D03*
X776576D03*
X773230D03*
X769883D03*
X766537D03*
X786616Y22923D03*
X783269D03*
X779923D03*
X776576D03*
X773230D03*
X769883D03*
X766537D03*
X786616Y78833D03*
X783269D03*
X779923D03*
X776576D03*
X773230D03*
X769883D03*
X766537D03*
X786616Y60723D03*
X783269D03*
X779923D03*
X776576D03*
X773230D03*
X769883D03*
X766537D03*
X786616Y41033D03*
X783269D03*
X779923D03*
X776576D03*
X773230D03*
X769883D03*
X766537D03*
X786616Y523900D03*
X783269D03*
X779923D03*
X776576D03*
X773230D03*
X769883D03*
X766537D03*
X786616Y579810D03*
X783269D03*
X779923D03*
X776576D03*
X773230D03*
X769883D03*
X766537D03*
X786616Y561700D03*
X783269D03*
X779923D03*
X776576D03*
X773230D03*
X769883D03*
X766537D03*
X786616Y542010D03*
X783269D03*
X779923D03*
X776576D03*
X773230D03*
X769883D03*
X766537D03*
X786616Y617610D03*
X783269D03*
X779923D03*
X776576D03*
X773230D03*
X769883D03*
X766537D03*
X786616Y599500D03*
X783269D03*
X779923D03*
X776576D03*
X773230D03*
X769883D03*
X766537D03*
X846852Y3233D03*
X843506D03*
X840159D03*
X836813D03*
X833466D03*
X830120D03*
X826773D03*
X823427D03*
X820080D03*
X816734D03*
X813387D03*
X810041D03*
X806694D03*
X803348D03*
X800002D03*
X796655D03*
X793309D03*
X789962D03*
X846852Y-14877D03*
X843506D03*
X840159D03*
X836813D03*
X833466D03*
X830120D03*
X826773D03*
X823427D03*
X820080D03*
X816734D03*
X813387D03*
X810041D03*
X806694D03*
X803348D03*
X800002D03*
X796655D03*
X793309D03*
X789962D03*
X846852Y22923D03*
X843506D03*
X840159D03*
X836813D03*
X833466D03*
X830120D03*
X826773D03*
X823427D03*
X820080D03*
X816734D03*
X813387D03*
X810041D03*
X806694D03*
X803348D03*
X800002D03*
X796655D03*
X793309D03*
X789962D03*
X846852Y78833D03*
X843506D03*
X840159D03*
X836813D03*
X833466D03*
X830120D03*
X826773D03*
X823427D03*
X820080D03*
X816734D03*
X813387D03*
X810041D03*
X806694D03*
X803348D03*
X800002D03*
X796655D03*
X793309D03*
X789962D03*
X846852Y60723D03*
X843506D03*
X840159D03*
X836813D03*
X833466D03*
X830120D03*
X826773D03*
X823427D03*
X820080D03*
X816734D03*
X813387D03*
X810041D03*
X806694D03*
X803348D03*
X800002D03*
X796655D03*
X793309D03*
X789962D03*
X846852Y41033D03*
X843506D03*
X840159D03*
X836813D03*
X833466D03*
X830120D03*
X826773D03*
X823427D03*
X820080D03*
X816734D03*
X813387D03*
X810041D03*
X806694D03*
X803348D03*
X800002D03*
X796655D03*
X793309D03*
X789962D03*
X846852Y523900D03*
X843506D03*
X840159D03*
X836813D03*
X833466D03*
X830120D03*
X826773D03*
X823427D03*
X820080D03*
X816734D03*
X813387D03*
X810041D03*
X806694D03*
X803348D03*
X800002D03*
X796655D03*
X793309D03*
X789962D03*
X846852Y579810D03*
X843506D03*
X840159D03*
X836813D03*
X833466D03*
X830120D03*
X826773D03*
X823427D03*
X820080D03*
X816734D03*
X813387D03*
X810041D03*
X806694D03*
X803348D03*
X800002D03*
X796655D03*
X793309D03*
X789962D03*
X846852Y561700D03*
X843506D03*
X840159D03*
X836813D03*
X833466D03*
X830120D03*
X826773D03*
X823427D03*
X820080D03*
X816734D03*
X813387D03*
X810041D03*
X806694D03*
X803348D03*
X800002D03*
X796655D03*
X793309D03*
X789962D03*
X846852Y542010D03*
X843506D03*
X840159D03*
X836813D03*
X833466D03*
X830120D03*
X826773D03*
X823427D03*
X820080D03*
X816734D03*
X813387D03*
X810041D03*
X806694D03*
X803348D03*
X800002D03*
X796655D03*
X793309D03*
X789962D03*
X846852Y617610D03*
X843506D03*
X840159D03*
X836813D03*
X833466D03*
X830120D03*
X826773D03*
X823427D03*
X820080D03*
X816734D03*
X813387D03*
X810041D03*
X806694D03*
X803348D03*
X800002D03*
X796655D03*
X793309D03*
X789962D03*
X846852Y599500D03*
X843506D03*
X840159D03*
X836813D03*
X833466D03*
X830120D03*
X826773D03*
X823427D03*
X820080D03*
X816734D03*
X813387D03*
X810041D03*
X806694D03*
X803348D03*
X800002D03*
X796655D03*
X793309D03*
X789962D03*
X910435Y3233D03*
X907088D03*
X903742D03*
X900395D03*
X897049D03*
X893702D03*
X890356D03*
X887009D03*
X883663D03*
X880317D03*
X876970D03*
X873624D03*
X870277D03*
X866931D03*
X863584D03*
X860238D03*
X856891D03*
X853545D03*
X850198D03*
X910435Y-14877D03*
X907088D03*
X903742D03*
X900395D03*
X897049D03*
X893702D03*
X890356D03*
X887009D03*
X883663D03*
X880317D03*
X876970D03*
X873624D03*
X870277D03*
X866931D03*
X863584D03*
X860238D03*
X856891D03*
X853545D03*
X850198D03*
X910435Y22923D03*
X907088D03*
X903742D03*
X900395D03*
X897049D03*
X893702D03*
X890356D03*
X887009D03*
X883663D03*
X880317D03*
X876970D03*
X873624D03*
X870277D03*
X866931D03*
X863584D03*
X860238D03*
X856891D03*
X853545D03*
X850198D03*
X910435Y78833D03*
X907088D03*
X903742D03*
X900395D03*
X897049D03*
X893702D03*
X890356D03*
X887009D03*
X883663D03*
X880317D03*
X876970D03*
X873624D03*
X870277D03*
X866931D03*
X863584D03*
X860238D03*
X856891D03*
X853545D03*
X850198D03*
X910435Y60723D03*
X907088D03*
X903742D03*
X900395D03*
X897049D03*
X893702D03*
X890356D03*
X887009D03*
X883663D03*
X880317D03*
X876970D03*
X873624D03*
X870277D03*
X866931D03*
X863584D03*
X860238D03*
X856891D03*
X853545D03*
X850198D03*
X910435Y41033D03*
X907088D03*
X903742D03*
X900395D03*
X897049D03*
X893702D03*
X890356D03*
X887009D03*
X883663D03*
X880317D03*
X876970D03*
X873624D03*
X870277D03*
X866931D03*
X863584D03*
X860238D03*
X856891D03*
X853545D03*
X850198D03*
X910435Y523900D03*
X907088D03*
X903742D03*
X900395D03*
X897049D03*
X893702D03*
X890356D03*
X887009D03*
X883663D03*
X880317D03*
X876970D03*
X873624D03*
X870277D03*
X866931D03*
X863584D03*
X860238D03*
X856891D03*
X853545D03*
X850198D03*
X910435Y579810D03*
X907088D03*
X903742D03*
X900395D03*
X897049D03*
X893702D03*
X890356D03*
X887009D03*
X883663D03*
X880317D03*
X876970D03*
X873624D03*
X870277D03*
X866931D03*
X863584D03*
X860238D03*
X856891D03*
X853545D03*
X850198D03*
X910435Y561700D03*
X907088D03*
X903742D03*
X900395D03*
X897049D03*
X893702D03*
X890356D03*
X887009D03*
X883663D03*
X880317D03*
X876970D03*
X873624D03*
X870277D03*
X866931D03*
X863584D03*
X860238D03*
X856891D03*
X853545D03*
X850198D03*
X910435Y542010D03*
X907088D03*
X903742D03*
X900395D03*
X897049D03*
X893702D03*
X890356D03*
X887009D03*
X883663D03*
X880317D03*
X876970D03*
X873624D03*
X870277D03*
X866931D03*
X863584D03*
X860238D03*
X856891D03*
X853545D03*
X850198D03*
X910435Y617610D03*
X907088D03*
X903742D03*
X900395D03*
X897049D03*
X893702D03*
X890356D03*
X887009D03*
X883663D03*
X880317D03*
X876970D03*
X873624D03*
X870277D03*
X866931D03*
X863584D03*
X860238D03*
X856891D03*
X853545D03*
X850198D03*
X910435Y599500D03*
X907088D03*
X903742D03*
X900395D03*
X897049D03*
X893702D03*
X890356D03*
X887009D03*
X883663D03*
X880317D03*
X876970D03*
X873624D03*
X870277D03*
X866931D03*
X863584D03*
X860238D03*
X856891D03*
X853545D03*
X850198D03*
X970671Y3233D03*
X967324D03*
X963978D03*
X960631D03*
X957285D03*
X953939D03*
X950592D03*
X947246D03*
X943899D03*
X940553D03*
X937206D03*
X933860D03*
X930513D03*
X927167D03*
X923820D03*
X920474D03*
X917128D03*
X913781D03*
X970671Y-14877D03*
X967324D03*
X963978D03*
X960631D03*
X957285D03*
X953939D03*
X950592D03*
X947246D03*
X943899D03*
X940553D03*
X937206D03*
X933860D03*
X930513D03*
X927167D03*
X923820D03*
X920474D03*
X917128D03*
X913781D03*
X970671Y22923D03*
X967324D03*
X963978D03*
X960631D03*
X957285D03*
X953939D03*
X950592D03*
X947246D03*
X943899D03*
X940553D03*
X937206D03*
X933860D03*
X930513D03*
X927167D03*
X923820D03*
X920474D03*
X917128D03*
X913781D03*
X970671Y78833D03*
X967324D03*
X963978D03*
X960631D03*
X957285D03*
X953939D03*
X950592D03*
X947246D03*
X943899D03*
X940553D03*
X937206D03*
X933860D03*
X930513D03*
X927167D03*
X923820D03*
X920474D03*
X917128D03*
X913781D03*
X970671Y60723D03*
X967324D03*
X963978D03*
X960631D03*
X957285D03*
X953939D03*
X950592D03*
X947246D03*
X943899D03*
X940553D03*
X937206D03*
X933860D03*
X930513D03*
X927167D03*
X923820D03*
X920474D03*
X917128D03*
X913781D03*
X970671Y41033D03*
X967324D03*
X963978D03*
X960631D03*
X957285D03*
X953939D03*
X950592D03*
X947246D03*
X943899D03*
X940553D03*
X937206D03*
X933860D03*
X930513D03*
X927167D03*
X923820D03*
X920474D03*
X917128D03*
X913781D03*
X970671Y523900D03*
X967324D03*
X963978D03*
X960631D03*
X957285D03*
X953939D03*
X950592D03*
X947246D03*
X943899D03*
X940553D03*
X937206D03*
X933860D03*
X930513D03*
X927167D03*
X923820D03*
X920474D03*
X917128D03*
X913781D03*
X970671Y579810D03*
X967324D03*
X963978D03*
X960631D03*
X957285D03*
X953939D03*
X950592D03*
X947246D03*
X943899D03*
X940553D03*
X937206D03*
X933860D03*
X930513D03*
X927167D03*
X923820D03*
X920474D03*
X917128D03*
X913781D03*
X970671Y561700D03*
X967324D03*
X963978D03*
X960631D03*
X957285D03*
X953939D03*
X950592D03*
X947246D03*
X943899D03*
X940553D03*
X937206D03*
X933860D03*
X930513D03*
X927167D03*
X923820D03*
X920474D03*
X917128D03*
X913781D03*
X970671Y542010D03*
X967324D03*
X963978D03*
X960631D03*
X957285D03*
X953939D03*
X950592D03*
X947246D03*
X943899D03*
X940553D03*
X937206D03*
X933860D03*
X930513D03*
X927167D03*
X923820D03*
X920474D03*
X917128D03*
X913781D03*
X970671Y617610D03*
X967324D03*
X963978D03*
X960631D03*
X957285D03*
X953939D03*
X950592D03*
X947246D03*
X943899D03*
X940553D03*
X937206D03*
X933860D03*
X930513D03*
X927167D03*
X923820D03*
X920474D03*
X917128D03*
X913781D03*
X970671Y599500D03*
X967324D03*
X963978D03*
X960631D03*
X957285D03*
X953939D03*
X950592D03*
X947246D03*
X943899D03*
X940553D03*
X937206D03*
X933860D03*
X930513D03*
X927167D03*
X923820D03*
X920474D03*
X917128D03*
X913781D03*
X1020868Y3233D03*
X1017521D03*
X1014175D03*
X1010828D03*
X1007482D03*
X1004135D03*
X1000789D03*
X997443D03*
X994096D03*
X990750D03*
X987403D03*
X984057D03*
X980710D03*
X977364D03*
X974017D03*
X1020868Y-14877D03*
X1017521D03*
X1014175D03*
X1010828D03*
X1007482D03*
X1004135D03*
X1000789D03*
X997443D03*
X994096D03*
X990750D03*
X987403D03*
X984057D03*
X980710D03*
X977364D03*
X974017D03*
X1020868Y22923D03*
X1017521D03*
X1014175D03*
X1010828D03*
X1007482D03*
X1004135D03*
X1000789D03*
X997443D03*
X994096D03*
X990750D03*
X987403D03*
X984057D03*
X980710D03*
X977364D03*
X974017D03*
X1020868Y78833D03*
X1017521D03*
X1014175D03*
X1010828D03*
X1007482D03*
X1004135D03*
X1000789D03*
X997443D03*
X994096D03*
X990750D03*
X987403D03*
X984057D03*
X980710D03*
X977364D03*
X974017D03*
X1020868Y60723D03*
X1017521D03*
X1014175D03*
X1010828D03*
X1007482D03*
X1004135D03*
X1000789D03*
X997443D03*
X994096D03*
X990750D03*
X987403D03*
X984057D03*
X980710D03*
X977364D03*
X974017D03*
X1020868Y41033D03*
X1017521D03*
X1014175D03*
X1010828D03*
X1007482D03*
X1004135D03*
X1000789D03*
X997443D03*
X994096D03*
X990750D03*
X987403D03*
X984057D03*
X980710D03*
X977364D03*
X974017D03*
X1020868Y523900D03*
X1017521D03*
X1014175D03*
X1010828D03*
X1007482D03*
X1004135D03*
X1000789D03*
X997443D03*
X994096D03*
X990750D03*
X987403D03*
X984057D03*
X980710D03*
X977364D03*
X974017D03*
X1020868Y579810D03*
X1017521D03*
X1014175D03*
X1010828D03*
X1007482D03*
X1004135D03*
X1000789D03*
X997443D03*
X994096D03*
X990750D03*
X987403D03*
X984057D03*
X980710D03*
X977364D03*
X974017D03*
X1020868Y561700D03*
X1017521D03*
X1014175D03*
X1010828D03*
X1007482D03*
X1004135D03*
X1000789D03*
X997443D03*
X994096D03*
X990750D03*
X987403D03*
X984057D03*
X980710D03*
X977364D03*
X974017D03*
X1020868Y542010D03*
X1017521D03*
X1014175D03*
X1010828D03*
X1007482D03*
X1004135D03*
X1000789D03*
X997443D03*
X994096D03*
X990750D03*
X987403D03*
X984057D03*
X980710D03*
X977364D03*
X974017D03*
X1020868Y617610D03*
X1017521D03*
X1014175D03*
X1010828D03*
X1007482D03*
X1004135D03*
X1000789D03*
X997443D03*
X994096D03*
X990750D03*
X987403D03*
X984057D03*
X980710D03*
X977364D03*
X974017D03*
X1020868Y599500D03*
X1017521D03*
X1014175D03*
X1010828D03*
X1007482D03*
X1004135D03*
X1000789D03*
X997443D03*
X994096D03*
X990750D03*
X987403D03*
X984057D03*
X980710D03*
X977364D03*
X974017D03*
X1094490Y3233D03*
X1091143D03*
X1087797D03*
X1084450D03*
X1081104D03*
X1077757D03*
X1074411D03*
X1071065D03*
X1067718D03*
X1064372D03*
X1061025D03*
X1057679D03*
X1054332D03*
X1050986D03*
X1047639D03*
X1044293D03*
X1094490Y-14877D03*
X1091143D03*
X1087797D03*
X1084450D03*
X1081104D03*
X1077757D03*
X1074411D03*
X1071065D03*
X1067718D03*
X1064372D03*
X1061025D03*
X1057679D03*
X1054332D03*
X1050986D03*
X1047639D03*
X1044293D03*
X1094490Y22923D03*
X1091143D03*
X1087797D03*
X1084450D03*
X1081104D03*
X1077757D03*
X1074411D03*
X1071065D03*
X1067718D03*
X1064372D03*
X1061025D03*
X1057679D03*
X1054332D03*
X1050986D03*
X1047639D03*
X1044293D03*
X1094490Y78833D03*
X1091143D03*
X1087797D03*
X1084450D03*
X1081104D03*
X1077757D03*
X1074411D03*
X1071065D03*
X1067718D03*
X1064372D03*
X1061025D03*
X1057679D03*
X1054332D03*
X1050986D03*
X1047639D03*
X1044293D03*
X1094490Y60723D03*
X1091143D03*
X1087797D03*
X1084450D03*
X1081104D03*
X1077757D03*
X1074411D03*
X1071065D03*
X1067718D03*
X1064372D03*
X1061025D03*
X1057679D03*
X1054332D03*
X1050986D03*
X1047639D03*
X1044293D03*
X1094490Y41033D03*
X1091143D03*
X1087797D03*
X1084450D03*
X1081104D03*
X1077757D03*
X1074411D03*
X1071065D03*
X1067718D03*
X1064372D03*
X1061025D03*
X1057679D03*
X1054332D03*
X1050986D03*
X1047639D03*
X1044293D03*
X1094490Y523900D03*
X1091143D03*
X1087797D03*
X1084450D03*
X1081104D03*
X1077757D03*
X1074411D03*
X1071065D03*
X1067718D03*
X1064372D03*
X1061025D03*
X1057679D03*
X1054332D03*
X1050986D03*
X1047639D03*
X1044293D03*
X1094490Y579810D03*
X1091143D03*
X1087797D03*
X1084450D03*
X1081104D03*
X1077757D03*
X1074411D03*
X1071065D03*
X1067718D03*
X1064372D03*
X1061025D03*
X1057679D03*
X1054332D03*
X1050986D03*
X1047639D03*
X1044293D03*
X1094490Y561700D03*
X1091143D03*
X1087797D03*
X1084450D03*
X1081104D03*
X1077757D03*
X1074411D03*
X1071065D03*
X1067718D03*
X1064372D03*
X1061025D03*
X1057679D03*
X1054332D03*
X1050986D03*
X1047639D03*
X1044293D03*
X1094490Y542010D03*
X1091143D03*
X1087797D03*
X1084450D03*
X1081104D03*
X1077757D03*
X1074411D03*
X1071065D03*
X1067718D03*
X1064372D03*
X1061025D03*
X1057679D03*
X1054332D03*
X1050986D03*
X1047639D03*
X1044293D03*
X1094490Y617610D03*
X1091143D03*
X1087797D03*
X1084450D03*
X1081104D03*
X1077757D03*
X1074411D03*
X1071065D03*
X1067718D03*
X1064372D03*
X1061025D03*
X1057679D03*
X1054332D03*
X1050986D03*
X1047639D03*
X1044293D03*
X1094490Y599500D03*
X1091143D03*
X1087797D03*
X1084450D03*
X1081104D03*
X1077757D03*
X1074411D03*
X1071065D03*
X1067718D03*
X1064372D03*
X1061025D03*
X1057679D03*
X1054332D03*
X1050986D03*
X1047639D03*
X1044293D03*
X1154726Y3233D03*
X1151380D03*
X1148033D03*
X1144687D03*
X1141340D03*
X1137994D03*
X1134647D03*
X1131301D03*
X1127954D03*
X1124608D03*
X1121261D03*
X1117915D03*
X1114568D03*
X1111222D03*
X1107876D03*
X1104529D03*
X1101183D03*
X1097836D03*
X1154726Y-14877D03*
X1151380D03*
X1148033D03*
X1144687D03*
X1141340D03*
X1137994D03*
X1134647D03*
X1131301D03*
X1127954D03*
X1124608D03*
X1121261D03*
X1117915D03*
X1114568D03*
X1111222D03*
X1107876D03*
X1104529D03*
X1101183D03*
X1097836D03*
X1154726Y22923D03*
X1151380D03*
X1148033D03*
X1144687D03*
X1141340D03*
X1137994D03*
X1134647D03*
X1131301D03*
X1127954D03*
X1124608D03*
X1121261D03*
X1117915D03*
X1114568D03*
X1111222D03*
X1107876D03*
X1104529D03*
X1101183D03*
X1097836D03*
X1154726Y78833D03*
X1151380D03*
X1148033D03*
X1144687D03*
X1141340D03*
X1137994D03*
X1134647D03*
X1131301D03*
X1127954D03*
X1124608D03*
X1121261D03*
X1117915D03*
X1114568D03*
X1111222D03*
X1107876D03*
X1104529D03*
X1101183D03*
X1097836D03*
X1154726Y60723D03*
X1151380D03*
X1148033D03*
X1144687D03*
X1141340D03*
X1137994D03*
X1134647D03*
X1131301D03*
X1127954D03*
X1124608D03*
X1121261D03*
X1117915D03*
X1114568D03*
X1111222D03*
X1107876D03*
X1104529D03*
X1101183D03*
X1097836D03*
X1154726Y41033D03*
X1151380D03*
X1148033D03*
X1144687D03*
X1141340D03*
X1137994D03*
X1134647D03*
X1131301D03*
X1127954D03*
X1124608D03*
X1121261D03*
X1117915D03*
X1114568D03*
X1111222D03*
X1107876D03*
X1104529D03*
X1101183D03*
X1097836D03*
X1154726Y523900D03*
X1151380D03*
X1148033D03*
X1144687D03*
X1141340D03*
X1137994D03*
X1134647D03*
X1131301D03*
X1127954D03*
X1124608D03*
X1121261D03*
X1117915D03*
X1114568D03*
X1111222D03*
X1107876D03*
X1104529D03*
X1101183D03*
X1097836D03*
X1154726Y579810D03*
X1151380D03*
X1148033D03*
X1144687D03*
X1141340D03*
X1137994D03*
X1134647D03*
X1131301D03*
X1127954D03*
X1124608D03*
X1121261D03*
X1117915D03*
X1114568D03*
X1111222D03*
X1107876D03*
X1104529D03*
X1101183D03*
X1097836D03*
X1154726Y561700D03*
X1151380D03*
X1148033D03*
X1144687D03*
X1141340D03*
X1137994D03*
X1134647D03*
X1131301D03*
X1127954D03*
X1124608D03*
X1121261D03*
X1117915D03*
X1114568D03*
X1111222D03*
X1107876D03*
X1104529D03*
X1101183D03*
X1097836D03*
X1154726Y542010D03*
X1151380D03*
X1148033D03*
X1144687D03*
X1141340D03*
X1137994D03*
X1134647D03*
X1131301D03*
X1127954D03*
X1124608D03*
X1121261D03*
X1117915D03*
X1114568D03*
X1111222D03*
X1107876D03*
X1104529D03*
X1101183D03*
X1097836D03*
X1154726Y617610D03*
X1151380D03*
X1148033D03*
X1144687D03*
X1141340D03*
X1137994D03*
X1134647D03*
X1131301D03*
X1127954D03*
X1124608D03*
X1121261D03*
X1117915D03*
X1114568D03*
X1111222D03*
X1107876D03*
X1104529D03*
X1101183D03*
X1097836D03*
X1154726Y599500D03*
X1151380D03*
X1148033D03*
X1144687D03*
X1141340D03*
X1137994D03*
X1134647D03*
X1131301D03*
X1127954D03*
X1124608D03*
X1121261D03*
X1117915D03*
X1114568D03*
X1111222D03*
X1107876D03*
X1104529D03*
X1101183D03*
X1097836D03*
X1218309Y3233D03*
X1214962D03*
X1211616D03*
X1208269D03*
X1204923D03*
X1201576D03*
X1198230D03*
X1194883D03*
X1191537D03*
X1188191D03*
X1184844D03*
X1181498D03*
X1178151D03*
X1174805D03*
X1171458D03*
X1168112D03*
X1164765D03*
X1161419D03*
X1158072D03*
X1218309Y-14877D03*
X1214962D03*
X1211616D03*
X1208269D03*
X1204923D03*
X1201576D03*
X1198230D03*
X1194883D03*
X1191537D03*
X1188191D03*
X1184844D03*
X1181498D03*
X1178151D03*
X1174805D03*
X1171458D03*
X1168112D03*
X1164765D03*
X1161419D03*
X1158072D03*
X1218309Y22923D03*
X1214962D03*
X1211616D03*
X1208269D03*
X1204923D03*
X1201576D03*
X1198230D03*
X1194883D03*
X1191537D03*
X1188191D03*
X1184844D03*
X1181498D03*
X1178151D03*
X1174805D03*
X1171458D03*
X1168112D03*
X1164765D03*
X1161419D03*
X1158072D03*
X1218309Y78833D03*
X1214962D03*
X1211616D03*
X1208269D03*
X1204923D03*
X1201576D03*
X1198230D03*
X1194883D03*
X1191537D03*
X1188191D03*
X1184844D03*
X1181498D03*
X1178151D03*
X1174805D03*
X1171458D03*
X1168112D03*
X1164765D03*
X1161419D03*
X1158072D03*
X1218309Y60723D03*
X1214962D03*
X1211616D03*
X1208269D03*
X1204923D03*
X1201576D03*
X1198230D03*
X1194883D03*
X1191537D03*
X1188191D03*
X1184844D03*
X1181498D03*
X1178151D03*
X1174805D03*
X1171458D03*
X1168112D03*
X1164765D03*
X1161419D03*
X1158072D03*
X1218309Y41033D03*
X1214962D03*
X1211616D03*
X1208269D03*
X1204923D03*
X1201576D03*
X1198230D03*
X1194883D03*
X1191537D03*
X1188191D03*
X1184844D03*
X1181498D03*
X1178151D03*
X1174805D03*
X1171458D03*
X1168112D03*
X1164765D03*
X1161419D03*
X1158072D03*
X1218309Y523900D03*
X1214962D03*
X1211616D03*
X1208269D03*
X1204923D03*
X1201576D03*
X1198230D03*
X1194883D03*
X1191537D03*
X1188191D03*
X1184844D03*
X1181498D03*
X1178151D03*
X1174805D03*
X1171458D03*
X1168112D03*
X1164765D03*
X1161419D03*
X1158072D03*
X1218309Y579810D03*
X1214962D03*
X1211616D03*
X1208269D03*
X1204923D03*
X1201576D03*
X1198230D03*
X1194883D03*
X1191537D03*
X1188191D03*
X1184844D03*
X1181498D03*
X1178151D03*
X1174805D03*
X1171458D03*
X1168112D03*
X1164765D03*
X1161419D03*
X1158072D03*
X1218309Y561700D03*
X1214962D03*
X1211616D03*
X1208269D03*
X1204923D03*
X1201576D03*
X1198230D03*
X1194883D03*
X1191537D03*
X1188191D03*
X1184844D03*
X1181498D03*
X1178151D03*
X1174805D03*
X1171458D03*
X1168112D03*
X1164765D03*
X1161419D03*
X1158072D03*
X1218309Y542010D03*
X1214962D03*
X1211616D03*
X1208269D03*
X1204923D03*
X1201576D03*
X1198230D03*
X1194883D03*
X1191537D03*
X1188191D03*
X1184844D03*
X1181498D03*
X1178151D03*
X1174805D03*
X1171458D03*
X1168112D03*
X1164765D03*
X1161419D03*
X1158072D03*
X1218309Y617610D03*
X1214962D03*
X1211616D03*
X1208269D03*
X1204923D03*
X1201576D03*
X1198230D03*
X1194883D03*
X1191537D03*
X1188191D03*
X1184844D03*
X1181498D03*
X1178151D03*
X1174805D03*
X1171458D03*
X1168112D03*
X1164765D03*
X1161419D03*
X1158072D03*
X1218309Y599500D03*
X1214962D03*
X1211616D03*
X1208269D03*
X1204923D03*
X1201576D03*
X1198230D03*
X1194883D03*
X1191537D03*
X1188191D03*
X1184844D03*
X1181498D03*
X1178151D03*
X1174805D03*
X1171458D03*
X1168112D03*
X1164765D03*
X1161419D03*
X1158072D03*
X1265159Y3233D03*
X1261813D03*
X1258466D03*
X1255120D03*
X1251773D03*
X1248427D03*
X1245080D03*
X1241734D03*
X1238387D03*
X1235041D03*
X1231694D03*
X1228348D03*
X1225002D03*
X1221655D03*
X1265159Y-14877D03*
X1261813D03*
X1258466D03*
X1255120D03*
X1251773D03*
X1248427D03*
X1245080D03*
X1241734D03*
X1238387D03*
X1235041D03*
X1231694D03*
X1228348D03*
X1225002D03*
X1221655D03*
X1265159Y22923D03*
X1261813D03*
X1258466D03*
X1255120D03*
X1251773D03*
X1248427D03*
X1245080D03*
X1241734D03*
X1238387D03*
X1235041D03*
X1231694D03*
X1228348D03*
X1225002D03*
X1221655D03*
X1265159Y78833D03*
X1261813D03*
X1258466D03*
X1255120D03*
X1251773D03*
X1248427D03*
X1245080D03*
X1241734D03*
X1238387D03*
X1235041D03*
X1231694D03*
X1228348D03*
X1225002D03*
X1221655D03*
X1265159Y60723D03*
X1261813D03*
X1258466D03*
X1255120D03*
X1251773D03*
X1248427D03*
X1245080D03*
X1241734D03*
X1238387D03*
X1235041D03*
X1231694D03*
X1228348D03*
X1225002D03*
X1221655D03*
X1265159Y41033D03*
X1261813D03*
X1258466D03*
X1255120D03*
X1251773D03*
X1248427D03*
X1245080D03*
X1241734D03*
X1238387D03*
X1235041D03*
X1231694D03*
X1228348D03*
X1225002D03*
X1221655D03*
X1265159Y523900D03*
X1261813D03*
X1258466D03*
X1255120D03*
X1251773D03*
X1248427D03*
X1245080D03*
X1241734D03*
X1238387D03*
X1235041D03*
X1231694D03*
X1228348D03*
X1225002D03*
X1221655D03*
X1265159Y579810D03*
X1261813D03*
X1258466D03*
X1255120D03*
X1251773D03*
X1248427D03*
X1245080D03*
X1241734D03*
X1238387D03*
X1235041D03*
X1231694D03*
X1228348D03*
X1225002D03*
X1221655D03*
X1265159Y561700D03*
X1261813D03*
X1258466D03*
X1255120D03*
X1251773D03*
X1248427D03*
X1245080D03*
X1241734D03*
X1238387D03*
X1235041D03*
X1231694D03*
X1228348D03*
X1225002D03*
X1221655D03*
X1265159Y542010D03*
X1261813D03*
X1258466D03*
X1255120D03*
X1251773D03*
X1248427D03*
X1245080D03*
X1241734D03*
X1238387D03*
X1235041D03*
X1231694D03*
X1228348D03*
X1225002D03*
X1221655D03*
X1265159Y617610D03*
X1261813D03*
X1258466D03*
X1255120D03*
X1251773D03*
X1248427D03*
X1245080D03*
X1241734D03*
X1238387D03*
X1235041D03*
X1231694D03*
X1228348D03*
X1225002D03*
X1221655D03*
X1265159Y599500D03*
X1261813D03*
X1258466D03*
X1255120D03*
X1251773D03*
X1248427D03*
X1245080D03*
X1241734D03*
X1238387D03*
X1235041D03*
X1231694D03*
X1228348D03*
X1225002D03*
X1221655D03*
G54D60*
X35499Y431705D03*
X28499D03*
X28871Y441432D03*
X35871D03*
X28871Y448191D03*
X35871D03*
X47500Y562500D03*
X47150Y599650D03*
X68572Y18008D03*
X75572D03*
X68671Y10407D03*
X75671D03*
X61000Y216212D03*
X54000D03*
X104733Y514100D03*
Y589700D03*
Y551900D03*
X54500Y562500D03*
X54150Y599650D03*
X111733Y514100D03*
Y589700D03*
Y551900D03*
X378292Y13078D03*
X371292D03*
X378432Y51198D03*
X371432D03*
X378292Y589678D03*
X371292D03*
X378842Y551578D03*
X371842D03*
X647900Y286000D03*
X640900D03*
X718437Y-10548D03*
X725437D03*
X721131Y42955D03*
X721000Y520500D03*
X722606Y605050D03*
X715606D03*
X715370Y613530D03*
X722370D03*
X728131Y42955D03*
X753000Y512000D03*
X760000D03*
X728000Y520500D03*
X753343Y551878D03*
X760343D03*
X753343Y589678D03*
X760343D03*
X1028400Y13078D03*
X1021400D03*
X1028630Y51028D03*
X1021630D03*
X1028200Y551000D03*
X1021200D03*
X1027100Y589700D03*
X1020100D03*
X1338000Y46000D03*
X1331000D03*
X1508750Y547150D03*
X1501750D03*
X1559983Y567937D03*
X1552983D03*
X1585270Y558204D03*
Y565204D03*
X1592270Y558204D03*
Y565204D03*
X1691342Y495833D03*
X1698342D03*
X1771500Y516700D03*
X1785000Y100100D03*
X1778000D03*
X1796848Y160937D03*
X1803848D03*
X1778500Y516700D03*
X1837463Y144198D03*
X1844463D03*
X1955046Y76272D03*
X1955458Y88011D03*
X1962046Y76272D03*
X1962458Y88011D03*
G54D252*
X1546953Y273250D03*
Y259750D03*
X1541047D03*
Y273250D03*
G54D162*
X684219Y333516D03*
Y331547D03*
Y329578D03*
Y327609D03*
Y325640D03*
Y323671D03*
Y321702D03*
Y319733D03*
Y317764D03*
Y315795D03*
Y313826D03*
Y311857D03*
Y309888D03*
Y307919D03*
Y305950D03*
Y303981D03*
G54D153*
X688350Y61358D03*
Y59390D03*
Y57421D03*
Y55453D03*
Y53484D03*
Y51516D03*
Y49547D03*
Y47579D03*
Y45610D03*
Y43642D03*
Y547608D03*
Y545640D03*
Y543671D03*
Y541703D03*
Y539734D03*
Y537766D03*
Y535797D03*
Y533829D03*
Y531860D03*
Y529892D03*
X1348550Y121308D03*
Y119340D03*
Y117371D03*
Y115403D03*
Y113434D03*
Y111466D03*
Y109497D03*
Y107529D03*
Y105560D03*
Y103592D03*
X1343350Y526003D03*
Y524034D03*
Y522066D03*
Y520097D03*
Y518129D03*
Y516160D03*
Y514192D03*
Y531908D03*
Y529940D03*
Y527971D03*
G54D117*
X290389Y400359D03*
X297149D03*
X303909D03*
X310668D03*
X317428D03*
X344468D03*
X351228D03*
X320808Y398410D03*
X324188Y396459D03*
X344468D03*
X324188Y392560D03*
X330948D03*
X337708D03*
X344468D03*
X357987Y400359D03*
X364747D03*
X371507D03*
X378267D03*
X385027D03*
X391787D03*
X398546D03*
X434983Y405497D03*
X441743D03*
X448503D03*
X455263D03*
X462023D03*
X468783D03*
X475542D03*
X509342Y401597D03*
X502582Y397696D03*
X509342D03*
Y405497D03*
X516102D03*
X522861D03*
X529621D03*
X939997Y400359D03*
X946757D03*
X953517D03*
X960276D03*
X967036D03*
X970416Y398410D03*
X994076Y400359D03*
X1000836D03*
X1007595D03*
X1014355D03*
X1021115D03*
X1027875D03*
X973796Y396459D03*
X994076D03*
X973796Y392560D03*
X980556D03*
X987316D03*
X994076D03*
X1034635Y400359D03*
X1041395D03*
X1048154D03*
X1084591Y405497D03*
X1091351D03*
X1152190Y397696D03*
X1098111Y405497D03*
X1104871D03*
X1111631D03*
X1118391D03*
X1125150D03*
X1158950Y401597D03*
Y397696D03*
Y405497D03*
X1165710D03*
X1172469D03*
X1179229D03*
G54D225*
X1421647Y534305D03*
X1420072D03*
X1418497D03*
X1416922D03*
X1415347D03*
X1413773D03*
X1412198D03*
X1410623D03*
X1409048D03*
X1407473D03*
X1565287Y595850D03*
X1563712D03*
X1562137D03*
X1560562D03*
X1558987D03*
X1557413D03*
X1555838D03*
X1554263D03*
X1552688D03*
X1551113D03*
G54D315*
X1894689Y518328D03*
G54D306*
X1856354Y84433D03*
Y96430D03*
G54D15*
X-15748Y101221D03*
Y116969D03*
Y132717D03*
Y148465D03*
Y357362D03*
Y373110D03*
Y388858D03*
Y404606D03*
X12205Y156339D03*
X-4331D03*
X17323Y101221D03*
Y116969D03*
Y132717D03*
Y148465D03*
X787Y101221D03*
Y116969D03*
Y132717D03*
Y148465D03*
X33858Y101221D03*
Y116969D03*
Y132717D03*
Y148465D03*
X28740Y109095D03*
Y124843D03*
Y140591D03*
Y156339D03*
X12205Y109095D03*
Y124843D03*
Y140591D03*
X-4331Y109095D03*
Y124843D03*
Y140591D03*
X17323Y357362D03*
Y373110D03*
Y388858D03*
Y404606D03*
X787Y357362D03*
Y373110D03*
Y388858D03*
Y404606D03*
X33858Y357362D03*
Y373110D03*
Y388858D03*
Y404606D03*
X28740Y365236D03*
Y380984D03*
Y396732D03*
X12205Y365236D03*
Y380984D03*
Y396732D03*
X-4331Y365236D03*
Y380984D03*
Y396732D03*
X12205Y412480D03*
X-4331D03*
X28740D03*
G54D135*
X663091Y147445D03*
X658091D03*
X653091D03*
X648091D03*
X663091Y152445D03*
X658091D03*
X653091D03*
X648091D03*
X663091Y157445D03*
X658091D03*
X653091D03*
X648091D03*
X663091Y162445D03*
X658091D03*
X653091D03*
X648091D03*
X663091Y167445D03*
X658091D03*
X653091D03*
X648091D03*
X663091Y172445D03*
X658091D03*
X653091D03*
X648091D03*
X663091Y429925D03*
X658091D03*
X653091D03*
X648091D03*
X663091Y434925D03*
X658091D03*
X653091D03*
X648091D03*
X663091Y439925D03*
X658091D03*
X653091D03*
X648091D03*
X663091Y444925D03*
X658091D03*
X653091D03*
X648091D03*
X663091Y449925D03*
X658091D03*
X653091D03*
X648091D03*
X663091Y454925D03*
X658091D03*
X653091D03*
X648091D03*
X688091Y147445D03*
X683091D03*
X678091D03*
X673091D03*
X668091D03*
X723091D03*
X718091D03*
X713091D03*
X708091D03*
X703091D03*
X698091D03*
X693091D03*
X688091Y152445D03*
X683091D03*
X678091D03*
X673091D03*
X668091D03*
X723091D03*
X718091D03*
X713091D03*
X708091D03*
X703091D03*
X698091D03*
X693091D03*
X688091Y157445D03*
X683091D03*
X678091D03*
X673091D03*
X668091D03*
X723091D03*
X718091D03*
X713091D03*
X708091D03*
X703091D03*
X698091D03*
X693091D03*
X688091Y162445D03*
X683091D03*
X678091D03*
X673091D03*
X668091D03*
X723091D03*
X718091D03*
X713091D03*
X708091D03*
X703091D03*
X698091D03*
X693091D03*
X688091Y167445D03*
X683091D03*
X678091D03*
X673091D03*
X668091D03*
X723091D03*
X718091D03*
X713091D03*
X708091D03*
X703091D03*
X698091D03*
X693091D03*
X688091Y172445D03*
X683091D03*
X678091D03*
X673091D03*
X668091D03*
X723091D03*
X718091D03*
X713091D03*
X708091D03*
X703091D03*
X698091D03*
X693091D03*
X688091Y429925D03*
X683091D03*
X678091D03*
X673091D03*
X668091D03*
X723091D03*
X718091D03*
X713091D03*
X708091D03*
X703091D03*
X698091D03*
X693091D03*
X688091Y434925D03*
X683091D03*
X678091D03*
X673091D03*
X668091D03*
X723091D03*
X718091D03*
X713091D03*
X708091D03*
X703091D03*
X698091D03*
X693091D03*
X688091Y439925D03*
X683091D03*
X678091D03*
X673091D03*
X668091D03*
X723091D03*
X718091D03*
X713091D03*
X708091D03*
X703091D03*
X698091D03*
X693091D03*
X688091Y444925D03*
X683091D03*
X678091D03*
X673091D03*
X668091D03*
X723091D03*
X718091D03*
X713091D03*
X708091D03*
X703091D03*
X698091D03*
X693091D03*
X688091Y449925D03*
X683091D03*
X678091D03*
X673091D03*
X668091D03*
X723091D03*
X718091D03*
X713091D03*
X708091D03*
X703091D03*
X698091D03*
X693091D03*
X688091Y454925D03*
X683091D03*
X678091D03*
X673091D03*
X668091D03*
X723091D03*
X718091D03*
X713091D03*
X708091D03*
X703091D03*
X698091D03*
X693091D03*
X743091Y147445D03*
X738091D03*
X733091D03*
X728091D03*
X743091Y152445D03*
X738091D03*
X733091D03*
X728091D03*
X743091Y157445D03*
X738091D03*
X733091D03*
X728091D03*
X743091Y162445D03*
X738091D03*
X733091D03*
X728091D03*
X743091Y167445D03*
X738091D03*
X733091D03*
X728091D03*
X743091Y172445D03*
X738091D03*
X733091D03*
X728091D03*
X743091Y429925D03*
X738091D03*
X733091D03*
X728091D03*
X743091Y434925D03*
X738091D03*
X733091D03*
X728091D03*
X743091Y439925D03*
X738091D03*
X733091D03*
X728091D03*
X743091Y444925D03*
X738091D03*
X733091D03*
X728091D03*
X743091Y449925D03*
X738091D03*
X733091D03*
X728091D03*
X743091Y454925D03*
X738091D03*
X733091D03*
X728091D03*
X1337618Y147445D03*
X1332618D03*
X1327618D03*
X1322618D03*
X1317618D03*
X1312618D03*
X1307618D03*
X1302618D03*
X1342618D03*
X1297618D03*
X1337618Y152445D03*
X1332618D03*
X1327618D03*
X1322618D03*
X1317618D03*
X1312618D03*
X1307618D03*
X1302618D03*
X1342618D03*
X1297618D03*
X1337618Y157445D03*
X1332618D03*
X1327618D03*
X1322618D03*
X1317618D03*
X1312618D03*
X1307618D03*
X1302618D03*
X1342618D03*
X1297618D03*
X1337618Y162445D03*
X1332618D03*
X1327618D03*
X1322618D03*
X1317618D03*
X1312618D03*
X1307618D03*
X1302618D03*
X1342618D03*
X1297618D03*
X1337618Y167445D03*
X1332618D03*
X1327618D03*
X1322618D03*
X1317618D03*
X1312618D03*
X1307618D03*
X1302618D03*
X1342618D03*
X1297618D03*
X1337618Y172445D03*
X1332618D03*
X1327618D03*
X1322618D03*
X1317618D03*
X1312618D03*
X1307618D03*
X1302618D03*
X1342618D03*
X1297618D03*
X1337618Y429925D03*
X1332618D03*
X1327618D03*
X1322618D03*
X1317618D03*
X1312618D03*
X1307618D03*
X1302618D03*
X1342618D03*
X1297618D03*
X1337618Y434925D03*
X1332618D03*
X1327618D03*
X1322618D03*
X1317618D03*
X1312618D03*
X1307618D03*
X1302618D03*
X1342618D03*
X1297618D03*
X1337618Y439925D03*
X1332618D03*
X1327618D03*
X1322618D03*
X1317618D03*
X1312618D03*
X1307618D03*
X1302618D03*
X1342618D03*
X1297618D03*
X1337618Y444925D03*
X1332618D03*
X1327618D03*
X1322618D03*
X1317618D03*
X1312618D03*
X1307618D03*
X1302618D03*
X1342618D03*
X1297618D03*
X1337618Y449925D03*
X1332618D03*
X1327618D03*
X1322618D03*
X1317618D03*
X1312618D03*
X1307618D03*
X1302618D03*
X1342618D03*
X1297618D03*
X1337618Y454925D03*
X1332618D03*
X1327618D03*
X1322618D03*
X1317618D03*
X1312618D03*
X1307618D03*
X1302618D03*
X1342618D03*
X1297618D03*
X1392618Y147445D03*
X1387618D03*
X1382618D03*
X1377618D03*
X1372618D03*
X1367618D03*
X1362618D03*
X1357618D03*
X1352618D03*
X1347618D03*
X1392618Y152445D03*
X1387618D03*
X1382618D03*
X1377618D03*
X1372618D03*
X1367618D03*
X1362618D03*
X1357618D03*
X1352618D03*
X1347618D03*
X1392618Y157445D03*
X1387618D03*
X1382618D03*
X1377618D03*
X1372618D03*
X1367618D03*
X1362618D03*
X1357618D03*
X1352618D03*
X1347618D03*
X1392618Y162445D03*
X1387618D03*
X1382618D03*
X1377618D03*
X1372618D03*
X1367618D03*
X1362618D03*
X1357618D03*
X1352618D03*
X1347618D03*
X1392618Y167445D03*
X1387618D03*
X1382618D03*
X1377618D03*
X1372618D03*
X1367618D03*
X1362618D03*
X1357618D03*
X1352618D03*
X1347618D03*
X1392618Y172445D03*
X1387618D03*
X1382618D03*
X1377618D03*
X1372618D03*
X1367618D03*
X1362618D03*
X1357618D03*
X1352618D03*
X1347618D03*
X1392618Y429925D03*
X1387618D03*
X1382618D03*
X1377618D03*
X1372618D03*
X1367618D03*
X1362618D03*
X1357618D03*
X1352618D03*
X1347618D03*
X1392618Y434925D03*
X1387618D03*
X1382618D03*
X1377618D03*
X1372618D03*
X1367618D03*
X1362618D03*
X1357618D03*
X1352618D03*
X1347618D03*
X1392618Y439925D03*
X1387618D03*
X1382618D03*
X1377618D03*
X1372618D03*
X1367618D03*
X1362618D03*
X1357618D03*
X1352618D03*
X1347618D03*
X1392618Y444925D03*
X1387618D03*
X1382618D03*
X1377618D03*
X1372618D03*
X1367618D03*
X1362618D03*
X1357618D03*
X1352618D03*
X1347618D03*
X1392618Y449925D03*
X1387618D03*
X1382618D03*
X1377618D03*
X1372618D03*
X1367618D03*
X1362618D03*
X1357618D03*
X1352618D03*
X1347618D03*
X1392618Y454925D03*
X1387618D03*
X1382618D03*
X1377618D03*
X1372618D03*
X1367618D03*
X1362618D03*
X1357618D03*
X1352618D03*
X1347618D03*
G54D234*
G01X9100Y22344D02*
Y23600D01*
X10600Y25100D01*
G01X20100Y22344D02*
Y24244D01*
X19400Y24944D01*
G01X13716Y24861D02*
Y24660D01*
X12600Y23544D01*
Y22344D01*
G01X4522Y54358D02*
X5339Y53541D01*
X9823D01*
G01X10925Y56167D02*
X9823Y55065D01*
Y53541D01*
G01X14025Y56211D02*
X13323Y55509D01*
Y53541D01*
G01X41000Y274647D02*
X42753Y276400D01*
X44900D01*
X51300Y270000D01*
X59300D01*
X62500Y273200D01*
Y275500D01*
G01X59500D02*
Y273700D01*
X58000Y272200D01*
X52400D01*
X45900Y278700D01*
G01X45800Y278800D02*
X40800D01*
X37000Y275000D01*
G01D02*
Y274647D01*
G01X16990Y525130D02*
X20490D01*
G01X24400Y519500D02*
Y522360D01*
X21630Y525130D01*
X20490D01*
G01X83820Y481460D02*
Y478080D01*
G01X20490Y521630D02*
Y514390D01*
X19533Y513433D01*
G01X12450Y519350D02*
X14730Y521630D01*
X16990D01*
G01D02*
X20490D01*
G01X-1000Y564000D02*
Y565800D01*
X0Y566800D01*
G01Y528800D02*
Y530178D01*
X1040Y531218D01*
G01X9100Y566900D02*
X10000Y566000D01*
Y564000D01*
G01X9400Y531300D02*
X10200Y530500D01*
Y528800D01*
G01X3500D02*
Y531200D01*
X3600Y531300D01*
G01Y567300D02*
X2500Y566200D01*
Y564000D01*
G01X106000Y11328D02*
Y8808D01*
X105892Y8700D01*
G01X109500Y14828D02*
X106000D01*
G01D02*
Y17260D01*
G01X57204Y8216D02*
X59327D01*
X60035Y7508D01*
G01X50096Y-10930D02*
X50235Y-11069D01*
X52499D01*
X52967Y-10601D01*
X54889D01*
G01D02*
Y-13808D01*
G01X105892Y45290D02*
Y49244D01*
X105898Y49250D01*
G01Y55194D02*
Y52750D01*
G01D02*
X109392D01*
G01X101000Y121500D02*
X97396D01*
X96939Y121957D01*
X92552D01*
X91913Y121318D01*
G01X97600Y167800D02*
X95100Y165300D01*
G01X97200Y262300D02*
X99238D01*
X102118Y265180D01*
X103250D01*
G01X97200Y262300D02*
Y265000D01*
G01X99758Y240300D02*
X97358D01*
G01X83553Y239800D02*
X90402D01*
X90558Y239956D01*
G01D02*
X90902Y240300D01*
X93858D01*
G01X83000Y262700D02*
X89540D01*
X89940Y262300D01*
X90040D01*
G01D02*
X93700D01*
G01X74500Y317000D02*
X75900D01*
X77300Y315600D01*
G01X54400Y340300D02*
X55600Y341500D01*
X57000D01*
G01D02*
X60000D01*
G01X67400Y391690D02*
X68500Y390590D01*
Y388600D01*
G01X57500Y385500D02*
Y388100D01*
G01X54000Y385500D02*
X57500D01*
G01X61000Y385400D02*
Y383000D01*
G01Y385400D02*
X59900Y386500D01*
Y388600D01*
G01X57800Y392100D02*
X55100Y389400D01*
X54900D01*
G01X90518Y388828D02*
X88300Y386610D01*
G01X71148Y461201D02*
X68648D01*
X66498Y463351D01*
Y467868D01*
X66016Y468350D01*
G01X104733Y514100D02*
Y517325D01*
X105958Y518550D01*
G01X104733Y551900D02*
Y555901D01*
X105412Y556580D01*
G01X104733Y589700D02*
Y594151D01*
X105352Y594770D01*
G01X150391Y29949D02*
Y23629D01*
X150392Y23628D01*
Y22923D01*
G01D02*
Y14815D01*
X150391Y14814D01*
G01X163391Y29949D02*
X163777Y29563D01*
Y22923D01*
G01D02*
Y15064D01*
X163427Y14714D01*
G01X157084Y29949D02*
Y22923D01*
G01D02*
Y14814D01*
G01X150392Y-14877D02*
Y-14172D01*
X150391Y-14171D01*
Y-7851D01*
G01X163777Y-14877D02*
Y-8237D01*
X163391Y-7851D01*
G01X153738Y9114D02*
Y3233D01*
G01D02*
Y-1751D01*
G01X157084Y-14877D02*
Y-7851D01*
G01X160431Y9114D02*
Y3233D01*
G01D02*
Y-1801D01*
G01X120273Y27899D02*
Y22923D01*
G01X141893Y27936D02*
X143698Y26131D01*
Y22924D01*
X143699Y22923D01*
G01X126966D02*
Y29563D01*
X126580Y29949D01*
G01X143699Y22923D02*
Y18933D01*
X141880Y17114D01*
G01X133659Y22923D02*
Y15514D01*
X132959Y14814D01*
G01X147045Y9114D02*
Y3233D01*
G01D02*
Y-1751D01*
G01X137006Y3233D02*
Y8872D01*
X136780Y9098D01*
G01X130313Y3233D02*
Y8964D01*
X130163Y9114D01*
G01X130313Y-1751D02*
Y3233D01*
G01X123620Y-1801D02*
Y3233D01*
G01X136780Y-1801D02*
Y-913D01*
X137006Y-687D01*
Y3233D01*
G01X126966Y-14877D02*
Y-8237D01*
X126580Y-7851D01*
G01X120273Y-9901D02*
Y-14877D01*
G01X143699D02*
X143698Y-14876D01*
Y-11669D01*
X141893Y-9864D01*
G01X123892Y13078D02*
X125528Y14714D01*
X126616D01*
G01X120273Y22923D02*
Y16839D01*
G01X170470Y22923D02*
Y15514D01*
X169770Y14814D01*
G01X167124Y3233D02*
Y8964D01*
X166974Y9114D01*
G01X167124Y-1751D02*
Y3233D01*
G01X123620Y9114D02*
Y3233D01*
G01X120273Y16839D02*
X118511D01*
X116500Y14828D01*
G01X126616Y14714D02*
X126966Y15064D01*
Y22923D01*
G01X113000Y14828D02*
Y15640D01*
X114680Y17320D01*
G01X109500Y11328D02*
X113000D01*
G01X116500D02*
X117708D01*
X119458Y13078D01*
X120392D01*
G01X113000Y11328D02*
X116500D01*
G01X120273Y60723D02*
Y54839D01*
G01X123620Y41033D02*
Y46914D01*
G01X136780Y46898D02*
X137006Y46672D01*
Y41033D01*
G01D02*
Y37113D01*
X136780Y36887D01*
Y35999D01*
G01X130313Y41033D02*
Y35983D01*
G01X130163Y84714D02*
X130313Y84564D01*
Y78833D01*
G01X136780Y84698D02*
X137006Y84472D01*
Y78833D01*
G01X153738D02*
Y84714D01*
G01Y73849D02*
Y78833D01*
G01X160431D02*
Y73799D01*
G01Y84714D02*
Y78833D01*
G01X150392Y60723D02*
Y61428D01*
X150391Y61429D01*
Y67749D01*
G01Y52614D02*
X150392Y52615D01*
Y60723D01*
G01X160431Y35999D02*
Y41033D01*
G01X163777Y60723D02*
Y52864D01*
X163427Y52514D01*
G01X160431Y41033D02*
Y46914D01*
G01X163391Y67749D02*
X163777Y67363D01*
Y60723D01*
G01X157084D02*
Y67749D01*
G01Y52614D02*
Y60723D01*
G01X153738Y36049D02*
Y41033D01*
G01D02*
Y46914D01*
G01X147045Y73849D02*
Y78833D01*
G01D02*
Y84714D01*
G01X130313Y73849D02*
Y78833D01*
G01X123620Y73799D02*
Y78833D01*
G01X136780Y73799D02*
Y74687D01*
X137006Y74913D01*
Y78833D01*
G01X147045Y36049D02*
Y41033D01*
G01D02*
Y46914D01*
G01X120273Y66000D02*
Y60723D01*
G01X126580Y67749D02*
X126966Y67363D01*
Y60723D01*
G01X143699D02*
X143698Y60724D01*
Y63931D01*
X141893Y65736D01*
G01X130163Y46914D02*
X130313Y46764D01*
Y41033D01*
G01X123620Y35983D02*
Y41033D01*
G01X141880Y54914D02*
X143699Y56733D01*
Y60723D01*
G01X133659D02*
Y53314D01*
X132959Y52614D01*
G01X126966Y60723D02*
Y52864D01*
X126616Y52514D01*
G01X166974Y73849D02*
X167024D01*
X167124Y73949D01*
Y78833D01*
G01D02*
Y84564D01*
X166974Y84714D01*
G01Y46914D02*
X167124Y46764D01*
Y41033D01*
G01X170470Y60723D02*
Y53314D01*
X169770Y52614D01*
G01X167124Y41033D02*
Y36049D01*
G01X123620Y84714D02*
Y78833D01*
G01X120273Y54839D02*
X118189D01*
X116000Y52650D01*
G01X112500D02*
Y53518D01*
X114082Y55100D01*
G01X112007Y93139D02*
X113262D01*
X114284Y92117D01*
Y90529D01*
G01X117354Y87029D02*
X114284D01*
G01X117354D02*
X120188D01*
X120392Y87233D01*
G01X114284Y87029D02*
X114076Y86821D01*
X111189D01*
G01X120392Y87233D02*
X120407Y87248D01*
G01X112500Y49150D02*
X109492D01*
X109392Y49250D01*
G01X116000Y49150D02*
X112500D01*
G01X120392Y50878D02*
X118938D01*
X117210Y49150D01*
X116000D01*
G01X123100Y209200D02*
Y210441D01*
X124692Y212033D01*
X124895D01*
G01X120179Y210345D02*
X121324Y209200D01*
X123100D01*
G01X126600D02*
X127754Y210354D01*
Y211853D01*
G01X113200Y402500D02*
X110500D01*
X110397Y402603D01*
G01X117363Y417416D02*
X116949Y417002D01*
X114270D01*
X113100Y415832D01*
Y414700D01*
G01Y411700D02*
Y414700D01*
G01X154843Y418959D02*
Y417467D01*
X151909Y414533D01*
Y413267D01*
G01X154814Y422658D02*
Y418988D01*
X154843Y418959D01*
G01X157084Y523900D02*
Y530949D01*
G01X150392Y523900D02*
Y524628D01*
X150391Y524629D01*
Y530949D01*
G01X163777Y523900D02*
Y530563D01*
X163391Y530949D01*
G01X120273Y523900D02*
Y529137D01*
X120210Y529200D01*
G01X126966Y523900D02*
Y530563D01*
X126580Y530949D01*
G01X143699Y523900D02*
Y523923D01*
X143698Y523924D01*
Y527131D01*
X141893Y528936D01*
G01X123792Y507300D02*
Y509942D01*
X123620Y510114D01*
G01X120292Y507300D02*
Y509700D01*
X119892Y510100D01*
G01X130163Y585714D02*
X130313Y585564D01*
Y579810D01*
G01D02*
Y574849D01*
G01X167124Y542010D02*
Y537149D01*
X167024Y537049D01*
X166974D01*
G01X160431Y542010D02*
Y547914D01*
G01Y536999D02*
Y542010D01*
G01X166974Y547914D02*
X167124Y547764D01*
Y542010D01*
G01X153738D02*
Y537049D01*
G01Y547914D02*
Y542010D01*
G01X123692Y589200D02*
Y585786D01*
X123620Y585714D01*
G01Y579810D02*
Y574799D01*
G01X130313Y542010D02*
Y537049D01*
G01X147045Y542010D02*
Y537049D01*
G01Y547914D02*
Y542010D01*
G01X123620D02*
Y536999D01*
G01X130163Y547914D02*
X130313Y547764D01*
Y542010D01*
G01X137006D02*
Y538113D01*
X136780Y537887D01*
Y536999D01*
G01X123492Y551400D02*
Y548042D01*
X123620Y547914D01*
G01X153738Y579810D02*
Y585714D01*
G01Y574849D02*
Y579810D01*
G01X157084Y561700D02*
Y568749D01*
G01X160431Y579810D02*
Y574799D01*
G01Y585714D02*
Y579810D01*
G01X167124D02*
Y574949D01*
X167024Y574849D01*
X166974D01*
G01Y585714D02*
X167124Y585564D01*
Y579810D01*
G01X163777Y561700D02*
Y568363D01*
X163391Y568749D01*
G01X150392Y561700D02*
Y562428D01*
X150391Y562429D01*
Y568749D01*
G01X123620Y585714D02*
Y579810D01*
G01X143699Y561700D02*
Y561723D01*
X143698Y561724D01*
Y564931D01*
X141893Y566736D01*
G01X147045Y579810D02*
Y585714D01*
G01Y574849D02*
Y579810D01*
G01X120273Y561700D02*
Y566719D01*
X120092Y566900D01*
G01X137006Y579810D02*
Y575913D01*
X136780Y575687D01*
Y574799D01*
G01X126966Y561700D02*
Y568363D01*
X126580Y568749D01*
G01X123620Y547914D02*
Y542010D01*
G01X120273D02*
Y537364D01*
X119892Y536983D01*
G01X119992Y551400D02*
Y548000D01*
X119892Y547900D01*
G01X120273Y579810D02*
Y575081D01*
X119892Y574700D01*
G01X120192Y589200D02*
Y586000D01*
X119892Y585700D01*
G01X150392Y599500D02*
Y600228D01*
X150391Y600229D01*
Y606549D01*
G01X163777Y599500D02*
Y606163D01*
X163391Y606549D01*
G01X157084Y599500D02*
Y606549D01*
G01X120273Y599500D02*
Y604719D01*
X120092Y604900D01*
G01X126966Y599500D02*
Y606163D01*
X126580Y606549D01*
G01X143699Y599500D02*
Y599523D01*
X143698Y599524D01*
Y602731D01*
X141893Y604536D01*
G01X130313Y612649D02*
Y617610D01*
G01X137006D02*
Y613713D01*
X136780Y613487D01*
Y612599D01*
G01X147045Y612649D02*
Y617610D01*
G01X123620D02*
Y612599D01*
G01X167124Y617610D02*
Y612749D01*
X167024Y612649D01*
X166974D01*
G01X160431Y612599D02*
Y617610D01*
G01X153738Y612649D02*
Y617610D01*
G01X120273D02*
Y612964D01*
X119892Y612583D01*
G01X217321Y22923D02*
X217320Y22924D01*
Y26131D01*
X215515Y27936D01*
G01X215502Y17114D02*
X217321Y18933D01*
Y22923D01*
G01X230706Y14814D02*
X230707Y14815D01*
Y22923D01*
G01D02*
X230706Y22924D01*
Y29949D01*
G01X224014Y22923D02*
Y23628D01*
X224013Y23629D01*
Y29949D01*
G01Y14814D02*
X224014Y14815D01*
Y22923D01*
G01X217321Y-14877D02*
X217320Y-14876D01*
Y-11669D01*
X215515Y-9864D01*
G01X220667Y-1751D02*
Y3233D01*
G01X227360D02*
Y-1751D01*
G01Y9114D02*
Y3233D01*
G01X220667D02*
Y9114D01*
G01X230707Y-14877D02*
X230706Y-14876D01*
Y-7851D01*
G01X224014Y-14877D02*
Y-14172D01*
X224013Y-14171D01*
Y-7851D01*
G01X210402Y9098D02*
X210628Y8872D01*
Y3233D01*
G01X206581Y14814D02*
X207281Y15514D01*
Y22923D01*
G01X193895Y29949D02*
Y22924D01*
X193896Y22923D01*
G01X200588D02*
Y29563D01*
X200202Y29949D01*
G01X187203Y22923D02*
Y23628D01*
X187202Y23629D01*
Y29949D01*
G01Y14814D02*
X187203Y14815D01*
Y22923D01*
G01X200238Y14714D02*
X200588Y15064D01*
Y22923D01*
G01X193896D02*
Y14815D01*
X193895Y14814D01*
G01X193896Y-14877D02*
X193895Y-14876D01*
Y-7851D01*
G01X200588Y-14877D02*
Y-8237D01*
X200202Y-7851D01*
G01X187203Y-14877D02*
Y-14172D01*
X187202Y-14171D01*
Y-7851D01*
G01X203785Y9114D02*
X203935Y8964D01*
Y3233D01*
G01X197242Y9114D02*
Y3233D01*
G01X190549Y9114D02*
Y3233D01*
G01X203935D02*
Y-1751D01*
G01X197242Y3233D02*
Y-1801D01*
G01X190549Y3233D02*
Y-1751D01*
G01X180510Y22923D02*
X180509Y22924D01*
Y26131D01*
X178704Y27936D01*
G01X178691Y17114D02*
X180510Y18933D01*
Y22923D01*
G01Y-14877D02*
X180509Y-14876D01*
Y-11669D01*
X178704Y-9864D01*
G01X183856Y3233D02*
Y9114D01*
G01X173817Y3233D02*
Y8872D01*
X173591Y9098D01*
G01X183856Y-1751D02*
Y3233D01*
G01X173591Y-1801D02*
Y-1601D01*
X173817Y-1375D01*
Y3233D01*
G01X220667Y78833D02*
Y84714D01*
G01X227360D02*
Y78833D01*
G01X220667Y73849D02*
Y78833D01*
G01X227360D02*
Y73849D01*
G01X217321Y60723D02*
X217320Y60724D01*
Y63931D01*
X215515Y65736D01*
G01X215502Y54914D02*
X217321Y56733D01*
Y60723D01*
G01X230707D02*
X230706Y60724D01*
Y67749D01*
G01X224014Y60723D02*
Y61428D01*
X224013Y61429D01*
Y67749D01*
G01X227360Y41033D02*
Y46914D01*
G01X220667Y41033D02*
Y46914D01*
G01Y36049D02*
Y41033D01*
G01X227360Y36049D02*
Y41033D01*
G01X230706Y52614D02*
X230707Y52615D01*
Y60723D01*
G01X224013Y52614D02*
X224014Y52615D01*
Y60723D01*
G01X197242Y78833D02*
Y84714D01*
G01X190549Y78833D02*
Y73849D01*
G01Y84714D02*
Y78833D01*
G01X197242Y73799D02*
Y78833D01*
G01X203935Y73849D02*
Y78833D01*
G01X200202Y67749D02*
X200588Y67363D01*
Y60723D01*
G01X210628Y78833D02*
Y84472D01*
X210402Y84698D01*
G01X203935Y78833D02*
Y84564D01*
X203785Y84714D01*
G01X197242Y46914D02*
Y41033D01*
G01X190549Y36049D02*
Y41033D01*
G01X210402Y46898D02*
X210628Y46672D01*
Y41033D01*
G01X207281Y60723D02*
Y53314D01*
X206581Y52614D01*
G01X187202Y67749D02*
Y61429D01*
X187203Y61428D01*
Y60723D01*
G01X193895Y67749D02*
Y60724D01*
X193896Y60723D01*
G01X200588D02*
Y52864D01*
X200238Y52514D01*
G01X193896Y60723D02*
Y52615D01*
X193895Y52614D01*
G01X187203Y60723D02*
Y52615D01*
X187202Y52614D01*
G01X203935Y36049D02*
Y41033D01*
G01D02*
Y46764D01*
X203785Y46914D01*
G01X190549Y41033D02*
Y46914D01*
G01X183856Y78833D02*
Y73849D01*
G01X173817Y78833D02*
Y84472D01*
X173591Y84698D01*
G01X183856Y84714D02*
Y78833D01*
G01X173591Y73799D02*
Y73999D01*
X173817Y74225D01*
Y78833D01*
G01X183856Y36049D02*
Y41033D01*
G01X180510Y60723D02*
X180509Y60724D01*
Y63931D01*
X178704Y65736D01*
G01X183856Y41033D02*
Y46914D01*
G01X173817Y41033D02*
Y36425D01*
X173591Y36199D01*
Y35999D01*
G01X178691Y54914D02*
X180510Y56733D01*
Y60723D01*
G01X224014Y523900D02*
Y524628D01*
X224013Y524629D01*
Y530949D01*
G01X230707Y523900D02*
Y523923D01*
X230706Y523924D01*
Y530949D01*
G01X217321Y523900D02*
Y523923D01*
X217320Y523924D01*
Y527131D01*
X215515Y528936D01*
G01X187203Y523900D02*
Y524628D01*
X187202Y524629D01*
Y530949D01*
G01X200588Y523900D02*
Y530563D01*
X200202Y530949D01*
G01X193896Y523900D02*
Y523923D01*
X193895Y523924D01*
Y530949D01*
G01X180510Y523900D02*
Y523923D01*
X180509Y523924D01*
Y527131D01*
X178704Y528936D01*
G01X227360Y542010D02*
Y537049D01*
G01X220667Y542010D02*
Y537049D01*
G01X203935Y542010D02*
Y537049D01*
G01X197242Y542010D02*
Y547914D01*
G01Y536999D02*
Y542010D01*
G01X190549D02*
Y537049D01*
G01X183856Y542010D02*
Y537049D01*
G01Y547914D02*
Y542010D01*
G01X190549Y547914D02*
Y542010D01*
G01X173817D02*
Y537425D01*
X173591Y537199D01*
Y536999D01*
G01X227360Y579810D02*
Y574849D01*
G01X230707Y561700D02*
Y561723D01*
X230706Y561724D01*
Y568749D01*
G01X220667Y579810D02*
Y574849D01*
G01X224014Y561700D02*
Y562428D01*
X224013Y562429D01*
Y568749D01*
G01X217321Y561700D02*
Y561723D01*
X217320Y561724D01*
Y564931D01*
X215515Y566736D01*
G01X197242Y579810D02*
Y585714D01*
G01Y574799D02*
Y579810D01*
G01X180510Y561700D02*
Y561723D01*
X180509Y561724D01*
Y564931D01*
X178704Y566736D01*
G01X173817Y579810D02*
Y575225D01*
X173591Y574999D01*
Y574799D01*
G01X183856Y579810D02*
Y585714D01*
G01Y574849D02*
Y579810D01*
G01X190549D02*
Y585714D01*
G01Y574849D02*
Y579810D01*
G01X193896Y561700D02*
Y561723D01*
X193895Y561724D01*
Y568749D01*
G01X187203Y561700D02*
Y562428D01*
X187202Y562429D01*
Y568749D01*
G01X200588Y561700D02*
Y568363D01*
X200202Y568749D01*
G01X203935Y579810D02*
Y574849D01*
G01X224014Y599500D02*
Y600228D01*
X224013Y600229D01*
Y606549D01*
G01X230707Y599500D02*
Y599523D01*
X230706Y599524D01*
Y606549D01*
G01X217321Y599500D02*
Y599523D01*
X217320Y599524D01*
Y602731D01*
X215515Y604536D01*
G01X200588Y599500D02*
Y606163D01*
X200202Y606549D01*
G01X187203Y599500D02*
Y600228D01*
X187202Y600229D01*
Y606549D01*
G01X193896Y599500D02*
Y599523D01*
X193895Y599524D01*
Y606549D01*
G01X180510Y599500D02*
Y599523D01*
X180509Y599524D01*
Y602731D01*
X178704Y604536D01*
G01X227360Y617610D02*
Y612649D01*
G01X220667Y617610D02*
Y612649D01*
G01X190549D02*
Y617610D01*
G01X183856Y612649D02*
Y617610D01*
G01X203935D02*
Y612649D01*
G01X197242Y612599D02*
Y617610D01*
G01X173817D02*
Y613025D01*
X173591Y612799D01*
Y612599D01*
G01X274210Y22923D02*
Y18650D01*
X273860Y18300D01*
Y14714D01*
G01X273824Y29949D02*
X274210Y29563D01*
Y22923D01*
G01X289124Y17114D02*
X290943Y18933D01*
Y22923D01*
G01D02*
X290942Y22924D01*
Y26131D01*
X289137Y27936D01*
G01X280203Y14814D02*
X280903Y15514D01*
Y22923D01*
G01X274210Y-14877D02*
Y-8237D01*
X273824Y-7851D01*
G01X277557Y3233D02*
Y-1751D01*
G01X277407Y9114D02*
X277557Y8964D01*
Y3233D01*
G01X284024Y9098D02*
X284250Y8872D01*
Y3233D01*
G01X290943Y-14877D02*
X290942Y-14876D01*
Y-11669D01*
X289137Y-9864D01*
G01X260825Y22923D02*
Y23628D01*
X260824Y23629D01*
Y29949D01*
G01X254132Y22923D02*
X254131Y22924D01*
Y26131D01*
X252326Y27936D01*
G01X237399Y22923D02*
Y29563D01*
X237013Y29949D01*
G01X237049Y14714D02*
X237399Y15064D01*
Y22923D01*
G01X267518D02*
X267517Y22924D01*
Y29949D01*
G01Y14814D02*
Y22922D01*
X267518Y22923D01*
G01X260824Y14814D02*
Y22922D01*
X260825Y22923D01*
G01X243392Y14814D02*
X244092Y15514D01*
Y22923D01*
G01X252313Y17114D02*
X254132Y18933D01*
Y22923D01*
G01X270864Y3233D02*
Y-1801D01*
G01Y9114D02*
Y3233D01*
G01X264171D02*
Y9114D01*
G01X234053Y3233D02*
Y-1801D01*
G01X264171Y-1751D02*
Y3233D01*
G01X240746Y-1751D02*
Y3233D01*
G01X257478D02*
Y-1751D01*
G01X247439Y3233D02*
Y8872D01*
X247213Y9098D01*
G01X240746Y3233D02*
Y8964D01*
X240596Y9114D01*
G01X257478D02*
Y3233D01*
G01X234053Y9114D02*
Y3233D01*
G01X254132Y-14877D02*
X254131Y-14876D01*
Y-11669D01*
X252326Y-9864D01*
G01X260825Y-14877D02*
Y-14172D01*
X260824Y-14171D01*
Y-7851D01*
G01X237399Y-14877D02*
Y-8237D01*
X237013Y-7851D01*
G01X267518Y-14877D02*
X267517Y-14876D01*
Y-7851D01*
G01X277407Y73849D02*
X277557Y73999D01*
Y78833D01*
G01D02*
Y84564D01*
X277407Y84714D01*
G01X284250Y78833D02*
Y84472D01*
X284024Y84698D01*
G01X274210Y60723D02*
Y67363D01*
X273824Y67749D01*
G01X277557Y36049D02*
Y41033D01*
G01X290943Y60723D02*
X290942Y60724D01*
Y63931D01*
X289137Y65736D01*
G01X289124Y54914D02*
X290943Y56733D01*
Y60723D01*
G01X284250Y41033D02*
Y46672D01*
X284024Y46898D01*
G01X280203Y52614D02*
X280903Y53314D01*
Y60723D01*
G01X274210D02*
Y53782D01*
X277407Y50585D01*
Y46914D01*
G01X270864Y73799D02*
Y78833D01*
G01D02*
Y84714D01*
G01X264171Y78833D02*
Y84714D01*
G01X257478Y78833D02*
Y73849D01*
G01X247439Y78833D02*
Y84472D01*
X247213Y84698D01*
G01X240746Y78833D02*
Y84564D01*
X240596Y84714D01*
G01X234053Y78833D02*
Y73799D01*
G01Y84714D02*
Y78833D01*
G01X264171Y73849D02*
Y78833D01*
G01X257478Y84714D02*
Y78833D01*
G01X240746Y73849D02*
Y78833D01*
G01Y41033D02*
Y36049D01*
G01X234053Y41033D02*
Y35999D01*
G01X267517Y67749D02*
Y60724D01*
X267518Y60723D01*
G01D02*
Y52615D01*
X267517Y52614D01*
G01X270864Y35999D02*
Y41033D01*
G01D02*
Y46914D01*
G01X260825Y60723D02*
Y61428D01*
X260824Y61429D01*
Y67749D01*
G01X254132Y60723D02*
X254131Y60724D01*
Y63931D01*
X252326Y65736D01*
G01X237013Y67749D02*
X237399Y67363D01*
Y60723D01*
G01X240596Y46914D02*
X240746Y46764D01*
Y41033D01*
G01X234053Y46914D02*
Y41033D01*
G01X247213Y46898D02*
X247439Y46672D01*
Y41033D01*
G01X264171Y46914D02*
Y41033D01*
G01X257478Y46914D02*
Y41033D01*
G01X260824Y52614D02*
Y60722D01*
X260825Y60723D01*
G01X252313Y54914D02*
X254132Y56733D01*
Y60723D01*
G01X244092D02*
Y53314D01*
X243392Y52614D01*
G01X237399Y60723D02*
Y52864D01*
X237049Y52514D01*
G01X264171Y41033D02*
Y36049D01*
G01X257478Y41033D02*
Y36049D01*
G01X277407Y46914D02*
X277557Y46764D01*
Y41033D01*
G01X274210Y523900D02*
Y530563D01*
X273824Y530949D01*
G01X290943Y523900D02*
Y523923D01*
X290942Y523924D01*
Y527131D01*
X289137Y528936D01*
G01X260825Y523900D02*
Y524628D01*
X260824Y524629D01*
Y530949D01*
G01X237399Y523900D02*
Y530563D01*
X237013Y530949D01*
G01X254132Y523900D02*
Y523923D01*
X254131Y523924D01*
Y527131D01*
X252326Y528936D01*
G01X267518Y523900D02*
Y523923D01*
X267517Y523924D01*
Y530949D01*
G01X277557Y542010D02*
Y537199D01*
X277407Y537049D01*
G01X264171Y542010D02*
Y537049D01*
G01X257478Y542010D02*
Y537049D01*
G01X240746Y542010D02*
Y537049D01*
G01X234053Y542010D02*
Y536999D01*
G01X270864Y542010D02*
Y536999D01*
G01X290943Y561700D02*
Y561723D01*
X290942Y561724D01*
Y564931D01*
X289137Y566736D01*
G01X277557Y579810D02*
Y574999D01*
X277407Y574849D01*
G01X274210Y561700D02*
Y568363D01*
X273824Y568749D01*
G01X260825Y561700D02*
Y562428D01*
X260824Y562429D01*
Y568749D01*
G01X257478Y579810D02*
Y574849D01*
G01X264171Y579810D02*
Y574849D01*
G01X237399Y561700D02*
Y568363D01*
X237013Y568749D01*
G01X240746Y579810D02*
Y574849D01*
G01X234053Y579810D02*
Y574799D01*
G01X254132Y561700D02*
Y561723D01*
X254131Y561724D01*
Y564931D01*
X252326Y566736D01*
G01X267518Y561700D02*
Y561723D01*
X267517Y561724D01*
Y568749D01*
G01X270864Y579810D02*
Y574799D01*
G01X274210Y599500D02*
Y606163D01*
X273824Y606549D01*
G01X290943Y599500D02*
Y599523D01*
X290942Y599524D01*
Y602731D01*
X289137Y604536D01*
G01X260825Y599500D02*
Y600228D01*
X260824Y600229D01*
Y606549D01*
G01X237399Y599500D02*
Y606163D01*
X237013Y606549D01*
G01X254132Y599500D02*
Y599523D01*
X254131Y599524D01*
Y602731D01*
X252326Y604536D01*
G01X267518Y599500D02*
Y599523D01*
X267517Y599524D01*
Y606549D01*
G01X264171Y617610D02*
Y612449D01*
G01X257478Y617610D02*
Y612649D01*
G01X234053Y617610D02*
Y612599D01*
G01X240746Y617610D02*
Y612649D01*
G01X270864Y617610D02*
Y612399D01*
G01X277557Y617610D02*
Y612799D01*
X277407Y612649D01*
Y612449D01*
G01X353500Y13200D02*
X354614Y14314D01*
X357492D01*
G01X324642Y13200D02*
X321192D01*
G01X312442D02*
X307992D01*
G01X297636Y22923D02*
Y23628D01*
X297635Y23629D01*
Y29949D01*
G01Y14814D02*
Y22922D01*
X297636Y22923D01*
G01X300982Y-1751D02*
Y3233D01*
G01X294289Y-1751D02*
Y3233D01*
G01X307675D02*
Y-1843D01*
G01Y9300D02*
Y3233D01*
G01X300982D02*
Y9114D01*
G01X294289Y3233D02*
Y9114D01*
G01X304329Y-14877D02*
X304328Y-14876D01*
Y-7851D01*
G01X297636Y-14877D02*
Y-14172D01*
X297635Y-14171D01*
Y-7851D01*
G01X304328Y22922D02*
X304329Y22923D01*
G01D02*
X304328Y22924D01*
G01D02*
Y29949D01*
G01X337642Y51000D02*
X334292D01*
G01X304278Y90414D02*
Y98986D01*
X306092Y100800D01*
G01X300982Y73849D02*
Y78833D01*
G01X294289Y73849D02*
Y78833D01*
G01X300982D02*
Y84714D01*
G01X294289Y78833D02*
Y84714D01*
G01X324642Y51000D02*
X321192D01*
G01X312442D02*
X309572D01*
X309301Y50729D01*
X307950D01*
G01X304329Y60723D02*
X304328Y60724D01*
Y67749D01*
G01X297636Y60723D02*
Y61428D01*
X297635Y61429D01*
Y67749D01*
G01Y52614D02*
X297636Y52615D01*
Y60723D01*
G01X294289Y46914D02*
Y41033D01*
G01X300982D02*
Y46914D01*
G01X294289Y41033D02*
Y36049D01*
G01X307675Y35957D02*
Y41033D01*
G01X300982Y36049D02*
Y41033D01*
G01X307675D02*
Y46175D01*
G01X304328Y52614D02*
X304329Y52615D01*
G01X307592Y73800D02*
X307675Y73883D01*
G01D02*
Y78833D01*
G01X304329Y52615D02*
Y60723D01*
G01X306092Y100800D02*
X304192Y102700D01*
Y105000D01*
G01X309981Y104689D02*
X311017Y105725D01*
X313637D01*
G01X297636Y523900D02*
Y524628D01*
X297635Y524629D01*
Y530949D01*
G01X304329Y523900D02*
Y523923D01*
X304328Y523924D01*
Y530949D01*
G01X307693Y495595D02*
X305988Y497300D01*
X304392D01*
G01X317714Y515364D02*
X318620Y516270D01*
Y519817D01*
X317714Y520723D01*
G01X337793Y515364D02*
Y523900D01*
G01D02*
Y523923D01*
G01X313193Y495595D02*
Y497644D01*
X311701Y499136D01*
G01X311021Y523900D02*
Y523923D01*
G01Y515364D02*
Y523900D01*
G01X307675Y579833D02*
Y579810D01*
G01Y574757D02*
Y579810D01*
G01X300982D02*
Y579833D01*
G01Y574849D02*
Y579810D01*
G01X357539Y550511D02*
X354989D01*
X353500Y552000D01*
G01X337642D02*
X334292D01*
G01X353500Y589800D02*
X354934Y588366D01*
X356798D01*
G01X324642Y552000D02*
X321123D01*
G01X300982Y542010D02*
Y537049D01*
G01X294289Y542010D02*
Y537049D01*
G01X307675Y548200D02*
Y542010D01*
G01X297636Y561700D02*
Y562428D01*
X297635Y562429D01*
Y568749D01*
G01X304329Y561700D02*
Y561723D01*
X304328Y561724D01*
Y568749D01*
G01X294289Y579810D02*
Y574849D01*
G01X312372Y552000D02*
X308100D01*
G01X353500D02*
X354611Y553111D01*
X357539D01*
G01X304329Y561700D02*
Y553665D01*
G01D02*
X304278Y553614D01*
G01X337642Y589800D02*
X334292D01*
G01X321192D02*
X324642D01*
G01X297636Y599500D02*
Y600228D01*
X297635Y600229D01*
Y606549D01*
G01X304329Y599523D02*
X304328Y599524D01*
Y606549D01*
G01X307675Y617610D02*
Y611600D01*
G01X300982Y617610D02*
Y612249D01*
G01X294289Y617610D02*
Y612249D01*
G01X327754Y607292D02*
X328528D01*
X331100Y609864D01*
G01X357492Y14314D02*
Y11714D01*
G01X360792Y13078D02*
X359428Y11714D01*
X357492D01*
G01X378292Y13078D02*
Y9920D01*
X375792Y7420D01*
Y6500D01*
G01X367911Y-9786D02*
Y-1858D01*
G01X357762Y52333D02*
Y49659D01*
G01X380892Y97000D02*
X384492D01*
X386292Y98800D01*
G01X401375Y518157D02*
X401376Y518158D01*
Y523900D01*
G01X411415D02*
Y520823D01*
X410592Y520000D01*
Y516187D01*
X411415Y515364D01*
G01X367911Y523900D02*
Y529057D01*
G01X404700Y552000D02*
X408184D01*
G01X356798Y588366D02*
Y590939D01*
G01X361192Y552000D02*
X360081Y553111D01*
X357539D01*
G01X367692Y536200D02*
X367911Y536419D01*
Y542010D01*
G01X367692Y547914D02*
X367911Y547695D01*
G01X357672Y547914D02*
X357872Y547714D01*
G01X367911Y579810D02*
Y575319D01*
G01Y547695D02*
Y542010D01*
G01Y575319D02*
X367334Y574742D01*
X367192D01*
G01X404700Y589800D02*
X408184D01*
G01X360292D02*
X359153Y590939D01*
X356798D01*
G01X378292Y589678D02*
Y591562D01*
X376204Y593650D01*
G01X401375Y607292D02*
X398803Y609864D01*
X398029D01*
G01X471651Y22923D02*
Y18933D01*
X469832Y17114D01*
G01X454919Y22923D02*
Y29563D01*
X454533Y29949D01*
G01X478344Y22923D02*
Y14814D01*
G01X471651Y22923D02*
X471650Y22924D01*
Y26131D01*
X469845Y27936D01*
G01X478344Y29949D02*
Y22923D01*
G01X460912Y14814D02*
X461612Y15514D01*
Y22923D01*
G01X454919Y-14877D02*
Y-8237D01*
X454533Y-7851D01*
G01X458266Y3233D02*
Y-1751D01*
G01X458116Y9114D02*
X458266Y8964D01*
Y3233D01*
G01X474998Y-1751D02*
Y3233D01*
G01X464732Y9098D02*
X464958Y8872D01*
Y3233D01*
G01X471651Y-14877D02*
X471650Y-14876D01*
Y-11669D01*
X469845Y-9864D01*
G01X478344Y-7851D02*
Y-14877D01*
G01X448226Y28100D02*
Y22923D01*
G01X451573Y9114D02*
Y3233D01*
G01D02*
Y-1801D01*
G01X448226Y-14877D02*
Y-7662D01*
X447744Y-7180D01*
G01X474998Y9114D02*
Y3233D01*
G01X454919Y22923D02*
Y15064D01*
X454569Y14714D01*
G01X448226Y22923D02*
Y17666D01*
X448892Y17000D01*
G01X448226Y11100D02*
Y3233D01*
G01X458266Y78833D02*
Y84564D01*
X458116Y84714D01*
G01X458266Y73849D02*
Y78833D01*
G01X474998D02*
Y73849D01*
G01Y84714D02*
Y78833D01*
G01Y41033D02*
Y46914D01*
G01X454533Y67749D02*
X454919Y67363D01*
Y60723D01*
G01X478344D02*
Y52614D01*
G01X464732Y46898D02*
X464958Y46672D01*
Y41033D01*
G01X474998Y36049D02*
Y41033D01*
G01X458266D02*
Y36049D01*
G01X461612Y60723D02*
Y53314D01*
X460912Y52614D01*
G01X458116Y46914D02*
X458266Y46764D01*
Y41033D01*
G01X469845Y65736D02*
X471650Y63931D01*
Y60724D01*
X471651Y60723D01*
G01X478344Y67749D02*
Y60723D01*
G01X451573Y73799D02*
Y78833D01*
G01D02*
Y84714D01*
G01X448226Y78833D02*
Y84912D01*
X448610Y85296D01*
G01X430150Y51000D02*
X433508D01*
G01X417150D02*
X421368D01*
G01X451573Y46900D02*
Y41033D01*
G01D02*
Y35999D01*
G01X464732Y84698D02*
X464958Y84472D01*
Y78833D01*
G01X469832Y54914D02*
X471651Y56733D01*
Y60723D01*
G01X448226Y41033D02*
Y35949D01*
X448414Y35761D01*
G01X469792Y47100D02*
X474812D01*
X474998Y46914D01*
G01X464692Y54700D02*
X469618D01*
X469832Y54914D01*
G01X448226Y60723D02*
Y67689D01*
G01Y78833D02*
Y73962D01*
G01X448517Y46975D02*
X448226Y46684D01*
G01X448973Y54883D02*
X448226Y55630D01*
G01X454919Y60723D02*
Y55950D01*
X454569Y55600D01*
G01X448226Y67689D02*
X448627Y68090D01*
G01X448226Y73962D02*
X448599Y73589D01*
G01X448226Y46684D02*
Y41033D01*
G01Y55630D02*
Y60723D01*
G01X454569Y55600D02*
Y52514D01*
G01X472163Y399496D02*
X471033Y401447D01*
G01X451883Y399496D02*
X450753Y397547D01*
G01X468783Y405347D02*
X467653Y407296D01*
G01X448503Y405347D02*
X447091Y407782D01*
G01X471650Y527131D02*
X469845Y528936D01*
G01X454919Y523900D02*
Y530563D01*
X454533Y530949D01*
G01X448226Y523900D02*
Y530972D01*
G01X434840Y523900D02*
Y518157D01*
G01X441533Y518057D02*
Y523900D01*
G01D02*
Y523923D01*
G01X428147Y518157D02*
Y523900D01*
G01X451573Y574799D02*
Y579810D01*
G01D02*
Y579833D01*
G01X474998Y542010D02*
Y537049D01*
G01X458266Y542010D02*
Y537049D01*
G01X448226Y542033D02*
Y542010D01*
G01X417150Y552000D02*
X421368D01*
G01X430150D02*
X433508D01*
G01X451573Y536999D02*
Y542010D01*
G01D02*
Y542033D01*
G01X454919Y561700D02*
Y568363D01*
X454533Y568749D01*
G01X458266Y579810D02*
Y574849D01*
G01X471651Y561700D02*
Y561723D01*
X471650Y561724D01*
Y564931D01*
X469845Y566736D01*
G01X474998Y579810D02*
Y574849D01*
G01X478344Y561700D02*
Y568749D01*
G01X448226Y579833D02*
Y579810D01*
G01X448291Y574773D02*
X448226Y574838D01*
Y579810D01*
G01Y561723D02*
Y569200D01*
G01Y542010D02*
Y536929D01*
G01X448692Y553100D02*
X447592Y552000D01*
G01X448226Y530972D02*
X448410Y531156D01*
G01X448226Y536929D02*
X448432Y536723D01*
G01X447592Y552000D02*
X442508D01*
G01X454919Y599500D02*
Y606163D01*
X454533Y606549D01*
G01X478344Y599500D02*
Y606549D01*
G01X471651Y599500D02*
Y599523D01*
X471650Y599524D01*
Y602731D01*
X469845Y604536D01*
G01X430150Y589800D02*
X433500D01*
G01X417150D02*
X420634D01*
G01X447744Y607220D02*
X448226Y606738D01*
Y599523D01*
G01X474998Y617610D02*
Y612649D01*
G01X451573Y617610D02*
Y612599D01*
G01X458266Y617610D02*
Y612649D01*
G01X448692Y590900D02*
X445692D01*
G01D02*
X444592Y589800D01*
X442508D01*
G01X418108Y609864D02*
Y604499D01*
G01X441533Y612557D02*
Y607292D01*
G01X434840D02*
X432268Y609864D01*
X431494D01*
G01X428147Y607292D02*
X425575Y609864D01*
X424801D01*
G01X448226Y617610D02*
Y613119D01*
X447766Y612659D01*
G01X515155Y14814D02*
Y22923D01*
G01D02*
Y29949D01*
G01X521848D02*
Y22923D01*
G01X534534Y14814D02*
X535234Y15514D01*
Y22923D01*
G01X528191Y14714D02*
X528541Y15064D01*
Y22923D01*
G01D02*
Y29563D01*
X528155Y29949D01*
G01X521848Y22923D02*
Y14814D01*
G01X538581Y3233D02*
Y8872D01*
X538355Y9098D01*
G01X515155Y-7851D02*
Y-14877D01*
G01X518502Y9114D02*
Y3233D01*
G01D02*
Y-1751D01*
G01X521848Y-14877D02*
Y-7851D01*
G01X531888Y-1751D02*
Y3233D01*
G01X525195Y-1801D02*
Y3233D01*
G01D02*
Y9114D01*
G01X531888Y3233D02*
Y8964D01*
X531738Y9114D01*
G01X528541Y-14877D02*
Y-8237D01*
X528155Y-7851D01*
G01X508462Y22923D02*
Y18932D01*
X506644Y17114D01*
G01X497723Y14814D02*
X498423Y15514D01*
Y22923D01*
G01X485037Y14814D02*
Y22923D01*
G01X491380Y14714D02*
X491730Y15064D01*
Y22923D01*
G01X485037D02*
Y29949D01*
G01X491730Y22923D02*
Y29563D01*
X491344Y29949D01*
G01X508462Y22923D02*
Y26131D01*
X506657Y27936D01*
G01X511809Y3233D02*
Y9114D01*
G01Y-1751D02*
Y3233D01*
G01X501544Y9098D02*
X501770Y8872D01*
Y3233D01*
G01X488384Y9114D02*
Y3233D01*
G01X481691Y9114D02*
Y3233D01*
G01X494927Y9114D02*
X495077Y8964D01*
Y3233D01*
G01X481691D02*
Y-1751D01*
G01X488384Y3233D02*
Y-1801D01*
G01X495077Y3233D02*
Y-1751D01*
G01X508462Y-14877D02*
Y-11669D01*
X506657Y-9864D01*
G01X485037Y-14877D02*
Y-7851D01*
G01X491730Y-14877D02*
Y-8237D01*
X491344Y-7851D01*
G01X538581Y78833D02*
Y84472D01*
X538355Y84698D01*
G01X518502Y78833D02*
Y84714D01*
G01Y73849D02*
Y78833D01*
G01X525195Y73799D02*
Y78833D01*
G01X531888Y73849D02*
Y78833D01*
G01X525195D02*
Y84714D01*
G01X531888Y78833D02*
Y84564D01*
X531738Y84714D01*
G01X515155Y67749D02*
Y60723D01*
G01D02*
Y52614D01*
G01X525195Y41033D02*
Y46914D01*
G01X528541Y60723D02*
Y67363D01*
X528155Y67749D01*
G01X531888Y36049D02*
Y41033D01*
G01X538581D02*
Y46672D01*
X538355Y46898D01*
G01X535234Y60723D02*
Y53314D01*
X534534Y52614D01*
G01X525195Y35999D02*
Y41033D01*
G01X521848Y60723D02*
Y67749D01*
G01X518502Y41033D02*
Y36049D01*
G01X521848Y52614D02*
Y60723D01*
G01X531888Y41033D02*
Y46764D01*
X531738Y46914D01*
G01X481691Y73849D02*
Y78833D01*
G01X488384Y73799D02*
Y78833D01*
G01X481691D02*
Y84714D01*
G01X488384Y78833D02*
Y84714D01*
G01X495077Y78833D02*
Y84564D01*
X494927Y84714D01*
G01X495077Y73849D02*
Y78833D01*
G01X511809Y73849D02*
Y78833D01*
G01D02*
Y84714D01*
G01Y41033D02*
Y46914D01*
G01X508462Y60723D02*
Y63931D01*
X506657Y65736D01*
G01X481691Y41033D02*
Y46914D01*
G01X488384Y41033D02*
Y46914D01*
G01X485037Y60723D02*
Y52614D01*
G01X498423Y60723D02*
Y53314D01*
X497723Y52614D01*
G01X488384Y35999D02*
Y41033D01*
G01X501544Y46898D02*
X501770Y46672D01*
Y41033D01*
G01X495077Y36049D02*
Y41033D01*
G01X481691Y36049D02*
Y41033D01*
G01X511809Y36049D02*
Y41033D01*
G01X485037Y67749D02*
Y60723D01*
G01X491730D02*
Y67363D01*
X491344Y67749D01*
G01X491730Y60723D02*
Y54062D01*
X494927Y50865D01*
Y46914D01*
G01X508462Y60723D02*
Y56732D01*
X506644Y54914D01*
G01X531738Y46914D02*
Y51154D01*
X528541Y54351D01*
Y60723D01*
G01X501544Y84698D02*
X501770Y84472D01*
Y78833D01*
G01X494927Y46914D02*
X495077Y46764D01*
Y41033D01*
G01X512722Y294196D02*
X514972D01*
G01X538750Y406200D02*
Y406150D01*
X539761Y405139D01*
Y403396D01*
G01X536381Y405347D02*
X537847D01*
X538700Y406200D01*
X538750D01*
G01X521848Y523900D02*
Y530949D01*
G01X528541Y523900D02*
Y530563D01*
X528155Y530949D01*
G01X515155Y523900D02*
Y530949D01*
G01X491730Y523900D02*
Y530563D01*
X491344Y530949D01*
G01X485037Y523900D02*
Y530949D01*
G01X508462Y523900D02*
Y527131D01*
X506657Y528936D01*
G01X518502Y542010D02*
Y537049D01*
G01X531888Y542010D02*
Y537049D01*
G01X525195Y542010D02*
Y536999D01*
G01X511809Y542010D02*
Y537049D01*
G01X481691Y542010D02*
Y537049D01*
G01X488384Y542010D02*
Y536999D01*
G01X495077Y542010D02*
Y537049D01*
G01X531888Y579810D02*
Y574849D01*
G01X528541Y561700D02*
Y568363D01*
X528155Y568749D01*
G01X525195Y579810D02*
Y574799D01*
G01X521848Y561700D02*
Y568749D01*
G01X518502Y579810D02*
Y574849D01*
G01X515155Y561700D02*
Y568749D01*
G01X495077Y579810D02*
Y574849D01*
G01X488384Y579810D02*
Y574799D01*
G01X491730Y561700D02*
Y568363D01*
X491344Y568749D01*
G01X511809Y579810D02*
Y574849D01*
G01X508462Y561700D02*
Y564931D01*
X506657Y566736D01*
G01X481691Y579810D02*
Y574849D01*
G01X485037Y561700D02*
Y568749D01*
G01X515155Y599500D02*
Y606549D01*
G01X521848Y599500D02*
Y606549D01*
G01X528541Y599500D02*
Y606163D01*
X528155Y606549D01*
G01X491730Y599500D02*
Y606163D01*
X491344Y606549D01*
G01X485037Y599500D02*
Y607230D01*
G01X508462Y599500D02*
Y602731D01*
X506657Y604536D01*
G01X511809Y617610D02*
Y612649D01*
G01X495077Y617610D02*
Y612649D01*
G01X481691Y617610D02*
Y613171D01*
X480950Y612430D01*
G01X488384Y617610D02*
Y612599D01*
G01X518502Y617610D02*
Y612649D01*
G01X525195Y617610D02*
Y612599D01*
G01X531888Y617610D02*
Y612649D01*
G01X575166Y9098D02*
X575392Y8872D01*
Y3233D01*
G01X582084Y-14877D02*
Y-11669D01*
X580279Y-9864D01*
G01X585431Y9114D02*
Y3233D01*
G01X592124Y9114D02*
Y3233D01*
G01X580279Y27936D02*
X582084Y26131D01*
Y22923D01*
G01D02*
Y18932D01*
X580266Y17114D01*
G01X595470Y14814D02*
Y22923D01*
G01X598817D02*
Y27899D01*
G01X595470Y22923D02*
Y29949D01*
G01X588777D02*
Y22923D01*
G01D02*
Y14814D01*
G01X598817Y3233D02*
Y9157D01*
G01X585431Y3233D02*
Y-1751D01*
G01X598817D02*
Y3233D01*
G01X592124D02*
Y-1751D01*
G01X598817Y-14877D02*
Y-9901D01*
G01X595470Y-14877D02*
Y-7851D01*
G01X588777Y-14877D02*
Y-7851D01*
G01X545273Y22923D02*
Y26131D01*
X543468Y27936D01*
G01X571345Y14814D02*
X572045Y15514D01*
Y22923D01*
G01X565352D02*
Y29563D01*
X564966Y29949D01*
G01X551966Y22923D02*
Y14814D01*
G01X558659Y22923D02*
Y14814D01*
G01X564992Y14714D02*
X565352Y15074D01*
Y22923D01*
G01X551966Y29949D02*
Y22923D01*
G01X558659Y29949D02*
Y22923D01*
G01X551966Y-7851D02*
Y-14877D01*
G01X545273D02*
Y-11669D01*
X543468Y-9864D01*
G01X555313Y-1751D02*
Y3233D01*
G01X548620Y-1751D02*
Y3233D01*
G01X568699Y-1751D02*
Y3233D01*
G01D02*
Y8964D01*
X568549Y9114D01*
G01X548620Y3233D02*
Y9114D01*
G01X555313Y3233D02*
Y9114D01*
G01X562006D02*
Y3233D01*
G01D02*
Y-1801D01*
G01X558659Y-14877D02*
Y-7851D01*
G01X565352Y-14877D02*
Y-8237D01*
X564966Y-7851D01*
G01X598817Y9157D02*
Y12817D01*
X599000Y13000D01*
G01X543455Y17114D02*
X545273Y18932D01*
Y22923D01*
G01X575392Y78833D02*
Y84472D01*
X575166Y84698D01*
G01X598817Y78833D02*
Y84757D01*
G01X592124Y78833D02*
Y84714D01*
G01X585431Y73849D02*
Y78833D01*
G01X598817Y73849D02*
Y78833D01*
G01X592124Y73849D02*
Y78833D01*
G01X575392Y41033D02*
Y46672D01*
X575166Y46898D01*
G01X598817Y41033D02*
Y46957D01*
G01X580279Y65736D02*
X582084Y63931D01*
Y60723D01*
G01D02*
Y56732D01*
X580266Y54914D01*
G01X588777Y60723D02*
Y67749D01*
G01X598817Y60723D02*
Y65699D01*
G01X595470Y60723D02*
Y67749D01*
G01X598817Y36049D02*
Y41033D01*
G01X592124Y46914D02*
Y41033D01*
G01X595470Y52614D02*
Y60723D01*
G01X592124Y41033D02*
Y36049D01*
G01X585431Y41033D02*
Y36049D01*
G01X588777Y52614D02*
Y60723D01*
G01X585431Y46914D02*
Y41033D01*
G01X555313Y78833D02*
Y84714D01*
G01X562006Y78833D02*
Y84714D01*
G01X568699Y78833D02*
Y84564D01*
X568549Y84714D01*
G01X568699Y73849D02*
Y78833D01*
G01X555313Y73849D02*
Y78833D01*
G01X562006Y73799D02*
Y78833D01*
G01X548620Y73849D02*
Y78833D01*
G01X545273Y60723D02*
Y56732D01*
X543455Y54914D01*
G01X545273Y60723D02*
Y63931D01*
X543468Y65736D01*
G01X571345Y52614D02*
X572045Y53314D01*
Y60723D01*
G01X551966D02*
Y67749D01*
G01X565352Y60723D02*
Y67363D01*
X564966Y67749D01*
G01X558659D02*
Y60723D01*
G01X565352Y52864D02*
Y60723D01*
G01X568549Y46914D02*
X568699Y46764D01*
Y41033D01*
G01X555313D02*
Y36049D01*
G01X562006Y41033D02*
Y35999D01*
G01X568699Y41033D02*
Y36049D01*
G01X558659Y60723D02*
Y52614D01*
G01X551966D02*
Y60723D01*
G01X548620Y36049D02*
Y41033D01*
G01X562006Y46914D02*
Y41033D01*
G01X555313Y46914D02*
Y41033D01*
G01X598817Y84757D02*
X598950Y84890D01*
Y89550D01*
G01X585431Y84714D02*
Y78833D01*
G01X598817Y46957D02*
X599000Y47140D01*
Y51000D01*
G01X548620Y84714D02*
Y78833D01*
G01Y46914D02*
Y41033D01*
G01X546521Y395597D02*
Y396416D01*
X545391Y397546D01*
G01X543141D02*
Y401447D01*
G01X545391Y397546D02*
X543141D01*
G01X588777Y523900D02*
Y530949D01*
G01X595470Y523900D02*
Y530949D01*
G01X598817Y523900D02*
Y528899D01*
G01X582084Y523900D02*
Y527131D01*
X580279Y528936D01*
G01X598900Y513200D02*
Y510240D01*
X598817Y510157D01*
G01X565352Y523900D02*
Y530563D01*
X564966Y530949D01*
G01X558659Y523900D02*
Y530949D01*
G01X551966Y523900D02*
Y530949D01*
G01X545273Y523900D02*
Y527131D01*
X543468Y528936D01*
G01X598817Y547957D02*
Y551183D01*
X598800Y551200D01*
G01X592124Y542010D02*
Y537049D01*
G01X585431Y542010D02*
Y537049D01*
G01X598817Y542010D02*
Y537049D01*
G01Y585757D02*
Y588983D01*
X598800Y589000D01*
G01X555313Y542010D02*
Y537049D01*
G01X568699Y542010D02*
Y537049D01*
G01X562006Y542010D02*
Y536999D01*
G01X548620Y542010D02*
Y537049D01*
G01X592124Y579810D02*
Y574849D01*
G01X588777Y561700D02*
Y568749D01*
G01X595470Y561700D02*
Y568749D01*
G01X598817Y561700D02*
Y566699D01*
G01Y579810D02*
Y574849D01*
G01X585431Y579810D02*
Y574849D01*
G01X582084Y561700D02*
Y564931D01*
X580279Y566736D01*
G01X545273Y561700D02*
Y564931D01*
X543468Y566736D01*
G01X548620Y579810D02*
Y574849D01*
G01X551966Y561700D02*
Y568749D01*
G01X568699Y579810D02*
Y574849D01*
G01X558659Y561700D02*
Y568749D01*
G01X555313Y579810D02*
Y574849D01*
G01X562006Y579810D02*
Y574799D01*
G01X565352Y561700D02*
Y568363D01*
X564966Y568749D01*
G01X582084Y599500D02*
Y602731D01*
X580279Y604536D01*
G01X598817Y599500D02*
Y604499D01*
G01X588777Y599500D02*
Y606549D01*
G01X595470Y599500D02*
Y606549D01*
G01X565352Y599500D02*
Y606163D01*
X564966Y606549D01*
G01X558659Y599500D02*
Y606549D01*
G01X551966Y599500D02*
Y606549D01*
G01X545273Y599500D02*
Y602731D01*
X543468Y604536D01*
G01X568699Y617610D02*
Y612649D01*
G01X562006Y617610D02*
Y612599D01*
G01X555313Y617610D02*
Y612649D01*
G01X548620Y617610D02*
Y612649D01*
G01X598817Y617610D02*
Y612649D01*
G01X592124Y617610D02*
Y612649D01*
G01X585431Y617610D02*
Y612649D01*
G01X602163Y-14877D02*
Y-9901D01*
G01X616500Y13000D02*
X616578Y13078D01*
X620092D01*
G01X657250Y-2050D02*
Y3070D01*
G01Y-14930D02*
Y-16250D01*
X658500Y-17500D01*
X660000D01*
G01X616150Y89550D02*
X619220D01*
X620092Y88678D01*
G01X602163Y60723D02*
Y65699D01*
G01X616900Y51000D02*
X619948D01*
X620070Y50878D01*
G01X647500Y291000D02*
X646278D01*
X645128Y292150D01*
X644800D01*
G01X651000Y291000D02*
X647500D01*
G01X602163Y523900D02*
Y528899D01*
G01X615900Y513200D02*
X617892D01*
X619392Y514700D01*
G01X618500Y551200D02*
Y555408D01*
X618892Y555800D01*
G01X618192Y593600D02*
Y589192D01*
X618000Y589000D01*
G01X602163Y542033D02*
Y542010D01*
G01D02*
Y537057D01*
G01Y599500D02*
Y604499D01*
G01Y593599D02*
Y599500D01*
G01X704500Y26300D02*
Y28700D01*
G01X715937Y20952D02*
Y21496D01*
X717720Y23279D01*
G01X726500Y20250D02*
X722000D01*
G01X670430Y29253D02*
X671777Y30600D01*
X672900D01*
G01X683800Y24856D02*
X684544D01*
X684950Y24450D01*
X686700D01*
G01X689900Y20800D02*
X689200Y21500D01*
X687400D01*
G01X708000Y26600D02*
X708500Y27100D01*
Y29000D01*
G01X681472Y40376D02*
Y46572D01*
X685000Y50100D01*
G01X687500Y254470D02*
Y251307D01*
G01X707653Y226347D02*
X709000Y227694D01*
Y229000D01*
G01X688250Y264000D02*
X690660D01*
G01X687520Y257570D02*
Y254490D01*
X687500Y254470D01*
G01X688250Y271000D02*
X690380D01*
X690704Y271324D01*
G01X688250Y267500D02*
X690069D01*
X690939Y266630D01*
G01X689540Y251400D02*
X690380Y252240D01*
G01X707500Y252500D02*
X711000D01*
G01X704500D02*
X707500D01*
G01X714000D02*
X711000D01*
G01X687550Y278000D02*
X689510D01*
X690130Y277380D01*
G01X704450Y226600D02*
Y227950D01*
X705500Y229000D01*
G01X709550Y297975D02*
Y301275D01*
G01X704500Y293800D02*
Y295474D01*
X707001Y297975D01*
X709550D01*
G01X717300Y300700D02*
Y297500D01*
G01X718200Y295000D02*
X717300Y295900D01*
Y297500D01*
G01X715575Y304375D02*
X713050D01*
G01X713970Y308360D02*
X711160D01*
X709550Y306750D01*
Y304375D01*
G01X704500Y515250D02*
Y512850D01*
G01X708500Y515250D02*
Y512500D01*
G01X689500Y555750D02*
X694000D01*
G01X698580Y561630D02*
X694000Y557050D01*
Y555750D01*
G01X773500Y13078D02*
X775136Y14714D01*
X776224D01*
G01X786616Y3233D02*
X786614D01*
G01X779771Y9114D02*
X779921Y8964D01*
Y3233D01*
G01X779923D02*
X779921D01*
G01X769883Y22923D02*
X769881D01*
G01Y27899D02*
Y22923D01*
G01X773230Y3233D02*
X773228D01*
G01Y-1801D02*
Y3233D01*
G01X776576Y-14877D02*
X776574D01*
Y-8237D01*
X776188Y-7851D01*
G01X769883Y-14877D02*
X769881D01*
Y-9901D01*
G01X776576Y22923D02*
X776574D01*
G01X755500Y11250D02*
Y8700D01*
G01X776224Y14714D02*
X776574Y15064D01*
Y22923D01*
G01X769881Y16839D02*
X769721Y16999D01*
X768249D01*
X766000Y14750D01*
G01X786388Y9098D02*
X786614Y8872D01*
Y3233D01*
G01X726250Y23550D02*
X726500Y23300D01*
Y20250D01*
G01X779921Y3233D02*
Y-1751D01*
G01X769881Y22923D02*
Y16839D01*
G01X773228Y3233D02*
Y9114D01*
G01X776574Y22923D02*
Y29563D01*
X776188Y29949D01*
G01X786614Y3233D02*
Y-687D01*
X786388Y-913D01*
Y-1801D01*
G01X764100Y17100D02*
X762500Y15500D01*
Y14750D01*
G01X759000D02*
Y16200D01*
X760100Y17300D01*
Y17255D01*
G01X759000Y14750D02*
X755500D01*
G01X766000Y11250D02*
X762500D01*
G01D02*
X759000D01*
G01X770000Y13078D02*
X769178D01*
X767350Y11250D01*
X766000D01*
G01X779771Y46914D02*
X779921Y46764D01*
Y41033D01*
G01X779923D02*
X779921D01*
G01X773230Y78833D02*
X773228D01*
G01Y73799D02*
Y78833D01*
G01X779923D02*
X779921D01*
G01X779771Y84714D02*
X779921Y84564D01*
Y78833D01*
G01X786616D02*
X786614D01*
G01X786388Y73799D02*
Y74687D01*
X786614Y74913D01*
Y78833D01*
G01X769883Y60723D02*
X769881D01*
G01Y66000D02*
Y60723D01*
G01X786616Y41033D02*
X786614D01*
G01X786388Y35999D02*
Y36887D01*
X786614Y37113D01*
Y41033D01*
G01X776576Y60723D02*
X776574D01*
G01X776188Y67749D02*
X776574Y67363D01*
Y60723D01*
G01X773228Y35983D02*
Y41033D01*
G01X755500Y88611D02*
Y84361D01*
G01Y49250D02*
Y46700D01*
G01X769881Y54839D02*
X768089D01*
X766000Y52750D01*
G01X773228Y46914D02*
Y41033D01*
G01X779921D02*
Y35983D01*
G01X773228Y78833D02*
Y84714D01*
G01X779921Y78833D02*
Y73849D01*
G01X786614Y78833D02*
Y84472D01*
X786388Y84698D01*
G01X769881Y60723D02*
Y54839D01*
G01X786614Y41033D02*
Y46672D01*
X786388Y46898D01*
G01X776574Y60723D02*
Y52864D01*
X776224Y52514D01*
G01X773228Y41033D02*
X773230D01*
G01X759000Y92111D02*
X755500D01*
G01D02*
X753100D01*
G01X762500D02*
Y92199D01*
X761650Y93049D01*
Y94550D01*
G01X762500Y52750D02*
Y53500D01*
X764100Y55100D01*
G01X759000Y88611D02*
X762500D01*
G01D02*
X766000D01*
G01D02*
X769611D01*
X770000Y89000D01*
G01X759000Y52750D02*
X755500D01*
G01D02*
Y55200D01*
G01X766000Y49250D02*
X762500D01*
G01D02*
X759000D01*
G01X770000Y50878D02*
X768372Y49250D01*
X766000D01*
G01X774582Y212033D02*
X773882D01*
X772732Y210883D01*
Y209533D01*
G01X770200Y208600D02*
X768670Y207070D01*
X766947D01*
G01D02*
X765330D01*
X762300Y210100D01*
Y213100D01*
G01X777182Y212033D02*
Y210483D01*
X776232Y209533D01*
G01X772732Y337533D02*
Y338983D01*
X773732Y339983D01*
X774347D01*
G01X768367Y337062D02*
X772261D01*
X772732Y337533D01*
G01X776232D02*
X777182Y338483D01*
Y340033D01*
G01X734200Y301150D02*
X736000Y302950D01*
Y303400D01*
G01X769883Y523900D02*
X769881Y523923D01*
Y529137D01*
X769818Y529200D01*
G01X776576Y523900D02*
X776574Y523923D01*
Y530563D01*
X776188Y530949D01*
G01X773400Y512800D02*
Y510286D01*
X773228Y510114D01*
G01X769900Y512800D02*
Y510500D01*
X769500Y510100D01*
G01X779771Y547914D02*
X779921Y547764D01*
Y542010D01*
G01X779923D02*
X779921D01*
G01X779771Y585714D02*
X779921Y585564D01*
Y579810D01*
G01X779923D02*
X779921D01*
G01X769883Y561700D02*
X769881Y561723D01*
Y566719D01*
X769700Y566900D01*
G01X776576Y561700D02*
X776574Y561723D01*
Y568363D01*
X776188Y568749D01*
G01X786616Y579810D02*
X786614D01*
Y575913D01*
X786388Y575687D01*
Y574799D01*
G01X773230Y579810D02*
X773228D01*
G01Y574799D02*
Y579810D01*
G01X786616Y542010D02*
X786614D01*
Y538113D01*
X786388Y537887D01*
Y536999D01*
G01X773230Y542010D02*
X773228D01*
G01Y547914D02*
Y542010D01*
G01Y585714D02*
X773300Y585786D01*
Y589200D01*
G01X773228Y547914D02*
X773100Y548042D01*
Y551400D01*
G01X779921Y542010D02*
Y537049D01*
G01Y579810D02*
Y574849D01*
G01X773228Y579810D02*
Y585714D01*
G01Y542010D02*
Y536999D01*
G01X769883Y542010D02*
X769881D01*
Y537364D01*
X769500Y536983D01*
G01X769600Y551400D02*
Y548000D01*
X769500Y547900D01*
G01X769883Y579810D02*
X769881D01*
Y575081D01*
X769500Y574700D01*
G01X769800Y589200D02*
Y586000D01*
X769500Y585700D01*
G01X769883Y599500D02*
X769881Y599523D01*
Y604719D01*
X769700Y604900D01*
G01X776576Y599500D02*
X776574Y599523D01*
Y606163D01*
X776188Y606549D01*
G01X779923Y617610D02*
X779921D01*
Y612649D01*
G01X773230Y617610D02*
X773228D01*
Y612599D01*
G01X786616Y617610D02*
X786614D01*
Y613713D01*
X786388Y613487D01*
Y612599D01*
G01X769883Y617610D02*
X769881D01*
Y612964D01*
X769500Y612583D01*
G01X800002Y22923D02*
X800000D01*
G01X843506D02*
Y29946D01*
X843503Y29949D01*
G01X843506Y22923D02*
Y14817D01*
X843503Y14814D01*
G01X836813Y22923D02*
X836811D01*
G01X836810Y14814D02*
X836811Y14815D01*
Y22923D01*
G01X830120D02*
X830118D01*
G01X828299Y17114D02*
X830118Y18933D01*
Y22923D01*
G01X836813Y-14877D02*
X836811D01*
Y-14172D01*
X836810Y-14171D01*
Y-7851D01*
G01X843506Y-14877D02*
Y-7854D01*
X843503Y-7851D01*
G01X830120Y-14877D02*
Y-11672D01*
X828312Y-9864D01*
G01X846852Y3233D02*
X846850D01*
G01Y-1801D02*
Y3233D01*
G01X833466D02*
X833464D01*
G01Y9114D02*
Y3233D01*
G01X840159D02*
X840157D01*
G01Y-1751D02*
Y3233D01*
G01X823427D02*
X823425D01*
G01X823199Y9098D02*
X823425Y8872D01*
Y3233D01*
G01X816734D02*
X816732D01*
G01X816582Y9114D02*
X816732Y8964D01*
Y3233D01*
G01X813387Y22923D02*
X813385D01*
G01X813035Y14714D02*
X813385Y15064D01*
Y22923D01*
G01X793309D02*
Y26128D01*
X791501Y27936D01*
G01X806694Y22923D02*
X806692D01*
G01Y14814D02*
Y22923D01*
G01X806694Y-14877D02*
X806692D01*
Y-7851D01*
G01X800002Y-14877D02*
X800000D01*
Y-14172D01*
X799999Y-14171D01*
Y-7851D01*
G01X793309Y-14877D02*
Y-11672D01*
X791501Y-9864D01*
G01X813387Y-14877D02*
X813385D01*
Y-8237D01*
X812999Y-7851D01*
G01X803348Y3233D02*
X803346D01*
G01Y-1751D02*
Y3233D01*
G01X810041D02*
X810039D01*
G01Y9114D02*
Y3233D01*
G01X796655D02*
X796653D01*
G01Y-1751D02*
Y3233D01*
G01X791488Y17114D02*
X793309Y18935D01*
Y22923D01*
G01X799999Y14814D02*
X800000Y14815D01*
Y22923D01*
G01X796653Y3233D02*
Y9114D01*
G01X800000Y22923D02*
Y23628D01*
X799999Y23629D01*
Y29949D01*
G01X820078Y22923D02*
Y15514D01*
X819378Y14814D01*
G01X836811Y22923D02*
Y23628D01*
X836810Y23629D01*
Y29949D01*
G01X830118Y22923D02*
X830117Y22924D01*
Y26131D01*
X828312Y27936D01*
G01X846850Y3233D02*
Y9114D01*
G01X833464Y3233D02*
Y-1751D01*
G01X840157Y3233D02*
Y9114D01*
G01X823425Y3233D02*
Y-1375D01*
X823199Y-1601D01*
Y-1801D01*
G01X816732Y3233D02*
Y-1751D01*
G01X813385Y22923D02*
Y29563D01*
X812999Y29949D01*
G01X806692Y22923D02*
Y29949D01*
G01X803346Y3233D02*
Y9114D01*
G01X810039Y3233D02*
Y-1801D01*
G01X803348Y78833D02*
X803346D01*
G01X846852Y41033D02*
X846850D01*
G01X828312Y65736D02*
X830117Y63931D01*
Y60724D01*
X830118Y60723D01*
G01X830120D02*
X830118D01*
G01X846852Y78833D02*
X846850D01*
G01X823427D02*
X823425D01*
G01X823199Y73799D02*
Y73999D01*
X823425Y74225D01*
Y78833D01*
G01X833466D02*
X833464D01*
G01Y73849D02*
Y78833D01*
G01X840159D02*
X840157D01*
G01Y73849D02*
Y78833D01*
G01X846850Y84714D02*
Y78833D01*
G01X816734Y41033D02*
X816732D01*
G01X833466D02*
X833464D01*
G01Y36049D02*
Y41033D01*
G01X843506Y60723D02*
Y67746D01*
X843503Y67749D01*
G01X843506Y60723D02*
Y52617D01*
X843503Y52614D01*
G01X836813Y60723D02*
X836811D01*
G01X836810Y67749D02*
Y61429D01*
X836811Y61428D01*
Y60723D01*
G01X840159Y41033D02*
X840157D01*
G01Y46914D02*
Y41033D01*
G01X823427D02*
X823425D01*
Y36425D01*
X823199Y36199D01*
Y35999D01*
G01X810041Y78833D02*
X810039D01*
G01Y84714D02*
Y78833D01*
G01X816734D02*
X816732D01*
G01X816582Y84714D02*
X816732Y84564D01*
Y78833D01*
G01X796655D02*
X796653D01*
G01Y84714D02*
Y78833D01*
G01X816582Y46914D02*
X816732Y46764D01*
Y41033D01*
G01X793309Y60723D02*
X793307D01*
G01X791501Y65736D02*
X793306Y63931D01*
Y60724D01*
X793307Y60723D01*
G01X810041Y41033D02*
X810039D01*
G01Y35999D02*
Y41033D01*
G01X803348D02*
X803346D01*
G01Y36049D02*
Y41033D01*
G01X813387Y60723D02*
X813385D01*
G01X812999Y67749D02*
X813385Y67363D01*
Y60723D01*
G01X806694D02*
X806692D01*
G01Y67749D02*
Y60723D01*
G01X800002D02*
X800000D01*
G01X799999Y67749D02*
Y61429D01*
X800000Y61428D01*
Y60723D01*
G01X796655Y41033D02*
X796653D01*
G01Y36049D02*
Y41033D01*
G01X803346Y73849D02*
Y78833D01*
G01X846850Y35999D02*
Y41033D01*
G01X796653Y78833D02*
Y73849D01*
G01X793307Y60723D02*
Y56733D01*
X791488Y54914D01*
G01X800000Y60723D02*
Y52615D01*
X799999Y52614D01*
G01X796653Y41033D02*
Y46914D01*
G01X830118Y60723D02*
Y56733D01*
X828299Y54914D01*
G01X823425Y78833D02*
Y84472D01*
X823199Y84698D01*
G01X833464Y78833D02*
Y84714D01*
G01X840157Y78833D02*
Y84714D01*
G01X846850Y78833D02*
Y73799D01*
G01X820078Y60723D02*
Y53314D01*
X819378Y52614D01*
G01X833464Y41033D02*
Y46914D01*
G01X836811Y60723D02*
Y52615D01*
X836810Y52614D01*
G01X840157Y41033D02*
Y36049D01*
G01X810039Y78833D02*
Y73799D01*
G01X816732Y78833D02*
Y73949D01*
X816632Y73849D01*
X816582D01*
G01X816732Y41033D02*
Y36049D01*
G01X810039Y41033D02*
Y46914D01*
G01X803346Y41033D02*
Y46914D01*
G01X813385Y60723D02*
Y52864D01*
X813035Y52514D01*
G01X806692Y60723D02*
Y52614D01*
G01X803346Y78833D02*
Y84714D01*
G01X846850Y41033D02*
Y46914D01*
G01X830120Y523900D02*
X830118Y523923D01*
X830117Y523924D01*
Y527131D01*
X828312Y528936D01*
G01X836813Y523900D02*
X836811Y523923D01*
Y524628D01*
X836810Y524629D01*
Y530949D01*
G01X843506Y523900D02*
X843504Y523923D01*
X843503Y523924D01*
Y530949D01*
G01X806694Y523900D02*
X806692Y523923D01*
Y530949D01*
G01X813387Y523900D02*
X813385Y523923D01*
Y530563D01*
X812999Y530949D01*
G01X793309Y523900D02*
X793307Y523923D01*
X793306Y523924D01*
Y527131D01*
X791501Y528936D01*
G01X800002Y523900D02*
X800000Y523923D01*
Y524628D01*
X799999Y524629D01*
Y530949D01*
G01X803348Y542010D02*
X803346D01*
G01X810041D02*
X810039D01*
G01X810041Y579810D02*
X810039D01*
G01X803348D02*
X803346D01*
G01X846852Y542010D02*
X846850D01*
G01X833466D02*
X833464D01*
G01X833466Y579810D02*
X833464D01*
G01X836813Y561700D02*
X836811Y561723D01*
Y562428D01*
X836810Y562429D01*
Y568749D01*
G01X846852Y579810D02*
X846850D01*
G01Y574799D02*
Y579810D01*
G01X843506Y561700D02*
X843504Y561723D01*
X843503Y561724D01*
Y568749D01*
G01X823427Y579810D02*
X823425D01*
Y575225D01*
X823199Y574999D01*
Y574799D01*
G01X840159Y579810D02*
X840157D01*
G01Y585714D02*
Y579810D01*
G01X830120Y561700D02*
X830118Y561723D01*
X830117Y561724D01*
Y564931D01*
X828312Y566736D01*
G01X840159Y542010D02*
X840157D01*
G01Y537049D02*
Y542010D01*
G01X823427D02*
X823425D01*
Y537425D01*
X823199Y537199D01*
Y536999D01*
G01X796655Y579810D02*
X796653D01*
G01Y585714D02*
Y579810D01*
G01X793309Y561700D02*
X793307Y561723D01*
X793306Y561724D01*
Y564931D01*
X791501Y566736D01*
G01X800002Y561700D02*
X800000Y561723D01*
Y562428D01*
X799999Y562429D01*
Y568749D01*
G01X806694Y561700D02*
X806692Y561723D01*
Y568749D01*
G01X813387Y561700D02*
X813385Y561723D01*
Y568363D01*
X812999Y568749D01*
G01X816734Y579810D02*
X816732D01*
G01X816582Y585714D02*
X816732Y585564D01*
Y579810D01*
G01X796655Y542010D02*
X796653D01*
G01Y537049D02*
Y542010D01*
G01X816734D02*
X816732D01*
G01X816582Y537049D02*
X816632D01*
X816732Y537149D01*
Y542010D01*
G01X803346Y537049D02*
Y542010D01*
G01X810039Y547914D02*
Y542010D01*
G01Y574799D02*
Y579810D01*
G01X803346Y574849D02*
Y579810D01*
G01X833464Y537049D02*
Y542010D01*
G01Y574849D02*
Y579810D01*
G01X846850Y547914D02*
Y542010D01*
G01X796653Y579810D02*
Y574849D01*
G01Y542010D02*
Y547914D01*
G01X846850Y579810D02*
Y585714D01*
G01X840157Y579810D02*
Y574849D01*
G01Y542010D02*
Y547914D01*
G01X816732Y579810D02*
Y574949D01*
X816632Y574849D01*
X816582D01*
G01X816732Y542010D02*
Y547764D01*
X816582Y547914D01*
G01X803346Y542010D02*
Y547914D01*
G01X810039Y542010D02*
Y536999D01*
G01Y579810D02*
Y585714D01*
G01X803346Y579810D02*
Y585714D01*
G01X833464Y542010D02*
Y547914D01*
G01Y579810D02*
Y585714D01*
G01X846850Y542010D02*
Y536999D01*
G01X830120Y599500D02*
X830118Y599523D01*
X830117Y599524D01*
Y602731D01*
X828312Y604536D01*
G01X836813Y599500D02*
X836811Y599523D01*
Y600228D01*
X836810Y600229D01*
Y606549D01*
G01X843506Y599500D02*
X843504Y599523D01*
X843503Y599524D01*
Y606549D01*
G01X806694Y599500D02*
X806692Y599523D01*
Y606549D01*
G01X813387Y599500D02*
X813385Y599523D01*
Y606163D01*
X812999Y606549D01*
G01X793309Y599500D02*
X793307Y599523D01*
X793306Y599524D01*
Y602731D01*
X791501Y604536D01*
G01X800002Y599500D02*
X800000Y599523D01*
Y600228D01*
X799999Y600229D01*
Y606549D01*
G01X816734Y617610D02*
X816732D01*
Y612749D01*
X816632Y612649D01*
X816582D01*
G01X846852Y617610D02*
X846850D01*
Y612599D01*
G01X840159Y617610D02*
X840157D01*
Y612649D01*
G01X833466Y617610D02*
X833464D01*
Y612649D01*
G01X823427Y617610D02*
X823425D01*
Y613025D01*
X823199Y612799D01*
Y612599D01*
G01X810041Y617610D02*
X810039D01*
Y612599D01*
G01X803348Y617610D02*
X803346D01*
Y612649D01*
G01X796655Y617610D02*
X796653D01*
Y612649D01*
G01X903742Y22923D02*
X903740D01*
G01X893702D02*
X893700D01*
G01X893000Y14814D02*
X893700Y15514D01*
Y22923D01*
G01X910435D02*
Y14817D01*
X910432Y14814D01*
G01X910435Y22923D02*
Y29946D01*
X910432Y29949D01*
G01X887009Y22923D02*
X887007D01*
G01X886657Y14714D02*
X887007Y15064D01*
Y22923D01*
G01X880317D02*
X880315D01*
G01X880314Y14814D02*
X880315Y14815D01*
Y22923D01*
G01X901934Y27936D02*
X903739Y26131D01*
Y22924D01*
X903740Y22923D01*
G01X876970Y3233D02*
X876968D01*
G01Y9114D02*
Y3233D01*
G01X887009Y-14877D02*
X887007D01*
Y-8237D01*
X886621Y-7851D01*
G01X880317Y-14877D02*
Y-7854D01*
X880314Y-7851D01*
G01X883663Y3233D02*
X883661D01*
G01Y9114D02*
Y3233D01*
G01X903742Y-14877D02*
Y-11672D01*
X901934Y-9864D01*
G01X896821Y9098D02*
X897047Y8872D01*
Y3233D01*
G01X890356D02*
X890354D01*
G01X890204Y9114D02*
X890354Y8964D01*
Y3233D01*
G01X910435Y-14877D02*
X910433D01*
Y-14172D01*
X910432Y-14171D01*
Y-7851D01*
G01X907088Y3233D02*
X907086D01*
G01Y-1751D02*
Y3233D01*
G01X856891Y22923D02*
X856889D01*
G01X850198D02*
X850196D01*
G01X849846Y14714D02*
X850196Y15064D01*
Y22923D01*
G01X873624D02*
X873622D01*
G01X873621Y14814D02*
X873622Y14815D01*
Y22923D01*
G01X866931D02*
X866929D01*
G01X865110Y17114D02*
X866929Y18933D01*
Y22923D01*
G01X866931Y-14877D02*
Y-11672D01*
X865123Y-9864D01*
G01X870277Y3233D02*
X870275D01*
G01Y9114D02*
Y3233D01*
G01X853545D02*
X853543D01*
G01Y-1751D02*
Y3233D01*
G01X873624Y-14877D02*
X873622D01*
Y-14172D01*
X873621Y-14171D01*
Y-7851D01*
G01X860238Y3233D02*
X860236D01*
G01X860010Y9098D02*
X860236Y8872D01*
Y3233D01*
G01X850198Y-14877D02*
X850196D01*
Y-8237D01*
X849810Y-7851D01*
G01X856889Y22923D02*
Y15514D01*
X856189Y14814D01*
G01X850196Y22923D02*
Y29563D01*
X849810Y29949D01*
G01X853543Y3233D02*
Y8964D01*
X853393Y9114D01*
G01X887007Y22923D02*
Y29563D01*
X886621Y29949D01*
G01X880315Y22923D02*
X880314Y22924D01*
Y29949D01*
G01X903740Y22923D02*
Y18933D01*
X901921Y17114D01*
G01X876968Y3233D02*
Y-1751D01*
G01X883661Y3233D02*
Y-1801D01*
G01X890354Y3233D02*
Y-1751D01*
G01X907086Y3233D02*
Y9114D01*
G01X873622Y22923D02*
Y23628D01*
X873621Y23629D01*
Y29949D01*
G01X866929Y22923D02*
X866928Y22924D01*
Y26131D01*
X865123Y27936D01*
G01X870275Y3233D02*
Y-1751D01*
G01X901897Y9100D02*
X907072D01*
X907086Y9114D01*
G01X853545Y41033D02*
X853543D01*
G01X890356D02*
X890354D01*
G01X876970Y78833D02*
X876968D01*
G01X890356D02*
X890354D01*
G01Y73849D02*
Y78833D01*
G01X883663D02*
X883661D01*
G01Y73799D02*
Y78833D01*
G01X907088D02*
X907086D01*
G01Y73849D02*
Y78833D01*
G01X876970Y41033D02*
X876968D01*
G01Y36049D02*
Y41033D01*
G01X910435Y60723D02*
Y67746D01*
X910432Y67749D01*
G01X896821Y46898D02*
X897047Y46672D01*
Y41033D01*
G01X910435Y60723D02*
Y52617D01*
X910432Y52614D01*
G01X903742Y60723D02*
X903740D01*
G01X901934Y65736D02*
X903739Y63931D01*
Y60724D01*
X903740Y60723D01*
G01X883663Y41033D02*
X883661D01*
G01Y35999D02*
Y41033D01*
G01X887009Y60723D02*
X887007D01*
G01X886621Y67749D02*
X887007Y67363D01*
Y60723D01*
G01X880317D02*
X880315D01*
G01X880314Y67749D02*
Y60724D01*
X880315Y60723D01*
G01X907088Y41033D02*
X907086D01*
G01Y46914D02*
Y41033D01*
G01X853545Y78833D02*
X853543D01*
G01Y73849D02*
Y78833D01*
G01X870277D02*
X870275D01*
G01Y84714D02*
Y78833D01*
G01X873624Y60723D02*
X873622D01*
G01X873621Y67749D02*
Y61429D01*
X873622Y61428D01*
Y60723D01*
G01X870277Y41033D02*
X870275D01*
G01Y36049D02*
Y41033D01*
G01X866931Y60723D02*
X866929D01*
G01X865123Y65736D02*
X866928Y63931D01*
Y60724D01*
X866929Y60723D01*
G01X850198D02*
X850196D01*
G01X849810Y67749D02*
X850196Y67363D01*
Y60723D01*
G01X853543Y36049D02*
Y41033D01*
G01X890204Y46914D02*
X890354Y46764D01*
Y41033D01*
G01X876968Y84714D02*
Y78833D01*
G01X853543D02*
Y84564D01*
X853393Y84714D01*
G01X860236Y78833D02*
Y84472D01*
X860010Y84698D01*
G01X856889Y60723D02*
Y53314D01*
X856189Y52614D01*
G01X850196Y60723D02*
Y52864D01*
X849846Y52514D01*
G01X860236Y41033D02*
Y46672D01*
X860010Y46898D01*
G01X853543Y41033D02*
Y46764D01*
X853393Y46914D01*
G01X890354Y78833D02*
Y84564D01*
X890204Y84714D01*
G01X897047Y78833D02*
Y84472D01*
X896821Y84698D01*
G01X883661Y78833D02*
Y84714D01*
G01X907086Y78833D02*
Y84714D01*
G01X876968Y41033D02*
Y46914D01*
G01X903740Y60723D02*
Y56733D01*
X901921Y54914D01*
G01X893700Y60723D02*
Y53314D01*
X893000Y52614D01*
G01X883661Y41033D02*
Y46914D01*
G01X887007Y60723D02*
Y52864D01*
X886657Y52514D01*
G01X880315Y60723D02*
Y52615D01*
X880314Y52614D01*
G01X907086Y41033D02*
Y36049D01*
G01X870275Y78833D02*
Y73849D01*
G01X873622Y60723D02*
Y52615D01*
X873621Y52614D01*
G01X870275Y41033D02*
Y46914D01*
G01X866929Y60723D02*
Y56733D01*
X865110Y54914D01*
G01X890354Y41033D02*
Y36049D01*
G01X876968Y78833D02*
Y73849D01*
G01X880317Y523900D02*
X880315Y523923D01*
X880314Y523924D01*
Y530949D01*
G01X887009Y523900D02*
X887007Y523923D01*
Y530563D01*
X886621Y530949D01*
G01X903742Y523900D02*
X903740Y523923D01*
X903739Y523924D01*
Y527131D01*
X901934Y528936D01*
G01X910435Y523900D02*
X910433Y523923D01*
Y524628D01*
X910432Y524629D01*
Y530949D01*
G01X873624Y523900D02*
X873622Y523923D01*
Y524628D01*
X873621Y524629D01*
Y530949D01*
G01X866931Y523900D02*
X866929Y523923D01*
X866928Y523924D01*
Y527131D01*
X865123Y528936D01*
G01X850198Y523900D02*
X850196Y523923D01*
Y530563D01*
X849810Y530949D01*
G01X876970Y579810D02*
X876968D01*
Y574849D01*
G01X907086D02*
Y579810D01*
X907088D01*
G01X883663D02*
X883661D01*
Y574799D01*
G01X903742Y561700D02*
X903740Y561723D01*
X903739Y561724D01*
Y564931D01*
X901934Y566736D01*
G01X910435Y561700D02*
X910433Y561723D01*
Y562428D01*
X910432Y562429D01*
Y568749D01*
G01X890354Y574849D02*
Y579810D01*
X890356D01*
G01X880317Y561700D02*
X880315Y561723D01*
X880314Y561724D01*
Y568749D01*
G01X887009Y561700D02*
X887007Y561723D01*
Y568363D01*
X886621Y568749D01*
G01X876970Y542010D02*
X876968D01*
Y537049D01*
G01X883663Y542010D02*
X883661D01*
Y536999D01*
G01X890356Y542010D02*
X890354D01*
Y537049D01*
G01X907088Y542010D02*
X907086D01*
Y537049D01*
G01X866931Y561700D02*
X866929Y561723D01*
X866928Y561724D01*
Y564931D01*
X865123Y566736D01*
G01X870277Y542010D02*
X870275D01*
Y537049D01*
G01X873624Y561700D02*
X873622Y561723D01*
Y562428D01*
X873621Y562429D01*
Y568749D01*
G01X850198Y561700D02*
X850196Y561723D01*
Y568363D01*
X849810Y568749D01*
G01X853545Y579810D02*
X853543D01*
Y574849D01*
G01X870277Y579810D02*
X870275D01*
Y574849D01*
G01X853545Y542010D02*
X853543D01*
Y537049D01*
G01X887009Y599500D02*
X887007Y599523D01*
Y606163D01*
X886621Y606549D01*
G01X910435Y599500D02*
X910433Y599523D01*
Y600228D01*
X910432Y600229D01*
Y606549D01*
G01X903742Y599500D02*
X903740Y599523D01*
X903739Y599524D01*
Y602731D01*
X901934Y604536D01*
G01X880317Y599500D02*
X880315Y599523D01*
X880314Y599524D01*
Y606549D01*
G01X866931Y599500D02*
X866929Y599523D01*
X866928Y599524D01*
Y602731D01*
X865123Y604536D01*
G01X850198Y599500D02*
X850196Y599523D01*
Y606163D01*
X849810Y606549D01*
G01X873624Y599500D02*
X873622Y599523D01*
Y600228D01*
X873621Y600229D01*
Y606549D01*
G01X853545Y617610D02*
X853543D01*
Y612649D01*
G01X870275D02*
Y617610D01*
X870277D01*
G01X876968Y612649D02*
Y617610D01*
X876970D01*
G01X907086Y612649D02*
Y617610D01*
X907088D01*
G01X890354Y612649D02*
Y617610D01*
X890356D01*
G01X883661Y612599D02*
Y617610D01*
X883663D01*
G01X970800Y13200D02*
X974250D01*
G01X940553Y22923D02*
X940551D01*
G01X938732Y17114D02*
X940551Y18933D01*
Y22923D01*
G01X962050Y13200D02*
X957600D01*
G01X947246Y22923D02*
Y14817D01*
X947243Y14814D01*
G01X947246Y22923D02*
Y29946D01*
X947243Y29949D01*
G01X953939Y22923D02*
Y29946D01*
X953936Y29949D01*
G01X940553Y-14877D02*
Y-11672D01*
X938745Y-9864D01*
G01X957285Y3233D02*
X957283D01*
G01Y9300D02*
Y3233D01*
G01X950592D02*
X950590D01*
G01Y-1751D02*
Y3233D01*
G01X947246Y-14877D02*
X947244D01*
Y-14172D01*
X947243Y-14171D01*
Y-7851D01*
G01X943899Y3233D02*
X943897D01*
G01Y9114D02*
Y3233D01*
G01X953939Y-14877D02*
Y-7854D01*
X953936Y-7851D01*
G01X917128Y22923D02*
Y29946D01*
X917125Y29949D01*
G01X923820Y22923D02*
X923818D01*
G01X923432Y29949D02*
X923818Y29563D01*
Y22923D01*
G01X917128D02*
Y14817D01*
X917125Y14814D01*
G01X930513Y22923D02*
X930511D01*
G01X929811Y14814D02*
X930511Y15514D01*
Y22923D01*
G01X917128Y-14877D02*
Y-7854D01*
X917125Y-7851D01*
G01X923820Y-14877D02*
X923818D01*
Y-8237D01*
X923432Y-7851D01*
G01X933860Y3233D02*
X933858D01*
G01X933632Y9098D02*
X933858Y8872D01*
Y3233D01*
G01X927167D02*
X927165D01*
G01X927015Y9114D02*
X927165Y8964D01*
Y3233D01*
G01X920474D02*
X920472D01*
G01Y9114D02*
Y3233D01*
G01X913781D02*
X913779D01*
G01Y-1751D02*
Y3233D01*
G01X920472D02*
Y-1801D01*
G01X913779Y3233D02*
Y9114D01*
G01X940551Y22923D02*
X940550Y22924D01*
Y26131D01*
X938745Y27936D01*
G01X957283Y3233D02*
Y-1843D01*
G01X950590Y3233D02*
Y9114D01*
G01X943897Y3233D02*
Y-1751D01*
G01X923818Y22923D02*
Y18650D01*
X923468Y18300D01*
Y14714D01*
G01X927165Y3233D02*
Y-1751D01*
G01X950592Y41033D02*
X950590D01*
G01X955700Y100800D02*
X953886Y98986D01*
Y90414D01*
G01X943899Y78833D02*
X943897D01*
G01Y73849D02*
Y78833D01*
G01X950592D02*
X950590D01*
G01Y84714D02*
Y78833D01*
G01X974250Y51000D02*
X970940D01*
X970800Y50860D01*
G01X940553Y60723D02*
X940551D01*
G01X938745Y65736D02*
X940550Y63931D01*
Y60724D01*
X940551Y60723D01*
G01X953939D02*
Y67746D01*
X953936Y67749D01*
G01X962050Y51000D02*
X959180D01*
X958909Y50729D01*
X957558D01*
G01X957285Y41033D02*
X957283D01*
G01X947246Y60723D02*
X947244D01*
G01X947243Y67749D02*
Y61429D01*
X947244Y61428D01*
Y60723D01*
G01X943899Y41033D02*
X943897D01*
G01Y46914D02*
Y41033D01*
G01X957283Y46185D02*
Y41033D01*
G01X927167Y78833D02*
X927165D01*
G01X927015Y73849D02*
X927165Y73999D01*
Y78833D01*
G01X913781D02*
X913779D01*
G01Y84714D02*
Y78833D01*
G01X920474D02*
X920472D01*
G01Y84714D02*
Y78833D01*
G01X930513Y60723D02*
X930511D01*
G01X920474Y41033D02*
X920472D01*
G01Y46914D02*
Y41033D01*
G01X917128Y60723D02*
Y52617D01*
X917125Y52614D01*
G01X913781Y41033D02*
X913779D01*
G01Y36049D02*
Y41033D01*
G01X927167D02*
X927165D01*
G01X917128Y60723D02*
Y67746D01*
X917125Y67749D01*
G01X927015Y46914D02*
Y50585D01*
X923818Y53782D01*
Y60723D01*
G01X923820D02*
X923818D01*
G01X927015Y46914D02*
X927165Y46764D01*
Y41033D01*
G01X950590Y36049D02*
Y41033D01*
G01X913779Y78833D02*
Y73849D01*
G01X920472Y78833D02*
Y73799D01*
G01Y41033D02*
Y35999D01*
G01X913779Y41033D02*
Y46914D01*
G01X943897Y78833D02*
Y84714D01*
G01X950590Y78833D02*
Y73849D01*
G01X940551Y60723D02*
Y56733D01*
X938732Y54914D01*
G01X957283Y41033D02*
Y35957D01*
G01X947244Y60723D02*
Y52615D01*
X947243Y52614D01*
G01X943897Y41033D02*
Y36049D01*
G01X927165Y78833D02*
Y84564D01*
X927015Y84714D01*
G01X933858Y78833D02*
Y84472D01*
X933632Y84698D01*
G01X930511Y60723D02*
Y53314D01*
X929811Y52614D01*
G01X933858Y41033D02*
Y46672D01*
X933632Y46898D01*
G01X923818Y60723D02*
Y67363D01*
X923432Y67749D01*
G01X927165Y41033D02*
Y36049D01*
G01X950590Y41033D02*
Y46914D01*
G01X953936Y52614D02*
X953939Y52617D01*
G01D02*
Y60723D01*
G01X953800Y105000D02*
Y102700D01*
X955700Y100800D01*
G01X959589Y104689D02*
X962209D01*
X963245Y105725D01*
G01X940553Y523900D02*
X940551Y523923D01*
X940550Y523924D01*
Y527131D01*
X938745Y528936D01*
G01X957301Y495595D02*
X955596Y497300D01*
X954000D01*
G01X917128Y523900D02*
X917126Y523923D01*
X917125Y523924D01*
Y530949D01*
G01X923820Y523900D02*
X923818Y523923D01*
Y530563D01*
X923432Y530949D01*
G01X947243D02*
X947244Y530948D01*
Y523923D01*
X947246Y523900D01*
G01X953939D02*
Y530946D01*
X953936Y530949D01*
G01X967324Y523900D02*
Y520376D01*
X968034Y519666D01*
Y516076D01*
X967322Y515364D01*
G01X960629Y523923D02*
Y523900D01*
G01X960631D02*
X960629D01*
G01X962801Y495595D02*
Y497644D01*
X961309Y499136D01*
G01X967324Y523900D02*
Y529012D01*
X967322Y529014D01*
G01X960629Y523900D02*
Y515364D01*
G01X957283Y574757D02*
Y579810D01*
G01X940553Y561700D02*
X940551Y561723D01*
X940550Y561724D01*
Y564931D01*
X938745Y566736D01*
G01X947246Y561700D02*
X947244Y561723D01*
Y562428D01*
X947243Y562429D01*
Y568749D01*
G01X950592Y579810D02*
X950590D01*
Y574849D01*
G01X943899Y579810D02*
X943897D01*
Y574849D01*
G01X950592Y542010D02*
X950590D01*
Y537049D01*
G01X943899Y542010D02*
X943897D01*
Y537049D01*
G01X913781Y579810D02*
X913779D01*
Y574849D01*
G01X920474Y579810D02*
X920472D01*
Y574799D01*
G01X927167Y579810D02*
X927165D01*
Y574999D01*
X927015Y574849D01*
G01X917128Y561700D02*
X917126Y561723D01*
X917125Y561724D01*
Y568749D01*
G01X923820Y561700D02*
X923818Y561723D01*
Y568363D01*
X923432Y568749D01*
G01X920474Y542010D02*
X920472D01*
Y536999D01*
G01X913781Y542010D02*
X913779D01*
Y537049D01*
G01X927167Y542010D02*
X927165D01*
Y537199D01*
X927015Y537049D01*
G01X957283Y579833D02*
Y579810D01*
G01D02*
X957285D01*
G01X940553Y599500D02*
X940551Y599523D01*
X940550Y599524D01*
Y602731D01*
X938745Y604536D01*
G01X947246Y599500D02*
X947244Y599523D01*
Y600228D01*
X947243Y600229D01*
Y606549D01*
G01X974250Y589800D02*
X970731D01*
G01X917128Y599500D02*
X917126Y599523D01*
X917125Y599524D01*
Y606549D01*
G01X923820Y599500D02*
X923818Y599523D01*
Y606163D01*
X923432Y606549D01*
G01X927015Y612449D02*
Y612649D01*
X927165Y612799D01*
Y617610D01*
X927167D01*
G01X920472Y612399D02*
Y617610D01*
X920474D01*
G01X913779Y612449D02*
Y617610D01*
X913781D01*
G01X957283Y611600D02*
Y617610D01*
X957285D01*
G01X950590Y612249D02*
Y617610D01*
X950592D01*
G01X943897Y612249D02*
Y617610D01*
X943899D01*
G01X953937Y599523D02*
X953936Y599524D01*
Y606549D01*
G01X1003108Y13200D02*
X1004222Y14314D01*
X1007100D01*
G01D02*
Y11714D01*
G01X1010400Y13078D02*
X1009036Y11714D01*
X1007100D01*
G01X1017519Y35942D02*
Y28014D01*
G01Y-1858D02*
Y-9786D01*
G01X1007370Y49659D02*
Y52333D01*
G01X987250Y51000D02*
X983900D01*
G01X1028630Y51028D02*
Y54730D01*
X1030400Y56500D01*
G01X1028630Y51028D02*
Y45870D01*
X1031600Y42900D01*
G01X1030500Y97000D02*
X1032900Y99400D01*
X1035300D01*
X1035900Y98800D01*
G01X1035750Y503006D02*
X1031301D01*
X1030500Y503807D01*
Y505756D01*
G01X987403Y523900D02*
X987401D01*
G01X1017521D02*
X1017519Y523923D01*
Y529057D01*
G01X987401Y523923D02*
Y523900D01*
G01D02*
Y515364D01*
G01X1010500Y551700D02*
X1009311Y550511D01*
X1007147D01*
G01X1028200Y551000D02*
Y548100D01*
X1026500Y546400D01*
G01X1007147Y553111D02*
X1004219D01*
X1003108Y552000D01*
G01D02*
X1004008Y551100D01*
X1005400D01*
X1005989Y550511D01*
X1007147D01*
G01X1017300Y536200D02*
X1017519Y536419D01*
Y542010D01*
G01D02*
X1017521D01*
G01X1007280Y547914D02*
X1007480Y547714D01*
G01X1017300Y547914D02*
X1017381Y547833D01*
X1017519D01*
G01X1017521Y579810D02*
Y583522D01*
X1019277Y585278D01*
G01X1016800Y574742D02*
X1017521Y575463D01*
G01X1017519Y547833D02*
Y542010D01*
G01X1019277Y585278D02*
Y585714D01*
G01X1017521Y575463D02*
Y579810D01*
G01X983900Y589800D02*
X987250D01*
G01X977362Y607292D02*
X978136D01*
X980708Y609864D01*
G01X997441Y607292D02*
X998215D01*
X1000787Y609864D01*
G01X1061025Y523900D02*
Y520825D01*
X1060200Y520000D01*
Y516187D01*
X1061023Y515364D01*
G01X1050986Y523900D02*
Y529021D01*
X1050985Y529022D01*
G01X1050986Y523900D02*
Y518160D01*
X1050983Y518157D01*
G01X1061025Y523900D02*
Y529021D01*
X1061024Y529022D01*
G01X1077757Y523900D02*
Y518159D01*
X1077755Y518157D01*
G01X1084450Y523900D02*
Y518159D01*
X1084448Y518157D01*
G01X1077757Y523900D02*
Y529022D01*
G01X1084450Y523900D02*
Y529022D01*
G01X1091143Y523900D02*
Y529005D01*
X1091141Y529007D01*
G01X1091143Y523900D02*
Y518059D01*
X1091141Y518057D01*
G01X1092116Y589800D02*
X1094200D01*
X1095300Y590900D01*
X1098300D01*
G01X1067716Y609864D02*
Y604499D01*
G01X1091141Y612557D02*
Y607292D01*
G01X1077755D02*
X1075183Y609864D01*
X1074409D01*
G01X1084448Y607292D02*
X1081876Y609864D01*
X1081102D01*
G01X1050983Y607292D02*
X1048411Y609864D01*
X1047637D01*
G01X1057676Y612657D02*
X1057677Y612658D01*
G01X1131301Y3233D02*
X1131299D01*
G01X1134647Y22923D02*
X1134645D01*
G01X1148033D02*
X1148031D01*
G01X1156265Y27936D02*
X1158070Y26131D01*
Y22923D01*
G01X1127954D02*
X1127952D01*
G01Y14814D02*
Y22923D01*
G01X1141340D02*
X1141338D01*
G01X1140952Y29949D02*
X1141338Y29563D01*
Y22923D01*
G01X1137994Y3233D02*
X1137992D01*
G01Y-1801D02*
Y3233D01*
G01X1124608D02*
X1124606D01*
G01Y-1751D02*
Y3233D01*
G01X1127954Y-14877D02*
X1127952D01*
Y-7851D01*
G01X1141340Y-14877D02*
X1141338D01*
Y-8237D01*
X1140952Y-7851D01*
G01X1134647Y-14877D02*
X1134645D01*
Y-7851D01*
G01X1158072Y-14877D02*
X1158070D01*
Y-11669D01*
X1156265Y-9864D01*
G01X1151380Y3233D02*
X1151378D01*
G01X1151152Y9098D02*
X1151378Y8872D01*
Y3233D01*
G01X1144687D02*
X1144685D01*
G01X1144535Y9114D02*
X1144685Y8964D01*
Y3233D01*
G01X1097836Y22923D02*
X1097834D01*
G01X1104529D02*
X1104527D01*
G01X1121261D02*
X1121259D01*
G01X1111222D02*
X1111220D01*
G01X1110520Y14814D02*
X1111220Y15514D01*
Y22923D01*
G01X1121261Y-14877D02*
Y-11672D01*
X1119453Y-9864D01*
G01X1104529Y-14877D02*
X1104527D01*
Y-8237D01*
X1104141Y-7851D01*
G01X1097836Y-14877D02*
X1097834D01*
Y-7662D01*
X1097352Y-7180D01*
G01X1101183Y3233D02*
X1101181D01*
G01Y9114D02*
Y3233D01*
G01X1114568D02*
X1114566D01*
G01X1114340Y9098D02*
X1114566Y8872D01*
Y3233D01*
G01X1107876D02*
X1107874D01*
G01X1107724Y9114D02*
X1107874Y8964D01*
Y3233D01*
G01X1119440Y17114D02*
X1121259Y18933D01*
Y22923D01*
G01X1131299Y-1751D02*
Y3233D01*
G01X1134645Y14814D02*
Y22923D01*
G01X1097834D02*
Y28100D01*
G01X1104527Y22923D02*
Y29563D01*
X1104141Y29949D01*
G01X1101181Y3233D02*
Y-1801D01*
G01X1158070Y22923D02*
Y18932D01*
X1156252Y17114D01*
G01X1127952Y22923D02*
Y29949D01*
G01X1141338Y22923D02*
Y15064D01*
X1140988Y14714D01*
G01X1137992Y3233D02*
Y9114D01*
G01X1124606Y3233D02*
Y9114D01*
G01X1144685Y3233D02*
Y-1751D01*
G01X1107874Y3233D02*
Y-1751D01*
G01X1121259Y22923D02*
X1121258Y22924D01*
Y26131D01*
X1119453Y27936D01*
G01X1131299Y3233D02*
Y9114D01*
G01X1134645Y22923D02*
Y29949D01*
G01X1104527Y22923D02*
Y15064D01*
G01X1097834Y22923D02*
Y17666D01*
G01D02*
X1098500Y17000D01*
G01X1104527Y15064D02*
X1104177Y14714D01*
G01X1097836Y3233D02*
X1097834D01*
Y11100D01*
G01X1144535Y46914D02*
Y50865D01*
X1141338Y54062D01*
Y60723D01*
G01X1124608Y41033D02*
X1124606D01*
G01X1124608Y78833D02*
X1124606D01*
G01X1131301D02*
X1131299D01*
G01Y73849D02*
Y78833D01*
G01X1137994D02*
X1137992D01*
G01Y73799D02*
Y78833D01*
G01X1144687D02*
X1144685D01*
G01Y73849D02*
Y78833D01*
G01X1156265Y65736D02*
X1158070Y63931D01*
Y60723D01*
G01X1144687Y41033D02*
X1144685D01*
G01X1151152Y46898D02*
X1151378Y46672D01*
Y41033D01*
G01X1131301D02*
X1131299D01*
G01Y36049D02*
Y41033D01*
G01X1127954Y60723D02*
X1127952D01*
G01Y67749D02*
Y60723D01*
G01X1137994Y41033D02*
X1137992D01*
G01Y35999D02*
Y41033D01*
G01X1134647Y60723D02*
X1134645D01*
G01Y67749D02*
Y60723D01*
G01X1140952Y67749D02*
X1141338Y67363D01*
Y60723D01*
G01X1107876Y78833D02*
X1107874D01*
G01X1107724Y84714D02*
X1107874Y84564D01*
Y78833D01*
G01X1101183D02*
X1101181D01*
G01Y73799D02*
Y78833D01*
G01X1097836Y41033D02*
X1097834D01*
G01X1121261Y60723D02*
Y63928D01*
X1119453Y65736D01*
G01X1097836Y78833D02*
X1097834D01*
G01X1104529Y60723D02*
X1104527D01*
G01X1104141Y67749D02*
X1104527Y67363D01*
Y60723D01*
G01X1107876Y41033D02*
X1107874D01*
G01X1107724Y46914D02*
X1107874Y46764D01*
Y41033D01*
G01X1101183D02*
X1101181D01*
G01Y46900D02*
Y41033D01*
G01X1144535Y46914D02*
X1144685Y46764D01*
Y41033D01*
G01X1119440Y54914D02*
X1121261Y56735D01*
Y60723D01*
G01X1124606Y46914D02*
Y41033D01*
G01Y84714D02*
Y78833D01*
G01X1097834Y60723D02*
X1097836D01*
G01X1101181Y78833D02*
Y84714D01*
G01X1097834Y41033D02*
Y36519D01*
G01Y78833D02*
Y84912D01*
X1098218Y85296D01*
G01X1104527Y60723D02*
Y55950D01*
X1104177Y55600D01*
Y52514D01*
G01X1101181Y41033D02*
Y35999D01*
G01X1131299Y78833D02*
Y84714D01*
G01X1151378Y78833D02*
Y84472D01*
X1151152Y84698D01*
G01X1137992Y78833D02*
Y84714D01*
G01X1144685Y78833D02*
Y84564D01*
X1144535Y84714D01*
G01X1158070Y60723D02*
Y56732D01*
X1156252Y54914D01*
G01X1148031Y60723D02*
Y53314D01*
X1147331Y52614D01*
G01X1131299Y41033D02*
Y46914D01*
G01X1127952Y60723D02*
Y52614D01*
G01X1137992Y41033D02*
Y46914D01*
G01X1134645Y60723D02*
Y52614D01*
G01X1141338Y60723D02*
X1141340D01*
G01X1107874Y78833D02*
Y73849D01*
G01X1114566Y78833D02*
Y84472D01*
X1114340Y84698D01*
G01X1111220Y60723D02*
Y53314D01*
X1110520Y52614D01*
G01X1107874Y41033D02*
Y36049D01*
G01X1114566Y41033D02*
Y46672D01*
X1114340Y46898D01*
G01X1144685Y41033D02*
Y36049D01*
G01X1124606Y41033D02*
Y36049D01*
G01Y78833D02*
Y73849D01*
G01X1098207Y73589D02*
X1097834Y73962D01*
G01X1098235Y68090D02*
X1097834Y67689D01*
G01Y41033D02*
Y46684D01*
G01Y60723D02*
Y55630D01*
G01Y73962D02*
Y78833D01*
G01Y67689D02*
Y60723D01*
G01Y46684D02*
X1098125Y46975D01*
G01X1097834Y55630D02*
X1098581Y54883D01*
G01X1121771Y305896D02*
X1119521D01*
G01X1115011Y340996D02*
X1117261D01*
G01X1121771Y399496D02*
X1120641Y401447D01*
G01X1100361Y397547D02*
X1101010Y398666D01*
X1101491Y399496D01*
G01X1118391Y405347D02*
X1117261Y407296D01*
G01X1098111Y405347D02*
X1096699Y407782D01*
G01X1134647Y523900D02*
X1134645Y523923D01*
Y530949D01*
G01X1141340Y523900D02*
X1141338Y523923D01*
Y530563D01*
X1140952Y530949D01*
G01X1121258Y527131D02*
X1119453Y528936D01*
G01X1104529Y523900D02*
X1104527Y523923D01*
Y530563D01*
X1104141Y530949D01*
G01X1097834Y530972D02*
Y523923D01*
X1097836Y523900D01*
G01X1101183Y542010D02*
X1101181D01*
G01X1127954Y561700D02*
X1127952Y561723D01*
Y568749D01*
G01X1144687Y579810D02*
X1144685D01*
Y574849D01*
G01X1131301Y579810D02*
X1131299D01*
Y574849D01*
G01X1124608Y579810D02*
X1124606D01*
Y574849D01*
G01X1158072Y561700D02*
X1158070Y561723D01*
Y564931D01*
X1156265Y566736D01*
G01X1134647Y561700D02*
X1134645Y561723D01*
Y568749D01*
G01X1141340Y561700D02*
X1141338Y561723D01*
Y568363D01*
X1140952Y568749D01*
G01X1137994Y579810D02*
X1137992D01*
Y574799D01*
G01X1158072Y523900D02*
X1158070Y523923D01*
Y527131D01*
X1156265Y528936D01*
G01X1124608Y542010D02*
X1124606D01*
Y537049D01*
G01X1144687Y542010D02*
X1144685D01*
Y537049D01*
G01X1137994Y542010D02*
X1137992D01*
Y536999D01*
G01X1131301Y542010D02*
X1131299D01*
Y537049D01*
G01X1097836Y579810D02*
X1097834D01*
G01X1104529Y561700D02*
X1104527Y561723D01*
Y568363D01*
X1104141Y568749D01*
G01X1101183Y579810D02*
X1101181D01*
G01Y574799D02*
Y579810D01*
G01X1121261Y561700D02*
X1121259Y561723D01*
X1121258Y561724D01*
Y564931D01*
X1119453Y566736D01*
G01X1107876Y579810D02*
X1107874D01*
Y574849D01*
G01X1097834Y579833D02*
Y579810D01*
G01X1107876Y542010D02*
X1107874D01*
Y537049D01*
G01X1097834Y542033D02*
Y542010D01*
G01X1101181Y542033D02*
Y542010D01*
G01X1097834D02*
X1097836D01*
G01X1097834Y561723D02*
Y569200D01*
G01Y579810D02*
Y574838D01*
X1097899Y574773D01*
G01X1101181Y579810D02*
Y579833D01*
G01Y542010D02*
Y536999D01*
G01X1098018Y531156D02*
X1097834Y530972D01*
G01Y542010D02*
Y536929D01*
G01D02*
X1098040Y536723D01*
G01X1158072Y599500D02*
X1158070Y599523D01*
Y602731D01*
X1156265Y604536D01*
G01X1134647Y599500D02*
X1134645Y599523D01*
Y606549D01*
G01X1141340Y599500D02*
X1141338Y599523D01*
Y606163D01*
X1140952Y606549D01*
G01X1127954Y599500D02*
X1127952Y599523D01*
Y606549D01*
G01X1121261Y599500D02*
X1121259Y599523D01*
X1121258Y599524D01*
Y602731D01*
X1119453Y604536D01*
G01X1104529Y599500D02*
X1104527Y599523D01*
Y606163D01*
X1104141Y606549D01*
G01X1101181Y612599D02*
Y617610D01*
X1101183D01*
G01X1097834Y599523D02*
Y606738D01*
X1097352Y607220D01*
G01X1097836Y617610D02*
X1097834D01*
Y613119D01*
X1097374Y612659D01*
G01X1211616Y3233D02*
X1211614D01*
G01X1218309D02*
X1218307D01*
G01X1194883Y22923D02*
X1194881D01*
G01X1214962D02*
X1214960D01*
G01X1214574Y29949D02*
X1214960Y29563D01*
Y22923D01*
G01X1208269D02*
X1208267D01*
G01Y14814D02*
Y22923D01*
G01X1184844D02*
X1184842D01*
G01X1184142Y14814D02*
X1184842Y15514D01*
Y22923D01*
G01X1201576D02*
X1201574D01*
G01Y29949D02*
Y22923D01*
G01X1181498Y3233D02*
X1181496D01*
G01Y-1751D02*
Y3233D01*
G01X1201576Y-14877D02*
X1201574D01*
Y-7851D01*
G01X1204923Y3233D02*
X1204921D01*
G01Y9114D02*
Y3233D01*
G01X1198230D02*
X1198228D01*
G01Y-1751D02*
Y3233D01*
G01X1194883Y-14877D02*
X1194881D01*
Y-11669D01*
X1193076Y-9864D01*
G01X1208269Y-14877D02*
X1208267D01*
Y-7851D01*
G01X1214962Y-14877D02*
X1214960D01*
Y-8237D01*
X1214574Y-7851D01*
G01X1171458Y22923D02*
X1171456D01*
G01Y29949D02*
Y22923D01*
G01X1158072D02*
X1158070D01*
G01X1164765D02*
X1164763D01*
G01Y29949D02*
Y22923D01*
G01X1178151D02*
X1178149D01*
G01X1177763Y29949D02*
X1178149Y29563D01*
Y22923D01*
G01X1178151Y-14877D02*
X1178149D01*
Y-8237D01*
X1177763Y-7851D01*
G01X1171458Y-14877D02*
X1171456D01*
Y-7851D01*
G01X1164765Y-14877D02*
X1164763D01*
Y-7851D01*
G01X1174805Y3233D02*
X1174803D01*
G01Y9114D02*
Y3233D01*
G01X1168112D02*
X1168110D01*
G01Y9114D02*
Y3233D01*
G01X1161419D02*
X1161417D01*
G01Y9114D02*
Y3233D01*
G01X1193063Y17114D02*
X1194881Y18932D01*
Y22923D01*
G01X1211614Y9114D02*
Y3233D01*
G01X1218157Y9114D02*
X1218307Y8964D01*
Y3233D01*
G01X1164763Y22923D02*
Y14814D01*
G01X1161417Y3233D02*
Y-1751D01*
G01X1214960Y22923D02*
Y15074D01*
X1214600Y14714D01*
G01X1208267Y22923D02*
Y29949D01*
G01X1201574Y22923D02*
Y14814D01*
G01X1181496Y3233D02*
Y8964D01*
X1181346Y9114D01*
G01X1188189Y3233D02*
Y8872D01*
X1187963Y9098D01*
G01X1204921Y3233D02*
Y-1751D01*
G01X1198228Y3233D02*
Y9114D01*
G01X1171456Y22923D02*
Y14814D01*
G01X1178149Y22923D02*
Y15064D01*
X1177799Y14714D01*
G01X1174803Y3233D02*
Y-1801D01*
G01X1168110Y3233D02*
Y-1751D01*
G01X1194881Y22923D02*
Y26131D01*
X1193076Y27936D01*
G01X1211614Y3233D02*
Y-1801D01*
G01X1218307Y3233D02*
Y-1751D01*
G01X1161419Y41033D02*
X1161417D01*
G01X1181346Y46914D02*
Y51154D01*
X1178149Y54351D01*
Y60723D01*
G01X1174805Y41033D02*
X1174803D01*
G01X1198230D02*
X1198228D01*
G01X1218309Y78833D02*
X1218307D01*
G01X1211616D02*
X1211614D01*
G01X1198230D02*
X1198228D01*
G01X1181498D02*
X1181496D01*
G01Y73849D02*
Y78833D01*
G01X1204923D02*
X1204921D01*
G01Y73849D02*
Y78833D01*
G01X1181498Y41033D02*
X1181496D01*
G01X1214962Y60723D02*
X1214960D01*
G01Y52864D02*
Y60723D01*
G01X1208269D02*
X1208267D01*
G01Y67749D02*
Y60723D01*
G01X1218309Y41033D02*
X1218307D01*
G01X1218157Y46914D02*
X1218307Y46764D01*
Y41033D01*
G01X1187963Y46898D02*
X1188189Y46672D01*
Y41033D01*
G01X1194883Y60723D02*
X1194881D01*
G01X1193076Y65736D02*
X1194881Y63931D01*
Y60723D01*
G01X1201576D02*
X1201574D01*
G01Y67749D02*
Y60723D01*
G01X1204923Y41033D02*
X1204921D01*
G01Y46914D02*
Y41033D01*
G01X1211616D02*
X1211614D01*
G01Y46914D02*
Y41033D01*
G01X1161419Y78833D02*
X1161417D01*
G01Y73849D02*
Y78833D01*
G01X1168112D02*
X1168110D01*
G01Y73849D02*
Y78833D01*
G01X1174805D02*
X1174803D01*
G01Y73799D02*
Y78833D01*
G01X1178151Y60723D02*
X1178149D01*
G01X1158072D02*
X1158070D01*
G01X1168112Y41033D02*
X1168110D01*
Y36049D01*
G01X1171458Y60723D02*
X1171456D01*
G01Y67749D02*
Y60723D01*
G01X1164765D02*
X1164763D01*
G01Y67749D02*
Y60723D01*
G01X1181346Y46914D02*
X1181496Y46764D01*
Y41033D01*
G01X1161417Y46914D02*
Y41033D01*
G01X1174803Y46914D02*
Y41033D01*
G01X1198228Y46914D02*
Y41033D01*
G01Y73849D02*
Y78833D01*
G01X1218307Y73849D02*
Y78833D01*
G01X1211614Y73799D02*
Y78833D01*
G01X1161417D02*
Y84714D01*
G01X1164763Y60723D02*
Y52614D01*
G01X1161417Y41033D02*
Y36049D01*
G01X1181496Y78833D02*
Y84564D01*
X1181346Y84714D01*
G01X1188189Y78833D02*
Y84472D01*
X1187963Y84698D01*
G01X1204921Y78833D02*
Y84714D01*
G01X1214960Y60723D02*
Y67363D01*
X1214574Y67749D01*
G01X1208267Y60723D02*
Y52614D01*
G01X1218307Y41033D02*
Y36049D01*
G01X1184842Y60723D02*
Y53314D01*
X1184142Y52614D01*
G01X1194881Y60723D02*
Y56732D01*
X1193063Y54914D01*
G01X1201574Y60723D02*
Y52614D01*
G01X1204921Y41033D02*
Y36049D01*
G01X1211614Y41033D02*
Y35999D01*
G01X1168110Y78833D02*
Y84714D01*
G01X1174803Y78833D02*
Y84714D01*
G01X1178149Y60723D02*
Y67363D01*
X1177763Y67749D01*
G01X1171456Y60723D02*
Y52614D01*
G01X1181496Y41033D02*
Y36049D01*
G01X1174803Y41033D02*
Y35999D01*
G01X1198228Y41033D02*
Y36049D01*
G01Y78833D02*
Y84714D01*
G01X1218307Y78833D02*
Y84564D01*
X1218157Y84714D01*
G01X1211614Y78833D02*
Y84714D01*
G01X1214962Y523900D02*
X1214960Y523923D01*
Y530563D01*
X1214574Y530949D01*
G01X1208269Y523900D02*
X1208267Y523923D01*
Y530949D01*
G01X1194883Y523900D02*
X1194881Y523923D01*
Y527131D01*
X1193076Y528936D01*
G01X1201576Y523900D02*
X1201574Y523923D01*
Y530949D01*
G01X1164765Y523900D02*
X1164763Y523923D01*
Y530949D01*
G01X1171458Y523900D02*
X1171456Y523923D01*
Y530949D01*
G01X1178151Y523900D02*
X1178149Y523923D01*
Y530563D01*
X1177763Y530949D01*
G01X1181498Y579810D02*
X1181496D01*
Y574849D01*
G01X1218309Y579810D02*
X1218307D01*
Y574849D01*
G01X1214962Y561700D02*
X1214960Y561723D01*
Y568363D01*
X1214574Y568749D01*
G01X1208269Y561700D02*
X1208267Y561723D01*
Y568749D01*
G01X1194883Y561700D02*
X1194881Y561723D01*
Y564931D01*
X1193076Y566736D01*
G01X1201576Y561700D02*
X1201574Y561723D01*
Y568749D01*
G01X1211616Y579810D02*
X1211614D01*
Y574799D01*
G01X1198230Y579810D02*
X1198228D01*
Y574849D01*
G01X1204923Y579810D02*
X1204921D01*
Y574849D01*
G01X1181498Y542010D02*
X1181496D01*
Y537049D01*
G01X1218307D02*
Y542010D01*
X1218309D01*
G01X1211616D02*
X1211614D01*
Y536999D01*
G01X1204923Y542010D02*
X1204921D01*
Y537049D01*
G01X1198230Y542010D02*
X1198228D01*
Y537049D01*
G01X1178151Y561700D02*
X1178149Y561723D01*
Y568363D01*
X1177763Y568749D01*
G01X1161419Y579810D02*
X1161417D01*
Y574849D01*
G01X1171458Y561700D02*
X1171456Y561723D01*
Y568749D01*
G01X1174805Y579810D02*
X1174803D01*
Y574799D01*
G01X1168112Y579810D02*
X1168110D01*
Y574849D01*
G01X1164765Y561700D02*
X1164763Y561723D01*
Y568749D01*
G01X1174805Y542010D02*
X1174803D01*
Y536999D01*
G01X1168112Y542010D02*
X1168110D01*
Y537049D01*
G01X1161419Y542010D02*
X1161417D01*
Y537049D01*
G01X1214962Y599500D02*
X1214960Y599523D01*
Y606163D01*
X1214574Y606549D01*
G01X1208269Y599500D02*
X1208267Y599523D01*
Y606549D01*
G01X1194883Y599500D02*
X1194881Y599523D01*
Y602731D01*
X1193076Y604536D01*
G01X1201576Y599500D02*
X1201574Y599523D01*
Y606549D01*
G01X1164765Y599500D02*
X1164763Y599523D01*
Y606549D01*
G01X1178151Y599500D02*
X1178149Y599523D01*
Y606163D01*
X1177763Y606549D01*
G01X1171458Y599500D02*
X1171456Y599523D01*
Y606549D01*
G01X1168110Y612649D02*
Y617610D01*
X1168112D01*
G01X1174803Y612599D02*
Y617610D01*
X1174805D01*
G01X1204923D02*
X1204921D01*
Y612649D01*
G01X1181496D02*
Y617610D01*
X1181498D01*
G01X1218307Y612649D02*
Y617610D01*
X1218309D01*
G01X1211614Y612599D02*
Y617610D01*
X1211616D01*
G01X1198230D02*
X1198228D01*
Y612649D01*
G01X1221655Y22923D02*
X1221653D01*
G01X1220953Y14814D02*
X1221653Y15514D01*
Y22923D01*
G01X1238387D02*
X1238385D01*
G01Y29949D02*
Y22923D01*
G01X1231694D02*
X1231692D01*
G01X1229874Y17114D02*
X1231692Y18932D01*
Y22923D01*
G01X1238387Y-14877D02*
X1238385D01*
Y-7851D01*
G01X1225002Y3233D02*
X1225000D01*
G01X1235041D02*
X1235039D01*
G01Y9114D02*
Y3233D01*
G01X1229887Y-9864D02*
X1231692Y-11669D01*
Y-14877D01*
X1231694D01*
G01X1245080Y22923D02*
X1245078D01*
G01Y14814D02*
Y22923D01*
G01X1266108Y13000D02*
X1266186Y13078D01*
X1269700D01*
G01X1248427Y22923D02*
X1248425D01*
Y27899D01*
G01X1241734Y3233D02*
X1241732D01*
G01Y9114D02*
Y3233D01*
G01X1248427D02*
X1248425D01*
G01Y-1751D02*
Y3233D01*
G01X1245080Y-14877D02*
X1245078D01*
Y-7851D01*
G01X1248427Y-14877D02*
X1248425D01*
Y-9901D01*
G01X1251773Y-14877D02*
X1251771D01*
Y-9901D01*
G01X1248425Y9157D02*
Y12817D01*
X1248608Y13000D01*
G01X1225000Y3233D02*
Y8872D01*
X1224774Y9098D01*
G01X1238385Y22923D02*
Y14814D01*
G01X1231692Y22923D02*
Y26131D01*
X1229887Y27936D01*
G01X1235039Y3233D02*
Y-1751D01*
G01X1245078Y22923D02*
Y29949D01*
G01X1241732Y3233D02*
Y-1751D01*
G01X1248425Y3233D02*
Y9157D01*
G01X1268022Y54443D02*
Y53122D01*
X1266508Y51608D01*
Y51000D01*
G01X1241734Y78833D02*
X1241732D01*
G01X1235041D02*
X1235039D01*
G01Y84714D02*
Y78833D01*
G01X1238387Y60723D02*
X1238385D01*
G01Y67749D02*
Y60723D01*
G01X1224774Y46898D02*
X1225000Y46672D01*
Y41033D01*
G01X1221655Y60723D02*
X1221653D01*
G01X1235041Y41033D02*
X1235039D01*
G01Y46914D02*
Y41033D01*
G01X1231694Y60723D02*
X1231692D01*
G01X1229887Y65736D02*
X1231692Y63931D01*
Y60723D01*
G01X1248427Y78833D02*
X1248425D01*
G01Y73849D02*
Y78833D01*
G01X1241734Y41033D02*
X1241732D01*
G01Y36049D02*
Y41033D01*
G01X1248427D02*
X1248425D01*
G01Y36049D02*
Y41033D01*
G01X1245080Y60723D02*
X1245078D01*
G01Y67749D02*
Y60723D01*
G01X1251773D02*
X1251771D01*
Y65699D01*
G01X1248427Y60723D02*
X1248425D01*
Y65699D01*
G01Y84757D02*
Y89345D01*
X1248608Y89528D01*
G01X1248425Y46957D02*
X1248608Y47140D01*
Y51000D01*
G01X1266108Y89528D02*
X1268581Y92001D01*
Y92706D01*
G01X1241732Y84714D02*
Y78833D01*
G01X1225000D02*
Y84472D01*
X1224774Y84698D01*
G01X1221653Y60723D02*
Y53314D01*
X1220953Y52614D01*
G01X1235039Y78833D02*
Y73849D01*
G01X1238385Y60723D02*
Y52614D01*
G01X1235039Y41033D02*
Y36049D01*
G01X1231692Y60723D02*
Y56732D01*
X1229874Y54914D01*
G01X1248425Y78833D02*
Y84757D01*
G01X1241732Y41033D02*
Y46914D01*
G01X1248425Y41033D02*
Y46957D01*
G01X1245078Y60723D02*
Y52614D01*
G01X1241732Y78833D02*
Y73849D01*
G01X1224775Y127924D02*
X1228751D01*
X1229754Y128927D01*
X1233463D01*
G01X1246251Y130066D02*
X1242848Y126663D01*
X1235727D01*
X1233463Y128927D01*
G01X1231694Y523900D02*
X1231692Y523923D01*
Y527131D01*
X1229887Y528936D01*
G01X1238387Y523900D02*
X1238385Y523923D01*
Y530949D01*
G01X1245080Y523900D02*
X1245078Y523923D01*
Y530949D01*
G01X1248427Y523900D02*
X1248425Y523923D01*
Y528899D01*
G01X1251773Y523900D02*
X1251771Y523923D01*
Y528899D01*
G01X1265500Y513200D02*
X1265978Y513678D01*
X1267978D01*
X1269000Y514700D01*
G01X1248425Y510157D02*
X1249000Y510732D01*
Y513200D01*
G01X1231694Y561700D02*
X1231692Y561723D01*
Y564931D01*
X1229887Y566736D01*
G01X1238387Y561700D02*
X1238385Y561723D01*
Y568749D01*
G01X1235041Y579810D02*
X1235039D01*
Y574849D01*
G01X1235041Y542010D02*
X1235039D01*
Y537049D01*
G01X1241734Y579810D02*
X1241732D01*
Y574849D01*
G01X1248425Y585757D02*
Y589817D01*
X1248608Y590000D01*
G01X1245080Y561700D02*
X1245078Y561723D01*
Y568749D01*
G01X1248427Y561700D02*
X1248425Y561723D01*
Y566699D01*
G01X1241734Y542010D02*
X1241732D01*
Y537049D01*
G01X1248425Y547957D02*
Y551817D01*
X1248608Y552000D01*
G01X1248427Y542010D02*
X1248425D01*
Y537049D01*
G01X1266508Y552000D02*
X1266500Y552008D01*
Y553800D01*
X1268500Y555800D01*
G01X1248427Y579810D02*
X1248425D01*
Y574849D01*
G01X1231694Y599500D02*
X1231692Y599523D01*
Y602731D01*
X1229887Y604536D01*
G01X1238387Y599500D02*
X1238385Y599523D01*
Y606549D01*
G01X1235041Y617610D02*
X1235039D01*
Y612649D01*
G01X1241734Y617610D02*
X1241732D01*
Y612649D01*
G01X1245080Y599500D02*
X1245078Y599523D01*
Y606549D01*
G01X1248427Y599500D02*
X1248425Y599523D01*
Y604499D01*
G01X1251773Y599500D02*
X1251771Y599523D01*
Y604499D01*
G01X1248427Y617610D02*
X1248425D01*
Y612649D01*
G01X1336500Y86500D02*
Y89896D01*
X1336900D01*
G01D02*
X1337004Y90000D01*
X1339500D01*
G01X1335120Y94450D02*
X1335034D01*
X1334384Y95100D01*
X1332000D01*
G01X1343500Y87500D02*
X1342500Y86500D01*
X1340000D01*
G01X1343590Y7970D02*
X1345970D01*
X1347620Y9620D01*
X1351160D01*
G01X1364700Y88950D02*
Y86550D01*
G01X1374400Y40200D02*
Y39068D01*
X1373117Y37785D01*
X1372400D01*
G01X1363400Y40200D02*
Y38782D01*
X1364489Y37693D01*
G01X1369700Y37800D02*
Y39000D01*
X1370900Y40200D01*
G01X1360700Y86550D02*
Y88950D01*
G01X1347000Y87500D02*
Y90000D01*
G01X1343500D02*
Y87500D01*
G01X1354200Y129450D02*
X1349700D01*
G01X1401960Y524955D02*
X1405460D01*
G01X1378400Y587056D02*
Y585928D01*
X1378200Y585728D01*
Y585724D01*
X1377732Y585256D01*
X1377728D01*
X1376800Y584328D01*
G01X1367400Y587056D02*
Y585696D01*
X1368605Y584491D01*
G01X1373700Y584656D02*
Y585856D01*
X1374900Y587056D01*
G01X1356120Y544446D02*
X1355503Y543829D01*
X1350600D01*
X1349000Y542229D01*
Y540050D01*
G01X1344500D02*
X1349000D01*
G01X1378200Y619200D02*
Y617156D01*
X1376800Y615756D01*
G01X1368200Y619200D02*
Y617200D01*
X1368700Y616700D01*
G01X1373838Y616161D02*
X1374306Y616629D01*
Y616689D01*
X1374700Y617083D01*
Y619200D01*
G01X1460965Y30906D02*
Y34830D01*
G01X1451516Y30669D02*
Y34830D01*
G01X1432619Y30669D02*
Y34830D01*
G01X1423170Y30669D02*
Y36635D01*
G01X1442067Y30669D02*
Y34830D01*
G01X1413721Y30669D02*
Y36749D01*
G01X1425560Y523955D02*
Y523340D01*
X1427900Y521000D01*
X1428500D01*
G01D02*
X1428900Y521400D01*
Y523900D01*
X1428800Y524000D01*
G01X1445750Y539000D02*
Y538700D01*
X1447350Y537100D01*
X1448900D01*
G01X1489311Y30906D02*
Y34830D01*
G01X1497711Y34427D02*
X1498760Y33378D01*
Y30906D01*
G01X1479863D02*
Y34830D01*
G01X1470414Y30906D02*
Y34830D01*
G01X1502268Y611939D02*
X1503107Y611100D01*
X1504700D01*
G01X1469200Y610739D02*
X1468000D01*
X1466800Y611939D01*
G01X1542009Y17268D02*
Y13806D01*
X1541400Y13197D01*
Y12500D01*
G01X1579700Y517900D02*
X1574700D01*
G01X1565210Y509160D02*
Y513290D01*
X1569820Y517900D01*
X1574700D01*
G01X1579290Y597340D02*
Y595090D01*
X1577420Y593220D01*
Y588920D01*
X1576000Y587500D01*
X1574500D01*
G01D02*
X1571493D01*
G01X1539000Y591919D02*
X1542500D01*
G01D02*
X1544181D01*
X1545000Y591100D01*
G01X1579290Y601040D02*
Y597340D01*
G01X1579900Y606050D02*
X1579290Y605440D01*
Y601040D01*
G01X1646700Y480300D02*
Y476769D01*
X1647186Y476283D01*
Y474076D01*
G01X1599104Y588396D02*
X1601143D01*
X1601540Y588793D01*
G01X1601504Y591526D02*
X1600634Y592396D01*
X1599104D01*
G01X1768720Y141250D02*
X1752250D01*
X1751800Y141700D01*
G01X1768720Y146250D02*
X1752889D01*
G01X1768720Y127750D02*
X1757689D01*
X1754189Y124250D01*
G01X1717014Y148950D02*
X1718591Y147373D01*
Y147372D01*
G01Y144222D02*
X1714114Y148699D01*
Y148950D01*
G01X1731260Y209600D02*
Y204236D01*
X1731264D01*
G01X1756600Y198800D02*
X1756461Y199260D01*
Y204236D01*
G01X1756000Y210000D02*
Y208500D01*
X1756461Y208039D01*
Y204236D01*
G01X1753400Y209900D02*
X1753345Y209846D01*
X1753307Y204236D01*
X1753311D01*
G01X1743900Y209700D02*
X1743897Y209697D01*
X1743893Y206500D01*
X1743881Y205700D01*
X1743858Y204236D01*
X1743862D01*
G01X1744000Y198800D02*
Y198988D01*
X1743862Y199126D01*
Y204236D01*
G01X1740709Y209600D02*
Y204236D01*
X1740713D01*
G01X1740900Y198800D02*
X1740672Y199032D01*
X1740717Y204236D01*
X1740713D01*
G01X1765950Y209600D02*
X1765944Y209594D01*
X1765940Y206500D01*
X1765928Y205700D01*
X1765905Y204236D01*
X1765909D01*
G01X1769100Y209700D02*
X1769094Y209694D01*
X1769090Y206500D01*
X1769078Y205700D01*
X1769055Y204236D01*
X1769059D01*
G01X1726700Y179400D02*
X1724965Y181135D01*
Y186937D01*
G01X1770973Y179574D02*
X1772209Y180810D01*
Y186937D01*
G01X1764673Y179374D02*
X1762760Y181287D01*
Y186937D01*
G01X1758375Y179574D02*
X1759610Y180809D01*
Y186937D01*
G01X1733178Y179574D02*
X1734413Y180809D01*
Y186937D01*
G01X1739377Y179374D02*
X1737563Y181188D01*
Y186937D01*
G01X1751975Y179374D02*
X1750161Y181188D01*
Y186937D01*
G01X1745777Y179574D02*
X1747012Y180809D01*
Y186937D01*
G01X1734649Y460603D02*
Y466991D01*
X1734663Y467005D01*
G01X1737799Y441754D02*
Y448096D01*
X1737795Y448100D01*
G01X1744098Y460603D02*
Y466991D01*
X1744112Y467005D01*
G01X1747248Y460603D02*
Y466991D01*
X1747262Y467005D01*
G01X1756696Y460603D02*
Y466991D01*
X1756710Y467005D01*
G01X1750397Y441754D02*
Y448033D01*
X1750393Y448037D01*
G01X1753547Y441754D02*
Y448096D01*
X1753543Y448100D01*
G01X1740948Y441754D02*
Y448461D01*
X1740963Y448476D01*
G01X1759846Y460603D02*
Y466991D01*
X1759860Y467005D01*
G01X1762996Y441754D02*
Y447934D01*
X1762992Y447938D01*
G01X1769295Y460603D02*
X1769309Y467005D01*
G01X1772445Y460603D02*
Y466991D01*
X1772459Y467005D01*
G01X1766145Y441754D02*
Y447855D01*
X1766100Y447900D01*
G01X1828657Y17268D02*
Y15000D01*
X1830257Y13400D01*
X1830341D01*
X1830344Y13397D01*
G01X1785612Y10729D02*
X1785492D01*
Y10810D01*
X1785724D01*
X1787707Y12793D01*
Y17268D01*
G01X1822848Y145937D02*
X1823980D01*
X1825243Y147200D01*
X1825917D01*
X1825967Y147150D01*
X1827833D01*
X1827883Y147200D01*
X1832300D01*
G01D02*
X1833600Y145900D01*
G01X1815348Y143437D02*
Y145937D01*
G01X1780720Y123250D02*
Y122720D01*
X1778000Y120000D01*
G01X1781700Y209700D02*
X1781693Y209693D01*
X1781664Y205700D01*
X1781654Y204236D01*
X1781658D01*
G01X1778550Y209600D02*
X1778543Y209593D01*
X1778515Y205700D01*
X1778504Y204236D01*
X1778508D01*
G01X1815670Y209728D02*
Y209230D01*
X1816338Y208562D01*
X1816312Y205700D01*
X1816299Y204236D01*
X1816303D01*
G01X1803072Y209728D02*
Y209230D01*
X1803740Y208562D01*
X1803714Y205700D01*
X1803701Y204236D01*
X1803705D01*
G01X1832274Y209734D02*
X1832074Y209534D01*
Y208874D01*
X1832056Y205700D01*
X1832047Y204236D01*
X1832051D01*
G01X1828950Y209600D02*
X1828937Y209587D01*
X1828909Y205700D01*
X1828898Y204236D01*
X1828902D01*
G01X1820349Y209586D02*
X1819488Y208725D01*
X1819462Y205700D01*
X1819449Y204236D01*
X1819453D01*
G01X1791150Y209600D02*
X1791141Y209591D01*
X1791113Y205700D01*
X1791102Y204236D01*
X1791106D01*
G01X1794300Y209700D02*
X1794291Y209691D01*
X1794262Y205700D01*
X1794252Y204236D01*
X1794256D01*
G01X1833388Y179500D02*
Y181138D01*
X1835201Y182951D01*
Y186937D01*
G01X1827565Y179174D02*
X1825752Y180987D01*
Y186937D01*
G01X1821367Y179574D02*
X1822602Y180809D01*
Y186937D01*
G01X1796170Y179574D02*
X1797406Y180810D01*
Y186937D01*
G01X1789870Y179374D02*
X1787957Y181287D01*
Y186937D01*
G01X1815000Y179300D02*
X1813154Y181146D01*
Y186937D01*
G01X1808769Y179574D02*
X1810004Y180809D01*
Y186937D01*
G01X1802369Y179374D02*
X1800555Y181188D01*
Y186937D01*
G01X1783572Y179574D02*
X1784807Y180809D01*
Y186937D01*
G01X1777172Y179374D02*
X1775358Y181188D01*
Y186937D01*
G01X1819488Y232106D02*
Y226756D01*
G01X1835550Y466870D02*
X1835451Y466771D01*
X1835433Y460602D01*
G01X1835437Y460603D02*
X1835433Y460602D01*
G01X1785043Y460603D02*
X1785057Y467005D01*
G01X1781893Y460603D02*
X1781907Y467005D01*
G01X1778744Y441754D02*
Y448096D01*
X1778740Y448100D01*
G01X1788193Y441754D02*
Y448296D01*
X1788189Y448300D01*
G01X1791342Y441754D02*
Y448396D01*
X1791338Y448400D01*
G01X1794492Y460603D02*
Y466992D01*
X1794505Y467005D01*
G01X1797641Y460603D02*
Y466991D01*
X1797655Y467005D01*
G01X1800791Y441754D02*
Y447939D01*
X1800787Y447943D01*
G01X1803941Y441754D02*
Y447841D01*
X1804000Y447900D01*
G01X1810240Y460603D02*
Y466991D01*
X1810254Y467005D01*
G01X1807090Y460603D02*
Y466991D01*
X1807104Y467005D01*
G01X1813389Y441754D02*
Y447941D01*
X1813385Y447945D01*
G01X1816539Y441754D02*
Y448296D01*
X1816535Y448300D01*
G01X1819689Y460603D02*
Y466992D01*
X1819702Y467005D01*
G01X1822838Y460603D02*
Y466991D01*
X1822852Y467005D01*
G01X1825988Y441754D02*
Y448026D01*
X1825984Y448030D01*
G01X1829137Y441754D02*
Y449563D01*
X1828600Y450100D01*
G01X1832287Y460603D02*
Y466991D01*
X1832301Y467005D01*
G01X1775594Y441754D02*
Y448096D01*
X1775590Y448100D01*
G01X1835433Y460602D02*
Y455947D01*
X1837260Y454120D01*
X1838768D01*
G01X1835000Y575750D02*
X1832750D01*
X1832600Y575600D01*
X1828800D01*
G01X1839500Y212700D02*
Y211500D01*
X1841525Y209475D01*
X1841504Y205700D01*
X1841496Y204236D01*
X1841500D01*
G01X1838586Y441754D02*
Y447006D01*
X1839400Y447820D01*
Y450440D01*
G01X1844885Y460603D02*
Y466425D01*
X1845330Y466870D01*
G01X1860158Y450322D02*
X1859930Y450550D01*
X1856490D01*
X1854334Y448394D01*
Y441754D01*
G01X1857484Y460603D02*
Y466796D01*
X1857480Y466800D01*
G01X1860633Y460603D02*
Y466133D01*
X1861300Y466800D01*
G01X1863783Y441754D02*
Y447383D01*
X1864300Y447900D01*
G01X1882677Y447930D02*
X1882681Y447926D01*
Y441754D01*
G01X1848035Y460603D02*
Y455218D01*
X1847185Y454368D01*
G01X1935000Y153600D02*
X1937900D01*
G01X1936750Y173600D02*
X1939316D01*
G01X1936750Y161600D02*
X1940647D01*
X1475098Y374668D03*
Y377868D03*
X1478298Y371487D03*
X1481479Y368287D03*
X1484679D03*
X1475098Y487132D03*
Y490332D03*
X1481479Y496713D03*
X1484679D03*
X1478298Y493513D03*
X1579902Y377868D03*
Y374668D03*
X1573521Y368287D03*
X1570321D03*
X1576702Y371487D03*
X1579902Y490332D03*
Y487132D03*
X1570321Y496713D03*
X1573521D03*
X1576702Y493513D03*
X1602717Y104467D03*
X1605867Y110766D03*
X1602717Y107617D03*
X1605867Y104467D03*
Y107617D03*
X1609016Y110766D03*
Y104467D03*
Y107617D03*
X1602717Y110766D03*
Y170609D03*
Y167459D03*
X1605867D03*
Y170609D03*
X1602717Y164310D03*
X1609016D03*
X1605867D03*
X1609016Y167459D03*
Y170609D03*
X1668859Y104467D03*
Y110766D03*
X1662560D03*
X1665709D03*
Y107617D03*
X1662560D03*
X1665709Y104467D03*
X1668859Y107617D03*
X1662560Y104467D03*
X1668859Y170609D03*
X1665709Y167459D03*
X1668859D03*
Y164310D03*
X1662560D03*
X1665709D03*
Y170609D03*
X1662560D03*
Y167459D03*
G54D270*
X1629039Y580079D03*
X1626087Y585591D03*
X1629039Y565118D03*
X1626087Y570630D03*
X1637898Y580079D03*
X1634945Y585591D03*
X1637898Y565118D03*
X1634945Y570630D03*
X1643803D03*
X1646756Y565118D03*
Y580079D03*
X1643803Y585591D03*
X1640850Y582835D03*
X1631992D03*
X1623134D03*
X1640850Y567874D03*
X1631992D03*
X1623134D03*
X1646756Y610000D03*
Y595039D03*
X1643803Y600551D03*
Y615512D03*
X1629039Y610000D03*
X1626087Y615512D03*
X1629039Y595039D03*
X1626087Y600551D03*
X1637898Y610000D03*
X1634945Y615512D03*
X1637898Y595039D03*
X1634945Y600551D03*
X1623134Y612756D03*
X1640850Y597795D03*
X1631992D03*
X1623134D03*
X1640850Y612756D03*
X1631992D03*
X1676283Y580079D03*
X1673331Y585591D03*
X1676283Y565118D03*
X1673331Y570630D03*
X1685142Y580079D03*
X1682189Y585591D03*
X1685142Y565118D03*
X1682189Y570630D03*
X1691047D03*
X1694000Y565118D03*
Y580079D03*
X1691047Y585591D03*
X1688094Y582835D03*
X1679236D03*
X1670378D03*
X1688094Y567874D03*
X1679236D03*
X1670378D03*
X1694000Y595039D03*
X1691047Y600551D03*
Y615512D03*
X1676283Y610000D03*
X1673331Y615512D03*
X1676283Y595039D03*
X1673331Y600551D03*
X1685142Y610000D03*
X1682189Y615512D03*
X1685142Y595039D03*
X1682189Y600551D03*
X1688094Y612756D03*
X1679236D03*
X1670378D03*
X1688094Y597795D03*
X1679236D03*
X1670378D03*
G54D24*
X-14690Y551470D03*
X-15570Y579350D03*
X33000Y505500D03*
X-6703Y508598D03*
X12450Y519350D03*
X30428Y485956D03*
X23000Y487500D03*
X15200Y487950D03*
X1483Y474017D03*
X-13000Y529400D03*
X-7335Y537800D03*
X-7383Y573807D03*
X64355Y-5240D03*
X58320Y-6800D03*
X72500Y122000D03*
X90558Y239956D03*
X90040Y262300D03*
X69200Y272600D03*
X104010Y227500D03*
X108879Y266557D03*
X103090Y258300D03*
X100800Y292800D03*
X105400Y283300D03*
X102067Y338387D03*
X76000Y335961D03*
X94810Y318710D03*
X91185Y334900D03*
X96840Y282050D03*
X104070Y342980D03*
X71300Y380710D03*
X100153Y376214D03*
X107300Y360500D03*
X106510Y351100D03*
X78700Y460200D03*
X130150Y203950D03*
X112200Y247200D03*
X112400Y277800D03*
X114120Y220530D03*
X113250Y272650D03*
X109230Y326840D03*
X115350Y315590D03*
X116910Y377860D03*
X209750Y217450D03*
X579900Y117700D03*
X598070Y137040D03*
X598880Y146990D03*
X590950Y144340D03*
X596600Y340900D03*
Y335900D03*
X601381Y400800D03*
X596600Y345900D03*
Y350900D03*
Y365900D03*
Y355900D03*
Y360900D03*
Y370900D03*
X602500Y370800D03*
X596481Y403800D03*
Y398800D03*
X601381Y405800D03*
X596481Y408800D03*
X601300Y410800D03*
X607840Y143940D03*
X606060Y155550D03*
X624600Y287900D03*
X663300Y281820D03*
X610200Y377600D03*
X607900Y370900D03*
X640555Y346055D03*
X628589Y463649D03*
X604900Y424300D03*
Y414300D03*
Y419300D03*
X629359Y469583D03*
X632771Y473269D03*
X605176Y487581D03*
X641107Y471989D03*
X634033Y467638D03*
X642600Y497800D03*
X695300Y17900D03*
X710551Y658D03*
X691400Y25800D03*
X702400Y23700D03*
X711300Y12200D03*
X680700Y24700D03*
X696803Y25820D03*
X714700Y75690D03*
X680880Y271000D03*
X667634Y278953D03*
X680932Y265673D03*
X693529Y250188D03*
X701134Y253677D03*
X713900Y291500D03*
X716900Y305400D03*
X668700Y285000D03*
X695790Y351300D03*
X684126Y369876D03*
X694662Y369884D03*
X670185Y492563D03*
X670400Y497700D03*
X667857Y508142D03*
X672452Y505805D03*
X691000Y512300D03*
X697094Y506828D03*
X702100Y509800D03*
X710760Y488200D03*
X691332Y507278D03*
X716100Y480260D03*
X705800Y576400D03*
X692340Y572850D03*
X698580Y561630D03*
X668260Y594770D03*
X682640Y591000D03*
X777100Y204500D03*
X786709Y200427D03*
X759000Y267000D03*
X734454Y245654D03*
X751300Y247600D03*
X756639Y248780D03*
X751578Y285171D03*
X732700Y293100D03*
X757905Y299400D03*
X761942Y282760D03*
X759900Y309188D03*
X765850Y291010D03*
X760103Y397997D03*
X814849Y205001D03*
X792514Y201290D03*
X797717Y201907D03*
X803134Y202969D03*
X808165Y203529D03*
X818960Y202230D03*
X823206Y192202D03*
X817821Y193049D03*
X813248Y190338D03*
X799224Y192309D03*
X863850Y224150D03*
X1218921Y119054D03*
X1260087Y123945D03*
X1261734Y108836D03*
X1257854Y141843D03*
X1232790Y144530D03*
X1338160Y66800D03*
X1341352Y61072D03*
X1342255Y50160D03*
X1341200Y73400D03*
X1341009Y279356D03*
X1334730Y279747D03*
X1315350Y310550D03*
X1323450Y500420D03*
X1356220Y78330D03*
X1362690Y82705D03*
X1383500Y52100D03*
X1386750Y278000D03*
X1376393Y280244D03*
X1402500Y276550D03*
X1400500Y294975D03*
X1402900Y289900D03*
X1393518Y372918D03*
X1386210Y389910D03*
X1398260Y527120D03*
X1372600Y503973D03*
X1392390Y561630D03*
X1390300Y535100D03*
X1387720Y547690D03*
X1356120Y544446D03*
X1389066Y583080D03*
X1352202Y551402D03*
X1394030Y595500D03*
X1420471Y279778D03*
X1415617Y284527D03*
X1408706Y286801D03*
X1405800Y297138D03*
X1439700Y370300D03*
X1432400Y398000D03*
X1435800Y377000D03*
X1427700Y361100D03*
X1433900Y385500D03*
X1431000Y406500D03*
X1414261Y524820D03*
X1417291Y528974D03*
X1439800Y551490D03*
X1446170Y543700D03*
X1500004Y209210D03*
X1505000Y214000D03*
Y209000D03*
X1489061Y231927D03*
X1500346Y219576D03*
X1467700Y255900D03*
X1495300Y224000D03*
X1506396Y289741D03*
X1514500Y285000D03*
X1479678Y339778D03*
X1577200Y108590D03*
X1586210Y104240D03*
X1580890Y105020D03*
X1581995Y155695D03*
X1588439Y154572D03*
X1580377Y161368D03*
X1544200Y246200D03*
X1528562Y283250D03*
X1572588Y322014D03*
X1576500Y341400D03*
X1559980Y317620D03*
X1562000Y303000D03*
X1536100Y339000D03*
X1552000Y325900D03*
X1586385Y301616D03*
X1582347Y612754D03*
X1587490Y611299D03*
X1593200Y63075D03*
X1647588Y94322D03*
X1650931Y90182D03*
X1630411Y78488D03*
X1640578Y77751D03*
X1602350Y72090D03*
X1627498Y94000D03*
X1594480Y94610D03*
X1601067Y94620D03*
X1643478Y91473D03*
X1635302Y79698D03*
X1621375Y66484D03*
X1645578Y77849D03*
X1607051Y69691D03*
X1619124Y77794D03*
X1591460Y104110D03*
X1592800Y115710D03*
X1592617Y122435D03*
X1615440Y181540D03*
X1630154Y208148D03*
X1592450Y168710D03*
X1604766Y182240D03*
X1591500Y181000D03*
X1629473Y184962D03*
X1592450Y175960D03*
X1643700Y242800D03*
X1602418Y237218D03*
X1648600Y233800D03*
X1650400Y246500D03*
X1649666Y241434D03*
X1637450Y331300D03*
X1649692Y288502D03*
X1643320Y281478D03*
X1641594Y288693D03*
X1647900Y306600D03*
X1604439Y324600D03*
X1629944Y324236D03*
X1633337Y362600D03*
X1649005Y354555D03*
X1625500Y367500D03*
X1625681Y372703D03*
X1647100Y398700D03*
X1625535Y361835D03*
X1635342Y355442D03*
X1614400Y367400D03*
X1599320Y441900D03*
X1613400Y420500D03*
X1624602Y417332D03*
X1606791Y459843D03*
X1598130Y435920D03*
X1643300Y455100D03*
Y448100D03*
X1619984Y448700D03*
X1602450Y451360D03*
X1644040Y428970D03*
X1597885Y449318D03*
X1636700Y427100D03*
X1674400Y78363D03*
X1654406Y94104D03*
X1679980Y94970D03*
X1656737Y77856D03*
X1665909Y93638D03*
X1669800Y84800D03*
X1685578Y94887D03*
X1711869Y81690D03*
X1673400Y59420D03*
X1685622Y103069D03*
X1670055Y96483D03*
X1690870Y104300D03*
X1669405Y200568D03*
X1672120Y190000D03*
X1684550Y187970D03*
X1680901Y170417D03*
X1684600Y194000D03*
X1676624Y185521D03*
X1678400Y179600D03*
X1652218Y182351D03*
X1663434Y185008D03*
X1668519Y185387D03*
X1658000Y185337D03*
X1663800Y320500D03*
X1654900Y302400D03*
X1660700Y351600D03*
X1655600Y346500D03*
X1657984Y403994D03*
X1659100Y362067D03*
X1653310Y405771D03*
X1654400Y455700D03*
X1666200Y447100D03*
X1686542Y497217D03*
X1687152Y491569D03*
X1716050Y67000D03*
X1733600Y65000D03*
X1763500Y91900D03*
X1756200Y78300D03*
X1771646Y90218D03*
X1743200Y80300D03*
X1740400Y69000D03*
X1755400Y87700D03*
X1719486Y506800D03*
X1762450Y497950D03*
X1761900Y504100D03*
X1727600Y555100D03*
X1743486Y607088D03*
X1727666Y609067D03*
X1728341Y617959D03*
X1754300Y605268D03*
X1832830Y76430D03*
X1812700Y133277D03*
X1797720Y150800D03*
X1806400Y143657D03*
X1809867Y126371D03*
X1784100Y117300D03*
X1809900Y108500D03*
X1881700Y141000D03*
X1857620Y135210D03*
X1882528Y102739D03*
X1877372Y102673D03*
X1868100Y149700D03*
X1851860Y143880D03*
X1867351Y103141D03*
X1891350Y144850D03*
X1879938Y185588D03*
X1893586Y196570D03*
X1887737Y196600D03*
X1903648Y76710D03*
X1937100Y146900D03*
X1924100Y127700D03*
X1899790Y110510D03*
X1909620Y117370D03*
X1931250Y114240D03*
X1925300Y102500D03*
X1929377Y118916D03*
X1915854Y118600D03*
X1922526Y122626D03*
X1937300Y104700D03*
X1943835Y145666D03*
X1941449Y139750D03*
X1943803Y167176D03*
X1933290Y201870D03*
X1947666Y190345D03*
X1946500Y180000D03*
X1946925Y163227D03*
X1941012Y191784D03*
X1946200Y172047D03*
X1899092Y231294D03*
X1961890Y211043D03*
Y238405D03*
G54D42*
X30857Y37344D03*
X31182Y68711D03*
X20757Y544000D03*
Y580000D03*
X144881Y224533D03*
Y256533D03*
Y288533D03*
Y320533D03*
Y352533D03*
Y384533D03*
X687243Y214000D03*
X794489Y224533D03*
Y256533D03*
Y320533D03*
Y288533D03*
Y352533D03*
X794439Y384533D03*
X1352332Y-6824D03*
X1352643Y25200D03*
X1354950Y384068D03*
X1356643Y572056D03*
Y603256D03*
G54D126*
X382855Y622550D03*
X639225Y255400D03*
Y258900D03*
G54D361*
G01X1365330Y-42860D02*
X1171158D01*
G03Y-46620I0J-1880D01*
G01X1363437D01*
G02Y-54000I0J-3690D01*
G01X1166637D01*
X1160827Y-48190D01*
X1139678D01*
X1135583Y-52285D01*
G01X1365330Y-41050D02*
X1171158D01*
G03Y-48430I0J-3690D01*
G01X1363437D01*
G02Y-52190I0J-1880D01*
G01X1167387D01*
X1161577Y-46380D01*
X1139678D01*
X1135583Y-42285D01*
G01X1880630Y45611D02*
Y38374D01*
X1886857Y32147D01*
X1891800D01*
X1893308Y33655D01*
X1900932D01*
X1900945Y33642D01*
G01X1880536Y60047D02*
X1878908Y58419D01*
X1872619D01*
X1870670Y56470D01*
Y37494D01*
X1876745Y31419D01*
Y27783D01*
X1873102Y24140D01*
Y16787D01*
X1875245Y14644D01*
X1878746D01*
X1881772Y17670D01*
X1886489D01*
X1894469Y25650D01*
X1900945D01*
G01X1880536Y57002D02*
Y55484D01*
X1879493Y54441D01*
X1878084D01*
X1875916Y56609D01*
X1873369D01*
X1872480Y55720D01*
Y50672D01*
X1873780Y49372D01*
Y47992D01*
X1872480Y46692D01*
Y45312D01*
X1873780Y44012D01*
Y42632D01*
X1872480Y41332D01*
Y38244D01*
X1874765Y35959D01*
X1876603D01*
X1877579Y34983D01*
Y33145D01*
X1878555Y32169D01*
Y27033D01*
X1874912Y23390D01*
Y17537D01*
X1875995Y16454D01*
X1877996D01*
X1881022Y19480D01*
X1885739D01*
X1886399Y20140D01*
Y21978D01*
X1887375Y22954D01*
X1889213D01*
X1890189Y23930D01*
Y25768D01*
X1891165Y26744D01*
X1893003D01*
X1893719Y27460D01*
X1896491D01*
X1896951Y27920D01*
Y28640D01*
X1895945Y29646D01*
G01X1880630Y49111D02*
X1882549Y51030D01*
X1889218D01*
G01X1884018Y49064D02*
X1888804D01*
X1889218Y48650D01*
Y46030D01*
G01X1884036Y60047D02*
X1884648Y59435D01*
X1887623D01*
X1889218Y61030D01*
G01X1884036Y57002D02*
X1884659Y57625D01*
X1887623D01*
X1889218Y56030D01*
G01X1884018Y45564D02*
X1885501D01*
X1886214Y44851D01*
Y41725D01*
X1885483Y40994D01*
X1883158D01*
X1882440Y40276D01*
Y39124D01*
X1887607Y33957D01*
X1891050D01*
X1892558Y35465D01*
X1896410D01*
X1896938Y35993D01*
Y36645D01*
X1895945Y37638D01*
G01X1907484Y155900D02*
Y154026D01*
X1907563Y153947D01*
Y152513D01*
X1909949Y150127D01*
Y149809D01*
X1909493Y149353D01*
X1908327D01*
G01X1909453Y155900D02*
Y154095D01*
X1909373Y154015D01*
Y153263D01*
X1911759Y150877D01*
Y149841D01*
X1912219Y149381D01*
X1913392D01*
G01X1903566Y146091D02*
X1901658Y147999D01*
Y153344D01*
X1901579Y153423D01*
Y155900D01*
G01X1903566Y146090D02*
Y146091D01*
G01D02*
X1905704Y143953D01*
Y143135D01*
X1905381Y142812D01*
X1904215D01*
G01X1903547Y155900D02*
Y153423D01*
X1903468Y153344D01*
Y148749D01*
X1907514Y144703D01*
Y143410D01*
X1908112Y142812D01*
X1909216D01*
G54D352*
G01X31599Y14409D02*
Y12351D01*
X33988Y9962D01*
Y8675D01*
G01X23728Y18731D02*
X25950D01*
X26772Y17909D01*
X28099D01*
G01X19964Y18793D02*
Y17136D01*
X21100Y16000D01*
G01X29850Y6112D02*
X27555D01*
X25152Y8515D01*
G01D02*
Y9875D01*
X25072Y9955D01*
Y11815D01*
G01X2871Y22791D02*
X5663Y25583D01*
Y29003D01*
X6163Y29503D01*
X8141D01*
G01X21100Y16000D02*
X25072Y12028D01*
Y11815D01*
G01X22058Y-8431D02*
Y-6941D01*
X23582Y-5417D01*
Y-1040D01*
X27584Y2962D01*
X29850D01*
G01X22058Y-8431D02*
Y-10946D01*
X21514Y-11490D01*
G01D02*
X22556Y-12532D01*
Y-13785D01*
X20732Y-15609D01*
Y-17983D01*
X19924Y-18791D01*
Y-18875D01*
G01X16550Y18300D02*
X17362Y17488D01*
Y16910D01*
X21572Y12700D01*
Y11815D01*
G01X2934Y26933D02*
Y28134D01*
X6075Y31275D01*
X8141D01*
G01X21652Y8515D02*
Y6348D01*
X23463Y4537D01*
X29850D01*
G01X21652Y8515D02*
Y10003D01*
X21572Y10083D01*
Y11815D01*
G01X22499Y-19381D02*
X21732Y-18614D01*
Y-16024D01*
X23650Y-14106D01*
Y-12854D01*
X25014Y-11490D01*
G01X25558Y-8431D02*
Y-10946D01*
X25014Y-11490D01*
G01X24582Y-3053D02*
Y-1491D01*
X27460Y1387D01*
X29850D01*
G01X25558Y-8431D02*
Y-6357D01*
X24582Y-5381D01*
Y-3053D01*
G01X4522Y57858D02*
Y58722D01*
X6670Y60870D01*
X8466D01*
G01X4522Y57858D02*
X4274Y57610D01*
X3410D01*
X2247Y56447D01*
X1826D01*
G01X1863Y59426D02*
X2016Y59579D01*
X3879D01*
X6942Y62642D01*
X8466D01*
G01X-9900Y489500D02*
Y489750D01*
X-9400Y490250D01*
X-6350D01*
X-1550Y495050D01*
Y496713D01*
G01X-9900Y486400D02*
Y489500D01*
G01X-13500D02*
Y486400D01*
G01X-9900Y493000D02*
X-7400D01*
X-6550Y493850D01*
G01X-13500Y493000D02*
X-9900D01*
G01X-6550Y493850D02*
X-5150Y495250D01*
Y496050D01*
X-2912Y498288D01*
X-1550D01*
G01X-4069Y488479D02*
Y485858D01*
X-4846Y485081D01*
G01D02*
Y482596D01*
X-4350Y482100D01*
G01X-4069Y488479D02*
Y488961D01*
X-868Y492162D01*
X-111D01*
X1013Y493286D01*
Y494150D01*
G01X2853Y488492D02*
X2711Y488350D01*
Y485075D01*
G01D02*
Y482105D01*
X2589Y481983D01*
G01X4163Y494150D02*
Y491636D01*
X2853Y490326D01*
Y488492D01*
G01X-569Y488479D02*
Y485858D01*
X-1346Y485081D01*
G01D02*
Y482746D01*
X-900Y482300D01*
G01X2588Y494150D02*
Y492188D01*
X-569Y489031D01*
Y488479D01*
G01X6353Y488492D02*
X6211Y488350D01*
Y485075D01*
G01D02*
Y482505D01*
X5689Y481983D01*
G01X5738Y494150D02*
Y490283D01*
X6353Y489668D01*
Y488492D01*
G01X-13000Y529400D02*
X-12300Y528700D01*
X-7400D01*
X-7300Y528800D01*
G01X-1959Y536159D02*
X-3906D01*
X-7444Y532621D01*
X-8385D01*
X-9287Y531719D01*
Y531604D01*
G01D02*
X-8344D01*
X-7300Y530560D01*
Y528800D01*
G01X-8300Y564000D02*
Y566629D01*
X-6566Y568363D01*
G01D02*
Y569499D01*
X-3906Y572159D01*
X-1959D01*
G01Y537931D02*
X-4064D01*
X-7623Y534372D01*
X-8462D01*
X-9291Y535201D01*
G01X-1959Y573931D02*
X-4064D01*
X-6748Y571247D01*
X-9206D01*
X-9283Y571324D01*
G01X98538Y341139D02*
X97848Y341829D01*
X94973D01*
G01X104070Y342980D02*
X100379D01*
X98538Y341139D01*
G01X103500Y304700D02*
X101500Y302700D01*
Y301500D01*
X102000Y301000D01*
Y298500D01*
G01X91710Y339200D02*
X90660D01*
X89860Y340000D01*
Y349241D01*
X88783Y350318D01*
X84148D01*
X83587Y350879D01*
Y352600D01*
G01X91710Y339200D02*
X94102D01*
X94973Y338329D01*
G01D02*
X98431D01*
X98680Y338080D01*
G01X91710Y342700D02*
Y344400D01*
X91110Y345000D01*
Y349680D01*
X88190Y352600D01*
X85161D01*
G01X91710Y342700D02*
X94102D01*
X94973Y341829D01*
G01X94519Y349333D02*
Y350140D01*
X90432Y354227D01*
Y356168D01*
X89687Y356913D01*
X87900D01*
G01X98563Y348721D02*
X101801D01*
X102040Y348960D01*
G01X94519Y349333D02*
X95131Y348721D01*
X98563D01*
G01X98540Y356310D02*
X100630D01*
X102160Y354780D01*
G01X94630Y356850D02*
X98000D01*
X98540Y356310D01*
G01X94630Y356850D02*
X93740D01*
X90527Y360063D01*
X87900D01*
G01X98520Y363830D02*
X101090D01*
X101770Y363150D01*
G01X94630Y363220D02*
X97910D01*
X98520Y363830D01*
G01X94630Y363220D02*
X94623Y363213D01*
X87900D01*
G01X101828Y371096D02*
X101524Y371400D01*
X98590D01*
G01X87900Y366362D02*
X90158D01*
X92100Y368304D01*
Y370200D01*
X92814Y370914D01*
X94710D01*
G01X98590Y371400D02*
X96886D01*
X96400Y370914D01*
X94710D01*
G01X96528Y387592D02*
X96516Y387604D01*
X93296D01*
G01D02*
X92394D01*
X90243Y385453D01*
Y381412D01*
X88965Y380134D01*
X86550D01*
X83587Y377171D01*
Y375400D01*
G01X122165Y378464D02*
X120595D01*
X116415Y374284D01*
X107400D01*
X105712Y375972D01*
G01D02*
X104500Y377184D01*
Y381609D01*
X98467Y387642D01*
X96578D01*
X96528Y387592D01*
G01X81700Y347000D02*
Y343900D01*
G01X80437Y352600D02*
Y350163D01*
X81700Y348900D01*
Y347000D01*
G01X87900Y347500D02*
X85700D01*
X85200Y347000D01*
G01X82012Y352600D02*
Y350688D01*
X85200Y347500D01*
Y347000D01*
G01X88000Y343900D02*
X85200D01*
G01X94519Y345833D02*
X97951D01*
X98563Y345221D01*
G01X87900Y355339D02*
Y355179D01*
X92710Y350369D01*
Y346680D01*
X93557Y345833D01*
X94519D01*
G01X98563Y345221D02*
X100801D01*
X101880Y346300D01*
G01X98540Y352810D02*
X101009D01*
X102060Y351759D01*
G01X94630Y353350D02*
X98000D01*
X98540Y352810D01*
G01X87900Y358488D02*
X90097D01*
X92180Y356405D01*
Y354901D01*
X93731Y353350D01*
X94630D01*
G01X98520Y360330D02*
X101540D01*
X101750Y360120D01*
G01X94630Y359720D02*
X97910D01*
X98520Y360330D01*
G01X94630Y359720D02*
X93490D01*
X91572Y361638D01*
X87900D01*
G01Y364787D02*
X90287D01*
X92914Y367414D01*
X94710D01*
G01X101965Y368296D02*
X101885D01*
X101489Y367900D01*
X98590D01*
G01X94710Y367414D02*
X96214D01*
X96700Y367900D01*
X98590D01*
G01X85161Y375400D02*
Y377330D01*
X87058Y379227D01*
X89473D01*
X91243Y380997D01*
Y382051D01*
X93296Y384104D01*
G01X96528Y384092D02*
X93308D01*
X93296Y384104D01*
G01X110032Y373284D02*
X106506D01*
X103314Y376476D01*
Y381086D01*
X100308Y384092D01*
X96528D01*
G01X122165Y218464D02*
X119965D01*
X119501Y218000D01*
X116996D01*
X115508Y216512D01*
G01X150000Y194850D02*
X150750Y195600D01*
X153200D01*
G01D02*
X156200D01*
G01X150000Y199850D02*
X150750Y199100D01*
X153200D01*
G01D02*
X156200D01*
G01X162800Y195600D02*
X159700D01*
G01X162788Y200650D02*
X161238Y199100D01*
X159700D01*
G01X116679Y210345D02*
Y212009D01*
X119016Y214346D01*
Y215094D01*
X120614Y216692D01*
X122165D01*
G01X115536Y213508D02*
X114567Y212539D01*
Y210808D01*
X115030Y210345D01*
X116679D01*
G01X122165Y250464D02*
X119965D01*
X117877Y248376D01*
X115497D01*
G01X116677Y242977D02*
Y243347D01*
X118795Y245465D01*
Y247165D01*
X120322Y248692D01*
X122165D01*
G01X116677Y242977D02*
X115043D01*
X114590Y243430D01*
Y244437D01*
X115525Y245372D01*
G01X115536Y277508D02*
X117944Y275100D01*
X119400D01*
G01D02*
Y279027D01*
X121065Y280692D01*
X122165D01*
G01Y282464D02*
X119965D01*
X119501Y282000D01*
X116996D01*
X115508Y280512D01*
G01X122165Y314464D02*
X119965D01*
X117661Y312160D01*
X115860D01*
X115508Y312512D01*
G01X115536Y309508D02*
X116629Y308415D01*
X118164D01*
G01D02*
Y308689D01*
X122165Y312690D01*
Y312692D01*
G01X113495Y338517D02*
Y339467D01*
X115536Y341508D01*
G01X122165Y346464D02*
X119965D01*
X119501Y346000D01*
X116996D01*
X115508Y344512D01*
G01X122165Y344692D02*
X118720D01*
X115536Y341508D01*
G01X117976Y372458D02*
Y374054D01*
X120614Y376692D01*
X122165D01*
G01X117976Y372458D02*
X114948D01*
X114122Y373284D01*
X110032D01*
G01X255018Y189873D02*
X255486Y190341D01*
X262345D01*
G01X299598Y401591D02*
X298788Y402401D01*
X290712D01*
X286764Y406349D01*
X284656D01*
X280656Y402349D01*
G01X272903Y171986D02*
X273263Y172346D01*
Y176996D01*
X274102Y177835D01*
X286742D01*
X290592Y181685D01*
G01X321679Y197141D02*
Y191972D01*
X309148Y179441D01*
X303853D01*
X302404Y177992D01*
X290975D01*
G01X317248Y190571D02*
X315178D01*
X306292Y181685D01*
X290592D01*
G01X299620Y197031D02*
X297574Y194985D01*
X266989D01*
X262345Y190341D01*
G01X270109Y271509D02*
X267859D01*
G01X266729Y273460D02*
X264179D01*
G01X283848Y427599D02*
X284340D01*
X296238Y415701D01*
G01X322192Y404571D02*
X308097Y418666D01*
X299323D01*
G01X310388Y160796D02*
Y161713D01*
X315292Y166617D01*
Y166767D01*
X334979Y186454D01*
Y194854D01*
G01X300529Y324160D02*
X298279D01*
G01X300529Y320260D02*
X298279D01*
G01X315498Y407291D02*
X307088Y415701D01*
X296238D01*
G01X336908Y395641D02*
Y409663D01*
X334198Y412373D01*
G01D02*
Y416819D01*
X316163Y434854D01*
Y438301D01*
X315621Y438843D01*
G01X469913Y266896D02*
X472163D01*
G01X469913Y262996D02*
X472163D01*
G01X475542Y261047D02*
X473292D01*
G01X472163Y259096D02*
X469913D01*
G01X522861Y218147D02*
X525111D01*
G01X509342Y311747D02*
X511592D01*
G01X505962Y309797D02*
X508212D01*
G01X509342Y300047D02*
X511592D01*
G01X509342Y303947D02*
X511592D01*
G01X484552Y311747D02*
X482302D01*
G01X484552Y315647D02*
X482302D01*
G01X511592Y288347D02*
X509342D01*
G01Y292247D02*
X511590D01*
X511592Y292245D01*
G01X600150Y117700D02*
X601900D01*
X603800Y115800D01*
X606600D01*
X607500Y116700D01*
G01X600150Y112700D02*
X601800D01*
X603700Y114600D01*
X606600D01*
X607500Y113700D01*
G01X617235Y247735D02*
X616900Y247400D01*
Y245800D01*
X617900Y244800D01*
Y241848D01*
X608552Y232500D01*
X593115D01*
X587400Y226785D01*
Y188015D01*
X615415Y160000D01*
X650700D01*
X653100Y157600D01*
Y157500D01*
X653091Y157445D01*
G01X614456Y244956D02*
X616329D01*
X616900Y244385D01*
Y242263D01*
X608137Y233500D01*
X592700D01*
X586400Y227200D01*
Y187600D01*
X615000Y159000D01*
X646600D01*
X648100Y157500D01*
X648091Y157445D01*
G01X546521Y290296D02*
X548771D01*
G01X546521Y294196D02*
X548771D01*
G01X617400Y115800D02*
X617897Y115303D01*
Y114395D01*
X617402Y113900D01*
X615838D01*
X614241Y115497D01*
X611501D01*
X611000Y115998D01*
Y116700D01*
G01X620054Y114096D02*
X619646D01*
X618250Y112700D01*
X615340D01*
X613743Y114297D01*
X611597D01*
X611000Y113700D01*
G01X605028Y119000D02*
X606228Y120200D01*
X607500D01*
G01X604977Y110200D02*
X607500D01*
G01X613602Y118047D02*
X611449Y120200D01*
X611000D01*
G01Y110200D02*
X612649D01*
X613602Y109247D01*
G01X660600Y170000D02*
X663100Y167500D01*
X663091Y167445D01*
G01Y172445D02*
Y172509D01*
X660600Y175000D01*
G01X641228Y251296D02*
X643308D01*
X646000Y253988D01*
Y255600D01*
G01X641100Y255400D02*
Y251424D01*
X641228Y251296D01*
G01X639000Y258900D02*
X636500D01*
X636400Y259000D01*
G01X633410Y269610D02*
X631322Y271698D01*
X628998D01*
X626000Y268700D01*
Y259546D01*
X627946Y257600D01*
X633500D01*
X634900Y259000D01*
X636400D01*
G01X639000Y255400D02*
X636500D01*
X636400Y255500D01*
G01X633410Y274610D02*
X631398Y272598D01*
X628625D01*
X625100Y269073D01*
Y259173D01*
X627573Y256700D01*
X633500D01*
X634700Y255500D01*
X636400D01*
G01X649500Y255600D02*
Y253250D01*
X649800Y252950D01*
Y252600D01*
G01X656450Y255913D02*
X652613D01*
X652300Y255600D01*
X649500D01*
G01X641100Y258900D02*
Y260300D01*
X640300Y261100D01*
Y262500D01*
G01X641100Y258900D02*
X641900D01*
X643100Y257700D01*
Y253700D01*
G01X646000Y259100D02*
Y260200D01*
X645100Y261100D01*
X642800D01*
G01X656450Y257488D02*
X652812D01*
X651200Y259100D01*
X649500D01*
G01D02*
X646000D01*
G01X659013Y253350D02*
Y251485D01*
X657700Y250172D01*
G01X660588Y250312D02*
Y253350D01*
G01X640500Y322000D02*
Y323551D01*
X640183Y323868D01*
X637486D01*
X637143Y323525D01*
Y322000D01*
G01X649819Y311857D02*
X648393D01*
X648066Y312184D01*
X646849D01*
X645137Y313896D01*
X644296D01*
X644000Y313600D01*
Y312000D01*
G01X649819Y313826D02*
X648426D01*
X647984Y313384D01*
X647347D01*
X645635Y315096D01*
X644425D01*
X644000Y315521D01*
Y317000D01*
G01X649819Y321702D02*
X648398D01*
X647629Y322471D01*
X646381D01*
X645602Y323250D01*
X644500D01*
X644000Y322750D01*
Y322000D01*
G01X649819Y323671D02*
X646879D01*
X644000Y326550D01*
Y327000D01*
G01X637143D02*
Y325518D01*
X637593Y325068D01*
X640076D01*
X640500Y325492D01*
Y327000D01*
G01Y312000D02*
Y313601D01*
X640229Y313872D01*
X637858D01*
X637561Y313575D01*
Y312000D01*
G01Y317000D02*
Y315522D01*
X638011Y315072D01*
X640076D01*
X640500Y315496D01*
Y317000D01*
G01X667800Y31550D02*
X667650Y31700D01*
Y34500D01*
G01X675235Y36797D02*
X669947D01*
X667650Y34500D01*
G01X675600Y145000D02*
Y144900D01*
G01X668091Y147445D02*
X668100Y147500D01*
X670600Y145000D01*
Y144900D01*
G01X668091Y152445D02*
X668100Y152500D01*
X670600Y150000D01*
G01X709959Y221841D02*
X711397D01*
X713700Y224144D01*
G01D02*
X715800Y226244D01*
Y227500D01*
G01X709959Y220069D02*
X712325D01*
X713800Y221544D01*
G01X669973Y301548D02*
Y300272D01*
X669706Y300005D01*
Y299194D01*
X670500Y298400D01*
X670800D01*
G01X668004Y301548D02*
Y300568D01*
X668506Y300066D01*
Y298906D01*
X668000Y298400D01*
G01X677849Y335948D02*
Y337249D01*
X678210Y337610D01*
Y338895D01*
X679203Y339888D01*
X680003D01*
X680884Y340769D01*
Y341505D01*
X680389Y342000D01*
X679000D01*
G01X679818Y335948D02*
Y337182D01*
X679410Y337590D01*
Y338397D01*
X679701Y338688D01*
X680501D01*
X682084Y340271D01*
Y341384D01*
X682700Y342000D01*
X684000D01*
G01X684219Y331547D02*
X685553D01*
X685850Y331250D01*
X686388D01*
X688825Y333687D01*
X690087D01*
X690500Y334100D01*
Y335500D01*
G01X684219Y329578D02*
X685352D01*
X685824Y330050D01*
X686886D01*
X689323Y332487D01*
X689961D01*
X690500Y331948D01*
Y330500D01*
G01X697352Y335500D02*
Y334050D01*
X696957Y333655D01*
X694369D01*
X694000Y334024D01*
Y335500D01*
G01X697352Y330500D02*
Y331847D01*
X696744Y332455D01*
X694354D01*
X694000Y332101D01*
Y330500D01*
G01X683091Y429925D02*
X682525D01*
X680370Y427770D01*
G01X680200Y432100D02*
X680266D01*
X683091Y434925D01*
G01X771773Y218464D02*
X769573D01*
X769109Y218000D01*
X766604D01*
X765116Y216512D01*
G01X765144Y213508D02*
X766947Y211705D01*
Y210570D01*
G01X771773Y216692D02*
X768328D01*
X765144Y213508D01*
G01X748700Y257500D02*
X747000D01*
X746575Y257075D01*
X745715D01*
X744070Y258720D01*
X744020D01*
G01X734161Y263600D02*
Y261491D01*
X735511Y260141D01*
X738598D01*
X738947Y260490D01*
X740697D01*
G01X744020Y258720D02*
Y259313D01*
X742843Y260490D01*
X740697D01*
G01X736900Y267913D02*
X738617D01*
X743540Y262990D01*
X743880D01*
X744505Y262365D01*
X745865D01*
X747159Y263659D01*
X747886D01*
G01X771773Y250464D02*
X769573D01*
X769109Y250000D01*
X768000D01*
X766512Y248512D01*
X765116D01*
G01X747886Y263659D02*
X750509D01*
X750900Y264050D01*
G01X754263Y254207D02*
X753663Y254807D01*
Y261287D01*
X750900Y264050D01*
G01X736900Y271063D02*
X742067D01*
X742128Y270902D01*
G01X745200Y270450D02*
X746300Y269350D01*
X748190D01*
X749090Y270250D01*
G01X742128Y270902D02*
X744748D01*
X745200Y270450D01*
G01X748700Y276350D02*
X747350D01*
X744800Y273800D01*
X739501D01*
X739088Y274213D01*
X736900D01*
G01X748700Y276350D02*
X751200D01*
X751700Y276850D01*
G01D02*
X754336D01*
X754846Y276340D01*
G01X742400Y281350D02*
X741850D01*
X740400Y279900D01*
Y278200D01*
X739300Y277100D01*
X738700D01*
X738438Y277362D01*
X736900D01*
G01X736000Y250500D02*
Y247200D01*
X734454Y245654D01*
G01X733500Y255000D02*
Y253000D01*
X736000Y250500D01*
G01X729437Y263600D02*
Y259663D01*
X733500Y255600D01*
Y255000D01*
G01X731012Y263600D02*
Y260788D01*
X734750Y257050D01*
X735750D01*
X737000Y255800D01*
Y255000D01*
G01X739400Y253400D02*
X738600D01*
X737000Y255000D01*
G01X739500Y250500D02*
Y247500D01*
G01X748700Y254000D02*
X747000D01*
X746475Y253475D01*
X745715D01*
X744020Y255170D01*
Y255220D01*
G01X732587Y263600D02*
Y261500D01*
X737097Y256990D01*
X740697D01*
G01X744020Y255220D02*
X742901D01*
X741131Y256990D01*
X740697D01*
G01X751363Y254207D02*
X752563Y255407D01*
Y260037D01*
X752050Y260550D01*
X750900D01*
G01X736900Y266339D02*
X738776D01*
X743125Y261990D01*
X743465D01*
X744455Y261000D01*
X746500D01*
X747341Y260159D01*
X747886D01*
G01X764341Y243042D02*
Y244705D01*
X765144Y245508D01*
G01X771773Y248692D02*
X768328D01*
X765144Y245508D01*
G01X747886Y260159D02*
X750509D01*
X750900Y260550D01*
G01X736900Y269488D02*
X739412D01*
X741498Y267402D01*
X742128D01*
G01X771773Y280692D02*
X770017D01*
X769020Y279695D01*
X767331D01*
X765144Y277508D01*
G01D02*
X765134Y277498D01*
Y274686D01*
G01X745200Y266950D02*
X746600Y268350D01*
X748090D01*
X748990Y267450D01*
G01X742128Y267402D02*
X744748D01*
X745200Y266950D01*
G01X748700Y272850D02*
X748008Y273542D01*
X745957D01*
X745215Y272800D01*
X739500D01*
X739338Y272638D01*
X736900D01*
G01X748700Y272850D02*
X751200D01*
X751700Y273350D01*
G01D02*
X754752D01*
X754758Y273356D01*
G01X736900Y275787D02*
X738587D01*
X738900Y276100D01*
X739715D01*
X741465Y277850D01*
X742400D01*
G01D02*
X744900D01*
X745400Y278350D01*
G01D02*
X746550Y279500D01*
X749100D01*
G01X771773Y282464D02*
X770434D01*
X769720Y281750D01*
X766354D01*
X765116Y280512D01*
G01X771773Y314464D02*
X769573D01*
X769109Y314000D01*
X767500D01*
X766012Y312512D01*
X765116D01*
G01X742400Y281350D02*
X744900D01*
X745400Y281850D01*
G01D02*
X749350D01*
X749800Y282300D01*
G01X737750Y295500D02*
Y292500D01*
G01Y298894D02*
Y295500D01*
G01X732587Y286400D02*
Y288956D01*
X736131Y292500D01*
X737750D01*
G01X736900Y282087D02*
X739157D01*
X743070Y286000D01*
G01D02*
X744976D01*
X745026Y286050D01*
X746870D01*
G01X751578Y285171D02*
X750699Y286050D01*
X746870D01*
G01X736900Y283661D02*
X737661D01*
X740199Y286199D01*
Y287485D01*
X742214Y289500D01*
X743070D01*
G01D02*
X744601Y291031D01*
Y295441D01*
X747470Y298310D01*
Y307130D01*
X742900Y311700D01*
X740533D01*
X739200Y313033D01*
Y314212D01*
X737912Y315500D01*
G01X746870Y289550D02*
X745501Y290919D01*
Y295068D01*
X748370Y297937D01*
Y307503D01*
X743273Y312600D01*
X740906D01*
X740100Y313406D01*
Y314126D01*
X741512Y315538D01*
G01X765144Y309508D02*
X765582Y309070D01*
Y307088D01*
G01X771773Y312692D02*
X768328D01*
X765144Y309508D01*
G01Y341508D02*
X767421D01*
X768367Y340562D01*
G01X741250Y295500D02*
Y292500D01*
G01Y295500D02*
Y298856D01*
G01Y292500D02*
Y292072D01*
X739956Y290778D01*
Y290698D01*
X738118Y288860D01*
X734661D01*
X734161Y288360D01*
Y286400D01*
G01X771773Y346464D02*
X769573D01*
X769109Y346000D01*
X766604D01*
X765116Y344512D01*
G01X771723Y378464D02*
X769523D01*
X768751Y377692D01*
X767677D01*
X766732Y376747D01*
X764131D01*
G01X771773Y344692D02*
X768328D01*
X765144Y341508D01*
G01X764159Y373743D02*
X765115Y372787D01*
X768059D01*
G01X771723Y376692D02*
X768092D01*
X765143Y373743D01*
X764159D01*
G01X804200Y195600D02*
X799300D01*
G01X804200D02*
X807200D01*
G01X804200Y199100D02*
X799300D01*
G01X804200D02*
X807200D01*
G01X810700Y195600D02*
X813700D01*
G01X810700Y199100D02*
X813500D01*
X813700Y198900D01*
G01X805367Y407400D02*
X806150D01*
X806250Y407500D01*
X809000D01*
G01D02*
X812000D01*
G01X809000Y404000D02*
X812000D01*
G01X805600Y403900D02*
X806450D01*
X806550Y404000D01*
X809000D01*
G01X904626Y189873D02*
X905094Y190341D01*
X911953D01*
G01X949206Y401591D02*
X948396Y402401D01*
X940320D01*
X936372Y406349D01*
X934264D01*
X930264Y402349D01*
G01X922511Y171986D02*
X922871Y172346D01*
Y176996D01*
X923710Y177835D01*
X936350D01*
X940200Y181685D01*
G01X959996Y160796D02*
Y161713D01*
X964900Y166617D01*
Y166767D01*
X967983Y169850D01*
G01X940583Y177992D02*
X952012D01*
X953461Y179441D01*
X958756D01*
X971287Y191972D01*
Y197141D01*
G01X966856Y190571D02*
X964786D01*
X955900Y181685D01*
X940200D01*
G01X949228Y197031D02*
X947182Y194985D01*
X916597D01*
X911953Y190341D01*
G01X984587Y194854D02*
Y186454D01*
X967983Y169850D01*
G01X919717Y271509D02*
X917467D01*
G01X916337Y273460D02*
X913787D01*
G01X950137Y324160D02*
X947887D01*
G01X950137Y320260D02*
X947887D01*
G01X965106Y407291D02*
X956696Y415701D01*
X945846D01*
G01X971800Y404571D02*
X957705Y418666D01*
X948931D01*
G01X933456Y427599D02*
X933948D01*
X945846Y415701D01*
G01X983806Y412373D02*
Y416819D01*
X965771Y434854D01*
Y438301D01*
X965229Y438843D01*
G01X986516Y395641D02*
Y409663D01*
X983806Y412373D01*
G01X1119521Y266896D02*
X1121771D01*
G01X1119521Y262996D02*
X1121771D01*
G01X1122900Y261047D02*
X1125150D01*
G01X1119521Y259096D02*
X1121771D01*
G01X1145430Y261047D02*
X1147680D01*
G01X1142050Y259096D02*
X1144300D01*
G01X1155570Y309797D02*
X1157820D01*
G01X1134160Y311747D02*
X1131910D01*
G01X1134160Y315647D02*
X1131910D01*
G01X1185989Y311747D02*
X1188239D01*
G01X1158950D02*
X1161200D01*
G01X1196129Y290296D02*
X1198379D01*
G01X1196129Y294196D02*
X1198379D01*
G01X1158950Y300047D02*
X1161200D01*
G01X1158950Y303947D02*
X1161200D01*
G01X1158950Y288347D02*
X1161200D01*
G01X1158950Y292247D02*
X1161200D01*
G01X1194999Y342947D02*
X1192749D01*
G01X1250200Y122900D02*
Y121230D01*
X1251013Y120417D01*
X1251900D01*
G01Y110417D02*
Y107040D01*
X1251980Y106960D01*
G01X1255400Y116917D02*
X1257817D01*
X1257850Y116950D01*
G01Y113850D02*
X1257783Y113917D01*
X1255400D01*
G01X1251900Y116917D02*
X1250965Y115982D01*
X1249310D01*
X1248531Y115203D01*
G01D02*
X1247752Y114424D01*
Y113039D01*
X1246968Y112255D01*
X1246260D01*
X1245760Y112755D01*
Y113655D01*
X1245260Y114155D01*
X1241406D01*
G01Y109155D02*
X1245260D01*
X1245760Y109655D01*
Y110555D01*
X1246260Y111055D01*
X1247466D01*
X1248952Y112541D01*
Y113926D01*
X1249808Y114782D01*
X1251035D01*
X1251900Y113917D01*
G01X1255400Y120417D02*
X1257417D01*
X1257800Y120800D01*
G01X1255400Y110417D02*
Y108000D01*
G01X1327500Y51547D02*
X1327853Y51900D01*
X1330500D01*
G01X1342255Y50160D02*
X1341910D01*
X1341000Y49250D01*
X1333150D01*
X1330500Y51900D01*
G01X1327452Y55544D02*
X1327996Y55000D01*
X1330500D01*
G01X1317618Y147445D02*
X1317300Y147127D01*
Y142255D01*
X1318118Y141437D01*
X1319775D01*
X1320500Y142162D01*
Y145000D01*
G01X1317618Y152445D02*
X1317600Y152500D01*
X1318825Y151275D01*
X1323535Y149323D01*
X1324371Y148487D01*
X1325100Y146726D01*
Y145000D01*
G01X1312618Y167445D02*
X1312600Y167500D01*
X1315130Y164970D01*
Y164870D01*
G01X1312618Y172445D02*
X1312600Y172500D01*
X1315150Y169950D01*
X1315180D01*
G01X1302618Y157445D02*
X1302270D01*
X1299907Y159808D01*
G01X1297618Y157445D02*
Y157852D01*
X1295500Y159970D01*
G01X1335100Y427500D02*
X1332600Y430000D01*
X1332618Y429925D01*
G01Y434925D02*
X1332600Y435000D01*
X1335100Y432500D01*
G01X1374320Y43895D02*
X1377185D01*
X1378959Y42121D01*
Y34050D01*
X1377405Y32496D01*
X1376808D01*
X1376263Y33041D01*
X1375359D01*
G01X1383227Y4966D02*
X1382693Y5500D01*
X1380300D01*
X1380219Y5581D01*
G01D02*
X1380138Y5500D01*
X1379086D01*
X1378000Y4414D01*
Y2240D01*
X1376777Y1017D01*
X1375048D01*
G01X1379110Y45033D02*
X1378640Y44563D01*
Y43855D01*
X1379959Y42536D01*
Y33635D01*
X1377820Y31496D01*
X1376866D01*
X1376639Y31269D01*
X1375359D01*
G01X1375048Y-755D02*
X1376420D01*
X1380119Y2944D01*
X1380300D01*
G01X1347350Y53413D02*
X1344097Y50160D01*
X1342255D01*
G01X1374320Y43895D02*
Y44302D01*
X1376989Y46971D01*
G01X1346444Y46449D02*
Y44783D01*
X1347866Y43361D01*
G01X1346444Y46449D02*
Y47385D01*
X1347611Y48552D01*
X1348965D01*
X1349913Y49500D01*
Y50850D01*
G01X1348945Y40264D02*
X1347866Y41343D01*
Y43361D01*
G01X1359512Y42384D02*
X1361419D01*
X1362448Y43413D01*
G01X1356010Y42074D02*
X1359202D01*
X1359512Y42384D01*
G01X1356010Y42074D02*
X1355340D01*
X1353316Y44098D01*
Y44851D01*
X1353314Y44853D01*
Y48133D01*
X1353063Y48384D01*
Y50850D01*
G01X1351366Y43361D02*
Y40944D01*
X1351908Y40402D01*
G01X1349944Y46449D02*
Y44783D01*
X1351366Y43361D01*
G01X1351488Y50850D02*
Y49087D01*
X1349944Y47543D01*
Y46449D01*
G01X1359512Y45884D02*
X1362500D01*
X1362674Y46058D01*
G01X1354638Y50850D02*
Y48750D01*
X1354973Y48415D01*
Y46611D01*
X1356010Y45574D01*
G01X1359512Y45884D02*
X1359202Y45574D01*
X1356010D01*
G01X1377666Y391909D02*
X1380409D01*
X1380800Y392300D01*
G01X1388700Y394845D02*
X1384906D01*
G01D02*
X1383345D01*
X1380800Y392300D01*
G01X1377666Y390137D02*
X1381537D01*
X1383700Y392300D01*
G01X1383074Y581963D02*
X1383013D01*
X1380947Y579897D01*
X1379359D01*
G01X1385185Y585222D02*
Y582905D01*
X1384243Y581963D01*
X1383074D01*
G01X1379359Y578125D02*
X1381525D01*
X1382500Y579100D01*
G01X1379359Y611097D02*
X1381600D01*
X1382605Y612102D01*
G01D02*
X1383879Y613376D01*
Y615750D01*
G01X1379359Y609325D02*
X1382309D01*
X1382586Y609602D01*
G01X1472061Y501278D02*
Y502021D01*
X1470650Y503432D01*
G01X1473261Y501278D02*
Y502519D01*
X1471850Y503930D01*
G01X1432560Y554655D02*
X1430395D01*
X1426380Y550640D01*
Y550030D01*
X1425817Y549467D01*
X1424210D01*
G01X1432560Y554655D02*
X1436160D01*
G01X1432560Y558155D02*
Y561160D01*
G01X1424210Y551042D02*
Y552010D01*
X1430355Y558155D01*
X1432560D01*
G01X1436160D02*
Y561200D01*
G01X1447022Y546578D02*
X1446180Y545736D01*
Y543700D01*
G01X1446170D02*
X1446180D01*
G01D02*
Y541509D01*
X1447089Y540600D01*
X1448900D01*
G01X1449922Y546664D02*
Y543551D01*
X1452000Y541473D01*
Y540600D01*
G01D02*
X1454850D01*
X1455000Y540750D01*
G01D02*
X1458000D01*
G01X1451533Y527867D02*
X1452018D01*
X1456400Y532249D01*
Y533685D01*
X1457100Y534385D01*
Y536350D01*
X1458000Y537250D01*
G01X1453533Y532667D02*
X1454899D01*
X1455400Y533168D01*
Y534100D01*
X1456100Y534800D01*
Y536150D01*
X1455000Y537250D01*
G01X1421647Y553605D02*
Y555152D01*
X1422546Y556051D01*
X1424093D01*
X1426640Y558598D01*
Y559233D01*
G01D02*
Y560863D01*
X1425243Y562260D01*
G01X1418497Y553605D02*
Y556757D01*
X1419772Y558032D01*
Y559180D01*
G01D02*
Y561254D01*
X1418402Y562624D01*
G01X1420072Y553605D02*
Y555900D01*
X1423140Y558968D01*
Y559233D01*
G01X1421560Y563455D02*
X1423140Y561875D01*
Y559233D01*
G01X1416922Y553605D02*
Y555821D01*
X1416272Y556471D01*
Y559180D01*
G01D02*
Y562214D01*
X1415582Y562904D01*
G01X1507076Y134925D02*
X1509973D01*
X1510311Y135263D01*
X1513342D01*
X1514425Y134180D01*
G01X1507076Y136893D02*
X1509971D01*
X1509972Y136894D01*
X1510403Y136463D01*
X1512908D01*
X1514425Y137980D01*
G01X1516700Y409900D02*
X1517500D01*
X1518000Y410400D01*
Y411100D01*
X1517075Y412025D01*
G01X1525000Y416750D02*
X1528100D01*
X1529675Y418325D01*
G01X1517075Y412025D02*
X1516150Y411100D01*
Y410450D01*
X1516700Y409900D01*
G01X1491425Y415600D02*
X1493375Y414694D01*
G01X1487525Y415600D02*
X1489475Y414694D01*
G01Y412220D02*
X1491425Y411314D01*
G01X1485575Y412220D02*
X1487525Y411314D01*
G01X1491425Y442640D02*
X1493375Y443546D01*
G01X1487525Y442640D02*
X1489475Y443546D01*
G01Y439260D02*
X1491425Y440166D01*
G01X1485575Y439260D02*
X1487525Y440166D01*
G01X1491425Y429120D02*
X1492469D01*
X1493375Y428214D01*
G01X1487525Y429120D02*
X1488569D01*
X1489475Y428214D01*
G01X1491425Y435880D02*
X1493375Y436786D01*
G01X1487525Y435880D02*
X1489475Y436786D01*
G01Y425740D02*
X1491400Y424600D01*
G01X1485575Y425740D02*
X1487500Y424600D01*
G01X1487525Y422360D02*
X1489475Y421454D01*
G01X1491425Y422360D02*
X1493375Y421454D01*
G01X1526525Y430925D02*
X1524950Y429350D01*
G01X1505462Y434630D02*
X1505075Y432500D01*
G01X1505679Y620111D02*
X1506726Y621158D01*
Y623027D01*
G01X1509426Y616398D02*
Y617600D01*
X1508926Y618100D01*
X1507690D01*
X1505679Y620111D01*
G01X1473888Y615130D02*
Y616412D01*
X1472850Y617450D01*
X1471214D01*
X1470664Y618000D01*
X1470356D01*
G01D02*
Y620244D01*
X1468900Y621700D01*
G01X1508550Y619810D02*
X1509064D01*
X1511198Y617676D01*
Y616398D01*
G01X1475660Y615130D02*
Y616403D01*
X1472932Y619131D01*
G01X1542275Y418325D02*
X1540700Y416750D01*
G01X1545425Y415175D02*
X1543850Y416750D01*
G01X1545425Y418325D02*
X1544522Y419228D01*
X1543178D01*
X1542275Y418325D01*
G01X1543850Y416750D02*
X1542275Y415175D01*
G01X1540700Y416750D02*
X1542275Y415175D01*
G01X1529675Y418325D02*
X1530762Y417238D01*
X1531738D01*
X1532825Y418325D01*
G01X1537550Y416750D02*
X1539125Y418325D01*
G01X1534400Y416750D02*
X1535975Y418325D01*
G01X1552198Y623479D02*
X1550869Y622150D01*
Y618955D01*
X1552688Y617136D01*
Y615150D01*
G01X1551113D02*
X1549520D01*
X1546554Y618116D01*
X1546104D01*
Y618145D01*
X1546075D01*
G01X1573500Y619500D02*
Y617000D01*
G01X1567850Y612587D02*
X1568363D01*
X1572776Y617000D01*
X1573500D01*
G01X1577000D02*
Y619500D01*
G01X1558987Y615150D02*
Y617708D01*
X1561083Y619804D01*
Y620894D01*
G01D02*
Y623240D01*
X1560747Y623576D01*
G01X1569954Y620727D02*
Y622906D01*
X1569495Y623365D01*
G01X1565287Y615150D02*
Y616386D01*
X1566873Y617972D01*
X1568105D01*
X1569954Y619821D01*
Y620727D01*
G01X1557413Y615150D02*
Y618876D01*
X1557583Y619046D01*
Y620894D01*
G01D02*
Y623551D01*
X1557575Y623559D01*
G01X1563712Y615150D02*
Y616976D01*
X1566454Y619718D01*
Y620727D01*
G01D02*
Y623316D01*
X1566520Y623382D01*
G01X1612245Y95466D02*
Y96095D01*
X1617000Y100850D01*
Y109301D01*
X1618465Y110766D01*
G01X1626339Y115491D02*
X1623190D01*
X1621615Y113916D01*
G01X1625485Y494188D02*
X1623323Y492026D01*
X1622383D01*
G01D02*
X1620873D01*
X1620423Y492476D01*
X1619398D01*
G01X1622383Y495526D02*
X1619448D01*
X1619398Y495476D01*
G01X1621783Y498617D02*
X1621423D01*
X1619398Y496592D01*
Y495476D01*
G01X1657144Y241740D02*
X1657145D01*
Y241739D01*
X1687782Y211102D01*
X1689398D01*
X1693649Y206851D01*
X1695386D01*
X1696036Y207501D01*
X1697536D01*
X1698186Y206851D01*
X1710834D01*
X1724354Y193331D01*
X1829899D01*
X1832051Y191179D01*
Y186937D01*
G01X1661766Y235420D02*
X1687284Y209902D01*
X1688900D01*
X1693151Y205651D01*
X1710336D01*
X1723856Y192131D01*
X1827918D01*
X1828902Y191147D01*
Y186937D01*
G01X1838350Y204236D02*
Y199682D01*
X1837375Y198707D01*
Y197585D01*
X1838210Y196750D01*
X1848237D01*
X1849100Y197613D01*
Y207322D01*
X1842022Y214400D01*
X1838795D01*
X1838245Y213850D01*
X1829353D01*
X1826842Y216361D01*
X1824450D01*
X1823800Y215711D01*
X1822300D01*
X1821650Y216361D01*
X1820150D01*
X1819500Y215711D01*
X1818000D01*
X1817350Y216361D01*
X1815850D01*
X1815200Y215711D01*
X1813700D01*
X1813050Y216361D01*
X1811550D01*
X1810900Y215711D01*
X1809400D01*
X1808750Y216361D01*
X1789757D01*
X1789107Y215711D01*
X1787607D01*
X1786957Y216361D01*
X1785457D01*
X1784807Y215711D01*
X1783307D01*
X1782657Y216361D01*
X1781157D01*
X1780507Y215711D01*
X1779007D01*
X1778357Y216361D01*
X1776857D01*
X1776207Y215711D01*
X1774707D01*
X1774057Y216361D01*
X1772557D01*
X1771907Y215711D01*
X1770407D01*
X1769757Y216361D01*
X1768257D01*
X1767607Y215711D01*
X1766107D01*
X1765457Y216361D01*
X1763929D01*
X1761710Y214142D01*
X1730013D01*
X1728924Y215231D01*
X1720031D01*
X1717400Y212600D01*
X1691853D01*
X1682101Y222352D01*
X1679942D01*
X1670306Y231988D01*
G01X1835201Y204236D02*
Y199681D01*
X1836175Y198707D01*
Y197087D01*
X1837712Y195550D01*
X1848735D01*
X1850300Y197115D01*
Y207820D01*
X1842520Y215600D01*
X1838297D01*
X1837747Y215050D01*
X1829851D01*
X1827340Y217561D01*
X1763431D01*
X1761212Y215342D01*
X1730511D01*
X1729422Y216431D01*
X1719533D01*
X1716902Y213800D01*
X1692351D01*
X1682599Y223552D01*
X1680440D01*
X1676982Y227010D01*
G01X1902513Y197965D02*
X1902488Y197990D01*
X1902487D01*
X1901101Y199377D01*
X1901100D01*
Y218346D01*
X1898046Y221400D01*
X1876575D01*
X1871615Y216440D01*
X1850006D01*
X1845316Y221130D01*
X1761951D01*
X1759732Y218911D01*
X1731991D01*
X1730902Y220000D01*
X1716702D01*
X1714302Y217600D01*
X1693700D01*
X1676085Y235215D01*
X1674601D01*
X1670708Y239108D01*
Y249541D01*
X1665239Y255010D01*
Y273398D01*
X1662389Y276248D01*
Y280429D01*
X1659818Y283000D01*
X1657998D01*
X1657498Y283500D01*
Y284900D01*
G01X1899900Y206900D02*
Y217848D01*
X1897548Y220200D01*
X1894753D01*
X1894103Y219550D01*
X1892603D01*
X1891953Y220200D01*
X1890202D01*
X1889552Y219550D01*
X1888052D01*
X1887402Y220200D01*
X1877073D01*
X1872113Y215240D01*
X1849508D01*
X1844818Y219930D01*
X1762449D01*
X1760230Y217711D01*
X1731493D01*
X1730404Y218800D01*
X1717200D01*
X1714800Y216400D01*
X1693202D01*
X1675587Y234015D01*
X1674103D01*
X1670521Y237597D01*
X1670512D01*
X1670504Y237605D01*
Y237614D01*
X1669508Y238610D01*
Y249043D01*
X1664039Y254512D01*
Y272900D01*
X1661189Y275750D01*
Y279931D01*
X1659320Y281800D01*
X1657998D01*
X1657498Y281300D01*
Y279900D01*
G01X1657500Y259700D02*
X1657498Y259702D01*
Y260900D01*
X1656947Y261451D01*
X1654937D01*
X1654229Y260743D01*
Y244655D01*
X1657144Y241740D01*
G01X1657567Y264600D02*
X1657569D01*
Y263251D01*
X1656969Y262651D01*
X1654439D01*
X1653029Y261241D01*
Y244157D01*
X1661766Y235420D01*
G01X1670306Y231988D02*
X1656714Y245580D01*
Y250907D01*
X1660457Y254650D01*
Y270800D01*
X1659657Y271600D01*
X1657998D01*
X1657498Y271100D01*
Y269700D01*
G01X1676982Y227010D02*
X1657914Y246078D01*
Y250409D01*
X1661657Y254152D01*
Y271298D01*
X1660155Y272800D01*
X1657998D01*
X1657498Y273300D01*
Y274700D01*
G01X1800307Y17268D02*
Y14786D01*
X1801299Y13794D01*
Y9330D01*
X1800799Y8830D01*
X1799462D01*
G01X1804462D02*
X1803126D01*
X1802499Y9457D01*
Y13828D01*
X1803457Y14786D01*
Y17268D01*
G01X1790078Y11860D02*
X1790970D01*
X1791980Y12870D01*
Y14419D01*
X1790857Y15542D01*
Y17268D01*
G01X1795078Y11900D02*
X1794143D01*
X1793180Y12863D01*
Y14579D01*
X1794007Y15406D01*
Y17268D01*
G01Y30668D02*
Y34094D01*
X1794831Y34918D01*
Y35742D01*
X1793702Y36871D01*
X1792700D01*
G01X1797700Y36804D02*
X1796532D01*
X1796031Y36303D01*
Y35220D01*
X1797157Y34094D01*
Y30668D01*
G01X1803300Y39900D02*
X1805247Y37953D01*
Y37098D01*
X1804432Y36283D01*
Y34597D01*
X1803457Y33622D01*
Y30668D01*
G01X1808363Y40033D02*
X1806447Y38117D01*
Y36600D01*
X1805632Y35785D01*
Y34597D01*
X1806607Y33622D01*
Y30668D01*
G01X1809757Y17268D02*
Y14786D01*
X1810732Y13811D01*
Y13103D01*
X1809794Y12165D01*
X1808795D01*
G01X1812907Y17268D02*
Y14786D01*
X1811932Y13811D01*
Y13103D01*
X1812870Y12165D01*
X1813795D01*
G01X1812352Y36949D02*
X1813036D01*
X1814057Y35928D01*
Y34892D01*
X1812907Y33742D01*
Y30668D01*
G01X1817352Y36909D02*
X1816316D01*
X1815257Y35850D01*
Y34967D01*
X1816057Y34167D01*
Y30668D01*
G01X1836531Y97664D02*
X1834644D01*
X1834458Y97850D01*
X1833050D01*
G01X1808057Y573125D02*
Y572475D01*
X1807774Y572192D01*
X1806808D01*
X1805620Y573380D01*
X1804620D01*
X1804300Y573700D01*
X1800206D01*
G01X1808057Y570125D02*
Y570724D01*
X1807789Y570992D01*
X1806310D01*
X1805122Y572180D01*
X1804281D01*
X1803833Y571732D01*
X1800206D01*
G01X1838400Y92325D02*
Y96997D01*
X1837733Y97664D01*
X1836531D01*
G01X1839598Y104984D02*
X1838151D01*
X1837723Y104556D01*
X1836547D01*
G01X1839598Y101484D02*
X1836529D01*
X1836523Y101490D01*
G01X1839598Y101484D02*
X1840675Y100407D01*
Y94600D01*
G01X1841630Y454321D02*
X1842553Y453398D01*
Y451750D01*
X1845900Y448403D01*
Y447551D01*
X1844885Y446536D01*
Y441754D01*
G01X1848035D02*
Y446616D01*
X1847100Y447551D01*
Y448901D01*
X1843753Y452248D01*
Y453444D01*
X1844630Y454321D01*
G01X1838586Y460603D02*
X1838582Y460607D01*
Y465753D01*
X1839675Y466846D01*
Y468223D01*
X1839268Y468630D01*
X1837857D01*
G01X1841736Y460603D02*
Y465919D01*
X1840875Y466780D01*
Y468143D01*
X1841362Y468630D01*
X1842857D01*
G01X1905516Y190300D02*
Y192384D01*
X1905120Y192780D01*
Y195358D01*
X1902513Y197965D01*
G01X1903548Y190300D02*
Y192520D01*
X1903920Y192892D01*
Y194859D01*
X1899900Y198879D01*
Y206900D01*
G54D34*
X25122Y11815D03*
X741300Y295500D03*
G54D226*
X1466733Y591553D03*
X1502030Y597154D03*
G54D52*
X14812Y74840D03*
X14487Y43473D03*
X4387Y550129D03*
Y586129D03*
X128511Y262662D03*
Y230662D03*
Y294662D03*
Y326662D03*
Y358662D03*
Y390662D03*
X703613Y207871D03*
X778119Y230662D03*
Y262662D03*
Y326662D03*
Y294662D03*
Y358662D03*
X778069Y390662D03*
X1368702Y-12953D03*
X1369013Y19071D03*
X1371320Y377939D03*
X1373013Y565927D03*
Y597127D03*
G54D172*
X1252354Y276226D03*
G54D163*
X687527Y379176D03*
X679847Y402676D03*
X687527D03*
X695207D03*
Y379176D03*
X679847D03*
X692647D03*
X690087D03*
X684967D03*
X682407D03*
X692647Y402676D03*
X690087D03*
X684967D03*
X682407D03*
G54D181*
X1268614Y341717D03*
G54D280*
X1734413Y186937D03*
X1731264Y204236D03*
Y186937D03*
X1728114Y204236D03*
Y186937D03*
X1724965Y204236D03*
X1772209D03*
Y186937D03*
X1769059Y204236D03*
Y186937D03*
X1765909Y204236D03*
X1724965Y186937D03*
X1765909D03*
X1762760Y204236D03*
Y186937D03*
X1759610Y204236D03*
Y186937D03*
X1756461Y204236D03*
Y186937D03*
X1753311Y204236D03*
Y186937D03*
X1750161Y204236D03*
X1721815D03*
X1750161Y186937D03*
X1747012Y204236D03*
Y186937D03*
X1743862Y204236D03*
Y186937D03*
X1740713Y204236D03*
Y186937D03*
X1737563Y204236D03*
Y186937D03*
X1734413Y204236D03*
X1721815Y186937D03*
X1759646Y226756D03*
X1756496D03*
X1753347D03*
X1750197D03*
X1747047D03*
X1772244Y244105D03*
X1769095D03*
X1765945D03*
X1762795D03*
X1759646D03*
X1756496D03*
X1743898Y226756D03*
X1753347Y244105D03*
X1750197D03*
X1747047D03*
X1743898D03*
X1740748D03*
X1737599D03*
X1734449D03*
X1740748Y226756D03*
X1737599D03*
X1772244D03*
X1769095D03*
X1765945D03*
X1762795D03*
X1734449D03*
X1835201Y204236D03*
Y186937D03*
X1832051Y204236D03*
Y186937D03*
X1828902Y204236D03*
Y186937D03*
X1825752Y204236D03*
Y186937D03*
X1822602Y204236D03*
Y186937D03*
X1819453Y204236D03*
Y186937D03*
X1816303Y204236D03*
Y186937D03*
X1813154Y204236D03*
Y186937D03*
X1810004Y204236D03*
Y186937D03*
X1806854Y204236D03*
Y186937D03*
X1803705Y204236D03*
Y186937D03*
X1800555Y204236D03*
Y186937D03*
X1797406Y204236D03*
Y186937D03*
X1794256Y204236D03*
Y186937D03*
X1791106Y204236D03*
Y186937D03*
X1787957Y204236D03*
Y186937D03*
X1784807Y204236D03*
Y186937D03*
X1781658Y204236D03*
Y186937D03*
X1778508Y204236D03*
Y186937D03*
X1775358Y204236D03*
Y186937D03*
X1832087Y244105D03*
X1828937D03*
X1825788D03*
X1822638D03*
X1819488D03*
X1816339D03*
X1813189D03*
X1810040D03*
X1806890D03*
X1803740D03*
X1800591D03*
X1797441D03*
X1794292D03*
X1791142D03*
X1787992D03*
X1784843D03*
X1781693D03*
X1778543D03*
X1775394D03*
X1832087Y226756D03*
X1828937D03*
X1825788D03*
X1822638D03*
X1819488D03*
X1816339D03*
X1813189D03*
X1810040D03*
X1806890D03*
X1803740D03*
X1800591D03*
X1797441D03*
X1794292D03*
X1791142D03*
X1787992D03*
X1784843D03*
X1781693D03*
X1778543D03*
X1775394D03*
X1844650Y204236D03*
Y186937D03*
X1841500Y204236D03*
Y186937D03*
X1838350Y204236D03*
Y186937D03*
G54D307*
X1889906Y96662D03*
X1900406D03*
G54D325*
X1959476Y101596D03*
G54D154*
X708358Y63650D03*
X706390D03*
X704421D03*
X702453D03*
X700484D03*
X698516D03*
X696547D03*
X694579D03*
X692610D03*
X690642D03*
X708358Y549900D03*
X706390D03*
X704421D03*
X702453D03*
X700484D03*
X698516D03*
X696547D03*
X694579D03*
X692610D03*
X690642D03*
X1368558Y123600D03*
X1366590D03*
X1364621D03*
X1362653D03*
X1360684D03*
X1358716D03*
X1356747D03*
X1354779D03*
X1352810D03*
X1350842D03*
X1363358Y534200D03*
X1361390D03*
X1359421D03*
X1357453D03*
X1355484D03*
X1353516D03*
X1351547D03*
X1349579D03*
X1347610D03*
X1345642D03*
G54D334*
X1953940Y219803D03*
Y221771D03*
Y229645D03*
Y227677D03*
G54D127*
X384505Y622550D03*
X640875Y255400D03*
Y258900D03*
G54D253*
X1544000Y266500D03*
G54D43*
X20515Y31338D03*
X20840Y62705D03*
X10415Y537994D03*
Y573994D03*
X134539Y218527D03*
Y250527D03*
Y282527D03*
Y314527D03*
Y346527D03*
Y378527D03*
X697585Y220006D03*
X784147Y218527D03*
Y250527D03*
Y314527D03*
Y282527D03*
Y346527D03*
X784097Y378527D03*
X1362674Y-818D03*
X1362985Y31206D03*
X1365292Y390074D03*
X1366985Y578062D03*
Y609262D03*
G54D262*
X1625951Y340193D03*
X1639055D03*
Y346099D03*
X1625951D03*
G54D343*
X1960433Y213997D03*
Y235451D03*
G54D235*
X1475098Y397067D03*
Y385256D03*
Y393130D03*
Y389193D03*
Y401004D03*
Y404941D03*
Y420689D03*
Y428563D03*
Y432500D03*
Y440374D03*
Y463996D03*
Y460059D03*
Y456122D03*
Y452185D03*
Y448248D03*
Y444311D03*
Y412815D03*
Y408878D03*
Y416752D03*
Y424626D03*
Y436437D03*
Y467933D03*
Y479744D03*
Y475807D03*
Y471870D03*
X1579902Y393130D03*
Y397067D03*
Y389193D03*
Y385256D03*
Y401004D03*
Y412815D03*
Y456122D03*
Y460059D03*
Y408878D03*
Y404941D03*
Y448248D03*
Y452185D03*
Y444311D03*
Y440374D03*
Y416752D03*
Y432500D03*
Y428563D03*
Y436437D03*
Y424626D03*
Y420689D03*
Y463996D03*
Y467933D03*
Y479744D03*
Y471870D03*
Y475807D03*
G54D244*
X1589500Y-600D03*
X1730143Y594742D03*
G54D271*
X1667012Y-14488D03*
G54D70*
X42724Y644684D03*
Y644656D03*
Y654684D03*
Y654656D03*
X67724Y644684D03*
Y644656D03*
Y654684D03*
Y654656D03*
X221656Y644656D03*
X196656D03*
X231446Y644756D03*
Y644784D03*
X221656Y644684D03*
X196656D03*
X221656Y654656D03*
X196656D03*
X231446Y654756D03*
Y654784D03*
X221656Y654684D03*
X196656D03*
X256446Y644756D03*
Y644784D03*
Y654756D03*
Y654784D03*
X409240Y644564D03*
X384240D03*
X418914Y644486D03*
Y644514D03*
X409240Y644536D03*
X384240D03*
X409240Y654564D03*
X384240D03*
X418914Y654486D03*
Y654514D03*
X409240Y654536D03*
X384240D03*
X443914Y644486D03*
Y644514D03*
Y654486D03*
Y654514D03*
X596707Y644293D03*
X571707D03*
X596708Y644266D03*
X571708D03*
X596707Y654293D03*
X571707D03*
X596708Y654266D03*
X571708D03*
X606462Y644245D03*
X631462D03*
X606462Y644217D03*
X631462D03*
X606462Y654245D03*
X631462D03*
X606462Y654217D03*
X631462D03*
X912351Y644245D03*
X887351D03*
X912351Y644273D03*
X887351D03*
X912351Y654245D03*
X887351D03*
X912351Y654273D03*
X887351D03*
X922116Y644206D03*
X947116D03*
X922116Y644234D03*
X947116D03*
X922116Y654206D03*
X947116D03*
X922116Y654234D03*
X947116D03*
X1200877Y644262D03*
Y644234D03*
Y654262D03*
Y654234D03*
X1225877Y644262D03*
X1235614Y644236D03*
X1260614D03*
X1235614Y644264D03*
X1260614D03*
X1225877Y644234D03*
Y654262D03*
X1235614Y654236D03*
X1260614D03*
X1235614Y654264D03*
X1260614D03*
X1225877Y654234D03*
X1514375Y644292D03*
Y644264D03*
Y654292D03*
Y654264D03*
X1539375Y644292D03*
Y644264D03*
Y654292D03*
Y654264D03*
G54D109*
X170516Y149639D03*
Y182139D03*
X137907Y446215D03*
Y478715D03*
X782990Y154000D03*
Y121500D03*
X782984Y449000D03*
Y481500D03*
G54D118*
G01X334292Y13200D02*
X337642D01*
G01X373400Y593800D02*
X373550Y593650D01*
X376204D01*
G01X625430Y492550D02*
Y490100D01*
G01D02*
X625340Y490010D01*
Y485610D01*
X622740Y483010D01*
Y480510D01*
X621600Y479370D01*
X616930D01*
G01X632113Y496892D02*
X632930Y496075D01*
Y492550D01*
G01X625500Y472759D02*
Y474200D01*
X623400Y476300D01*
G01X625500Y472759D02*
Y469159D01*
G01X621930Y492550D02*
Y488050D01*
X620930Y487050D01*
X616930D01*
G01X634930D02*
X632250D01*
G01X629300Y490000D02*
X629430Y490130D01*
Y492550D01*
G01X970731Y552000D02*
X974350D01*
G01X961950Y589800D02*
X960200D01*
X959000Y591000D01*
X957500D01*
G01X983900Y13200D02*
X987250D01*
G01X1003108Y51000D02*
X1004449Y49659D01*
X1007370D01*
G01X1003108Y589800D02*
X1004542Y588366D01*
X1006406D01*
G01X983900Y552000D02*
X987250D01*
G01X1016778Y611759D02*
X1017521Y612502D01*
G01D02*
Y617610D01*
G01X1083116Y552000D02*
X1079758D01*
G01X1070976D02*
X1066758D01*
G01X1054308D02*
X1057792D01*
G01X1098300Y553100D02*
X1095800D01*
G01D02*
X1094700Y552000D01*
X1092116D01*
G01X1083108Y589800D02*
X1079758D01*
G01X1070242D02*
X1066758D01*
G01X1057792D02*
X1054308D01*
G01X1266200Y122500D02*
X1266370Y122670D01*
Y127670D01*
G01X1277230Y117570D02*
X1278830Y119170D01*
X1279550D01*
G01X1277660Y109450D02*
Y109780D01*
X1279550Y111670D01*
G01Y122670D02*
X1277100D01*
G01D02*
X1275930D01*
X1274050Y124550D01*
Y127670D01*
G01X1457814Y13466D02*
Y13566D01*
X1457815Y13567D01*
Y17283D01*
G01X1429469D02*
Y13466D01*
G01X1438918Y13533D02*
Y17283D01*
G01X1448367D02*
Y13533D01*
G01X1420019Y13466D02*
Y13566D01*
X1420020Y13567D01*
Y17283D01*
G01X1410571D02*
Y13170D01*
G01X1486162Y17283D02*
Y13500D01*
G01X1495611Y17283D02*
Y13466D01*
G01X1467264Y17283D02*
Y13533D01*
G01X1476712Y13466D02*
Y13566D01*
X1476713Y13567D01*
Y17283D01*
X324407Y9114D03*
X317714D03*
X307675Y17057D03*
Y28014D03*
X321061D03*
X324407D03*
X314368D03*
X331100D03*
Y17057D03*
X334446Y9114D03*
X354525Y28022D03*
X351179D03*
X344486D03*
X341140D03*
X334446Y28014D03*
X334447Y17057D03*
X311021Y9114D03*
X314368Y17057D03*
X324407D03*
X327754Y9114D03*
X321061Y17057D03*
X341140D03*
X337793Y9114D03*
X344486Y17057D03*
Y9122D03*
X347833D03*
X351179Y17057D03*
X354525Y9122D03*
X354526Y17057D03*
X317714Y46914D03*
Y35957D03*
X307928Y67802D03*
X307675Y54857D03*
X321061Y65814D03*
X324407D03*
X314368D03*
X331100D03*
X321061Y54857D03*
X327754Y35957D03*
Y46914D03*
X324407Y54857D03*
Y35957D03*
Y46914D03*
X314368Y54857D03*
X311021Y46914D03*
X331100Y54857D03*
X317714Y73757D03*
X327754D03*
X324407D03*
X354525Y65822D03*
X351179D03*
X344486D03*
X341140D03*
X334446Y46914D03*
X354526Y54857D03*
X354525Y46922D03*
X354526Y35957D03*
X351179Y54857D03*
X347833Y46922D03*
X344486D03*
Y35957D03*
Y54857D03*
X337793Y46914D03*
Y35957D03*
X341140Y54857D03*
X334447D03*
X347833Y73757D03*
X344486D03*
X337793D03*
X334447D03*
X354526D03*
X311021Y35957D03*
X334446Y65814D03*
X334447Y35957D03*
X347833D03*
X320784Y203219D03*
X330948Y201258D03*
X308198Y528863D03*
X317714Y536957D03*
Y547914D03*
Y585714D03*
X307675Y555857D03*
X307984Y566743D03*
X317714Y574757D03*
X324407Y585714D03*
X344486Y585722D03*
X327754Y536957D03*
X321061Y529014D03*
X334447Y555857D03*
X341140D03*
X337793Y547914D03*
X344486Y555857D03*
Y547922D03*
X347833D03*
X351179Y555857D03*
X354525Y547922D03*
X354526Y555857D03*
X331100D03*
X334446Y547914D03*
X311021D03*
X314368Y555857D03*
X324407Y547914D03*
Y555857D03*
X327754Y547914D03*
X321061Y555857D03*
X334446Y529014D03*
X341140Y529022D03*
X337793Y536957D03*
X347833D03*
X351179Y529022D03*
X354526Y536957D03*
X331100Y529014D03*
X311021Y536957D03*
X324407D03*
X311021Y574757D03*
X324407D03*
Y566814D03*
X327754Y574757D03*
X337793Y585714D03*
X347833Y585722D03*
X354525D03*
X334446Y585714D03*
X311021D03*
X327754D03*
X334446Y566814D03*
X341140Y566822D03*
X337793Y574757D03*
X344486D03*
X347833D03*
X351179Y566822D03*
X354526Y574757D03*
X354525Y566822D03*
X331100Y566814D03*
X334447Y574757D03*
X344486Y529022D03*
Y536957D03*
X354525Y529022D03*
X334447Y536957D03*
X324407Y529014D03*
X314368Y566814D03*
X321061D03*
X344486Y566822D03*
X307675Y593657D03*
X334447D03*
X341140D03*
X344486D03*
X351179D03*
X354526D03*
X331100D03*
X314368D03*
X324407D03*
X321061D03*
X361218Y28014D03*
X401376Y9121D03*
X404722D03*
X411416Y9122D03*
X404723Y28022D03*
X401377D03*
X411416D03*
X404723Y17057D03*
X408069Y17042D03*
X414763Y9122D03*
X398029Y17042D03*
X414762Y17058D03*
X364565Y28014D03*
X414762Y28021D03*
X364265Y46914D03*
X361518D03*
X411416Y46922D03*
X411415Y36058D03*
X404723Y65822D03*
X414763D03*
X404723Y54857D03*
X401377Y46922D03*
Y35957D03*
X414763Y54857D03*
X398029Y54842D03*
X404723Y46922D03*
X414763Y35957D03*
Y46922D03*
X408069Y54842D03*
X394684Y35957D03*
X401377Y65822D03*
X411416D03*
Y73757D03*
X401377D03*
X404723D03*
X414763D03*
X404723Y35957D03*
X401377Y529022D03*
X411416D03*
Y536957D03*
X411415Y547921D03*
X411416Y574757D03*
Y585722D03*
X401377Y566822D03*
X411416D03*
X414763Y585722D03*
X404723Y529022D03*
X408069Y555842D03*
X414763Y547922D03*
X404723D03*
X398029Y555842D03*
X414763Y555857D03*
X401376Y547922D03*
X404723Y555857D03*
Y536957D03*
X401377Y574757D03*
X404723Y566822D03*
Y585722D03*
X401377D03*
X394684Y574757D03*
X414763D03*
X404723D03*
X401377Y536957D03*
X414763D03*
Y566822D03*
X408069Y593642D03*
X398029D03*
X404723Y593657D03*
X414763D03*
X438187Y9120D03*
X428147D03*
X434840D03*
X421455Y9121D03*
X444880Y28022D03*
X421456D03*
Y17057D03*
X428149Y28022D03*
X434842Y28268D03*
X438187Y17059D03*
X424801Y17042D03*
X444880Y9122D03*
Y17059D03*
X431494Y17042D03*
X438189Y28022D03*
X421455Y46921D03*
X444880Y65822D03*
X421456D03*
X438189D03*
Y46922D03*
Y35957D03*
X431494Y54842D03*
X444880Y54859D03*
Y46922D03*
X428149Y35957D03*
Y46922D03*
X421456Y54857D03*
X434842Y46922D03*
Y35957D03*
X424801Y54842D03*
X438187Y54859D03*
X421456Y35957D03*
X434842Y65822D03*
X428149D03*
X421456Y73757D03*
X438189D03*
X428149D03*
X444882Y35957D03*
X434842Y73757D03*
X458640Y200596D03*
X421456Y585722D03*
X428149Y529022D03*
X434842D03*
X421456Y547922D03*
X428149Y566822D03*
X434842D03*
X438189Y536957D03*
X438187Y555859D03*
X424801Y555842D03*
X434842Y547922D03*
X421456Y555857D03*
X428149Y547922D03*
X444880D03*
Y555859D03*
X431494Y555842D03*
X438189Y547922D03*
X428149Y536957D03*
X444880Y585722D03*
X438189D03*
Y566822D03*
X434842Y574757D03*
X421456Y566822D03*
X428149Y574757D03*
X444882D03*
X438189D03*
X434842Y585722D03*
X428149D03*
X444882Y536957D03*
X434842D03*
X421456Y529022D03*
X444880Y566822D03*
Y593659D03*
X431494Y593642D03*
X424801D03*
X421456Y593657D03*
X438187Y593659D03*
X957283Y28014D03*
Y17057D03*
X970669Y28014D03*
X963976D03*
X967322Y9114D03*
X960629D03*
X963976Y17057D03*
X970669D03*
X957536Y67802D03*
X957283Y54857D03*
X970669D03*
X960629Y35957D03*
X963976Y54857D03*
X960629Y46914D03*
X967322Y35957D03*
Y73757D03*
X963976Y65814D03*
X970669D03*
X967322Y46914D03*
X970392Y203219D03*
X967322Y536957D03*
X957806Y528863D03*
X960629Y547914D03*
X967322Y574757D03*
X957283Y555857D03*
X957592Y566743D03*
X970669Y555857D03*
Y566814D03*
X963976Y555857D03*
X967322Y585714D03*
Y547914D03*
X960629Y585714D03*
X963976Y566814D03*
X960629Y574757D03*
Y536957D03*
X970669Y529014D03*
X957283Y593657D03*
X963976D03*
X970669D03*
X974015Y28014D03*
X994094Y28022D03*
X990748D03*
X1004133D03*
X1000787D03*
X984055Y17057D03*
X990748D03*
X987401Y9114D03*
X994094Y17057D03*
Y9122D03*
X997441D03*
X1000787Y17057D03*
X1004133Y9122D03*
X1004134Y17057D03*
X980708D03*
X984054Y9114D03*
X974015D03*
Y17057D03*
X977362Y9114D03*
X984054Y28014D03*
X980708D03*
X977362Y35957D03*
Y46914D03*
X974015Y54857D03*
X997441Y46922D03*
Y35957D03*
X994094Y46922D03*
Y35957D03*
Y54857D03*
X987401Y46914D03*
Y35957D03*
X990748Y54857D03*
X1004134D03*
Y35957D03*
X1004133Y46922D03*
X1000787Y54857D03*
X984054Y65814D03*
X990748Y65822D03*
X994094D03*
X1000787D03*
X1004133D03*
X980708Y65814D03*
X974015D03*
X987401Y73757D03*
X994094D03*
X997441D03*
X1004134D03*
X984055D03*
X974015D03*
X977362D03*
X974015Y35957D03*
Y46914D03*
X984055Y54857D03*
X980708D03*
X984054Y46914D03*
X984055Y35957D03*
X980556Y201258D03*
X977362Y536957D03*
X974015D03*
X984055D03*
X980708Y529014D03*
X977362Y547914D03*
X974015D03*
X984054D03*
X997441Y547922D03*
X994094D03*
X987401Y547914D03*
X997441Y585722D03*
X977362Y574757D03*
X974015Y555857D03*
Y566814D03*
Y574757D03*
X984055D03*
X980708Y555857D03*
Y566814D03*
X994094Y574757D03*
Y555857D03*
Y566822D03*
X990748Y555857D03*
Y566822D03*
X984055Y555857D03*
X984054Y566814D03*
X977362Y585714D03*
X1004133Y547922D03*
X1004134Y555857D03*
X1004133Y566822D03*
X1004134Y574757D03*
X1000787Y555857D03*
Y566822D03*
X1004133Y585722D03*
X974015Y529014D03*
X990748Y529022D03*
X987401Y536957D03*
X994094D03*
X997441D03*
X1000787Y529022D03*
X1004134Y536957D03*
X987401Y585714D03*
X994094Y585722D03*
X984054Y585714D03*
X974015D03*
X984054Y529014D03*
X997441Y574757D03*
X987401D03*
X994094Y529022D03*
X1004133D03*
X980708Y593657D03*
X984055D03*
X990748D03*
X994094D03*
X1000787D03*
X1004134D03*
X974015D03*
X1054331Y28022D03*
X1050985D03*
X1071064Y9122D03*
X1064371Y28022D03*
X1094488D03*
X1087797D03*
X1061024D03*
X1077757D03*
X1084450Y28098D03*
X1071064Y17057D03*
X1061024Y9122D03*
X1094488D03*
Y17059D03*
X1081102Y17042D03*
X1064371Y17057D03*
X1087797Y9122D03*
X1050985D03*
X1054331Y17057D03*
X1071064Y28022D03*
X1087795Y17059D03*
X1074409Y17042D03*
X1084450Y9122D03*
X1057677Y17042D03*
X1064371Y9122D03*
X1077757D03*
X1054331D03*
X1047637Y17042D03*
X1054331Y54857D03*
X1047637Y54842D03*
X1057677D03*
X1044292Y35957D03*
X1050985Y65822D03*
X1071064Y46922D03*
X1094490Y35957D03*
X1064371Y54857D03*
X1081102Y54842D03*
X1094488Y54859D03*
Y46922D03*
X1064371Y35957D03*
Y46922D03*
X1074409Y54842D03*
X1087795Y54859D03*
X1071064Y35957D03*
X1061024Y65822D03*
X1084450D03*
X1077757D03*
X1071064Y73757D03*
X1061024D03*
X1071064Y65822D03*
X1064371D03*
X1054331D03*
X1064371Y73757D03*
X1054331D03*
X1050985D03*
X1087797Y65822D03*
X1094488D03*
X1087797Y73757D03*
X1084450D03*
X1077757D03*
X1061024Y46922D03*
Y35957D03*
X1084450D03*
Y46922D03*
X1071064Y54857D03*
X1077757Y35957D03*
Y46922D03*
X1054331Y35957D03*
Y46922D03*
X1087797Y35957D03*
Y46922D03*
X1050985Y35957D03*
Y46922D03*
Y536957D03*
X1054331D03*
X1050984Y547922D03*
X1054331D03*
X1050985Y529022D03*
Y566822D03*
X1054331Y555857D03*
Y566822D03*
X1050985Y574757D03*
X1047637Y555842D03*
X1054331Y574757D03*
X1057677Y555842D03*
X1044292Y574757D03*
X1050985Y585722D03*
X1054331D03*
X1064371Y547922D03*
X1084450D03*
X1061024Y529022D03*
X1084450D03*
X1077757D03*
X1067716Y547907D03*
X1061024Y536957D03*
Y547922D03*
X1071064D03*
X1087797Y536957D03*
X1077757D03*
X1071064Y529022D03*
X1084450Y536957D03*
X1087797Y547922D03*
X1094488D03*
X1064371Y574757D03*
X1071064Y555857D03*
Y566822D03*
X1084450Y574757D03*
X1074409Y555842D03*
X1087795Y555859D03*
X1087797Y585722D03*
X1064371D03*
X1084450D03*
X1071064Y574757D03*
X1061024Y566822D03*
X1084450D03*
X1077757D03*
X1061024Y574757D03*
Y585722D03*
X1071064D03*
X1087797Y574757D03*
X1064371Y566822D03*
X1094488D03*
X1064371Y555857D03*
X1081102Y555842D03*
X1094488Y555859D03*
X1064371Y536957D03*
X1077757Y547922D03*
Y585722D03*
Y574757D03*
X1094488Y585722D03*
X1087797Y566822D03*
X1094490Y574757D03*
X1054331Y529022D03*
X1094490Y536957D03*
X1071064Y593657D03*
X1087795Y593659D03*
X1057677Y593642D03*
X1047637D03*
X1094488Y593659D03*
X1081102Y593642D03*
X1064371Y593657D03*
X1054331D03*
X1108248Y200596D03*
X1111631Y198327D03*
X1445454Y267304D03*
X1458102Y270402D03*
X1458052Y273603D03*
Y276753D03*
X1445454D03*
X1442304Y279902D03*
X1461400Y264700D03*
X1458052Y279902D03*
X1451753Y270454D03*
X1461202Y276753D03*
X1448603Y279902D03*
X1464351Y276753D03*
X1461202Y279902D03*
Y273603D03*
X1451753D03*
Y267304D03*
X1448603Y270454D03*
Y267304D03*
X1442303Y267303D03*
X1454902Y276753D03*
X1451753Y279902D03*
X1442303Y270454D03*
X1461300Y270400D03*
X1445454Y279902D03*
X1448603Y276753D03*
X1442304Y273603D03*
X1454902D03*
X1451753Y276753D03*
X1454902Y279902D03*
X1445454Y270454D03*
X1448603Y273603D03*
X1454902Y270454D03*
X1464424Y273676D03*
X1445454Y273603D03*
X1464351Y279902D03*
X1454902Y311397D03*
X1463610Y321329D03*
X1451753Y301948D03*
X1445454D03*
X1464351Y311397D03*
X1461202D03*
X1458052Y308247D03*
X1464351Y301948D03*
X1451753Y298798D03*
X1458052Y311397D03*
X1454902Y295649D03*
X1445454Y311397D03*
X1442304D03*
X1454902Y298798D03*
X1464351Y305098D03*
X1458052Y295649D03*
X1448603Y301948D03*
X1442304Y308247D03*
X1448603Y298798D03*
X1445454D03*
X1458052Y314546D03*
X1462776Y318200D03*
X1451753Y314546D03*
X1448603Y308247D03*
X1454902Y305098D03*
X1448603Y311397D03*
X1458051Y301949D03*
X1464351Y295649D03*
X1442304Y305098D03*
X1445454Y308247D03*
X1448603Y314546D03*
X1454928Y317723D03*
X1461202Y305098D03*
X1440910Y316693D03*
X1458052Y298798D03*
X1451753Y317696D03*
X1458052Y305098D03*
X1448603Y317696D03*
X1458400Y318500D03*
X1445454Y305098D03*
X1448603D03*
X1454902Y308247D03*
X1451753Y305098D03*
X1442303Y298799D03*
X1464351Y298798D03*
X1461202D03*
Y295649D03*
X1445528Y317772D03*
X1454902Y301948D03*
X1461202D03*
Y314546D03*
X1464350Y308247D03*
X1445427Y295624D03*
X1448577D03*
X1451751Y295649D03*
X1454902Y314546D03*
X1448603Y283053D03*
X1461202Y283052D03*
X1445454Y289351D03*
X1451753D03*
X1454902Y283052D03*
X1442304Y289350D03*
X1458052Y286202D03*
X1454902Y289351D03*
Y286202D03*
X1454751Y292651D03*
X1442304Y292499D03*
X1448603Y289351D03*
X1458052D03*
X1464351Y283052D03*
X1461202Y286202D03*
X1464351D03*
X1461202Y289351D03*
X1451754Y283053D03*
X1448603Y286202D03*
X1451753D03*
X1464351Y289351D03*
X1458051Y283051D03*
X1451753Y311397D03*
X1445427Y292526D03*
X1470649Y279902D03*
Y270454D03*
Y276753D03*
X1469829Y266909D03*
X1470649Y273603D03*
X1480098Y270454D03*
X1483247Y273603D03*
Y270454D03*
X1489546Y279902D03*
X1473798Y276753D03*
X1476948Y273603D03*
X1480098Y267304D03*
X1476948Y270454D03*
X1473798D03*
X1480098Y273603D03*
X1486397Y270454D03*
X1483247Y267304D03*
X1476948Y279902D03*
X1473798D03*
X1480098Y276753D03*
X1483247Y279902D03*
X1476948Y276753D03*
X1486574Y267127D03*
X1496030Y267665D03*
X1473798Y273603D03*
X1489546Y270454D03*
X1486397Y273603D03*
X1483247Y276753D03*
X1470649Y305098D03*
Y311397D03*
Y301948D03*
Y308247D03*
Y314546D03*
Y295649D03*
Y298798D03*
Y283052D03*
Y286202D03*
Y289351D03*
X1480098Y305098D03*
X1476949Y301949D03*
X1486397Y311397D03*
X1489546Y314546D03*
X1473798Y305098D03*
X1480098Y301948D03*
Y298798D03*
X1495651Y311350D03*
X1493400Y300800D03*
X1486397Y298798D03*
X1480098Y295649D03*
X1476948Y298798D03*
X1489546Y286202D03*
X1486397Y305098D03*
X1473798Y295649D03*
X1483247Y305098D03*
X1480098Y308247D03*
X1473798Y298798D03*
X1492696Y314546D03*
X1473798Y308247D03*
X1476948Y305098D03*
X1497509Y303120D03*
X1489546Y308247D03*
X1476948Y311397D03*
X1489546Y317696D03*
X1486397Y295649D03*
Y308247D03*
X1483247Y298798D03*
X1473798Y301948D03*
X1476948Y295649D03*
X1486396Y317696D03*
X1495699Y314546D03*
X1476948Y308247D03*
X1473798Y314546D03*
X1483247D03*
X1489546Y301948D03*
Y311397D03*
X1486397Y314546D03*
X1483247Y311397D03*
X1492700Y311376D03*
X1495300Y297300D03*
X1478524Y318900D03*
X1480098Y311397D03*
X1483247Y301948D03*
X1473798Y311397D03*
X1493500Y304400D03*
X1486397Y301948D03*
X1483247Y308247D03*
X1476948Y286202D03*
X1483247D03*
Y289351D03*
Y283052D03*
X1473798D03*
X1486397Y286202D03*
X1480098D03*
X1476948Y289351D03*
X1480098Y283052D03*
X1473798Y289351D03*
Y286202D03*
X1486397Y283052D03*
X1476949Y283051D03*
X1480098Y314546D03*
X1588176Y157600D03*
X1604000Y93925D03*
X1606470Y93759D03*
X1632574Y106107D03*
X1594565Y148720D03*
X1635750Y128240D03*
X1648393Y153280D03*
X1642150Y118660D03*
X1651536Y134388D03*
X1642087Y143837D03*
X1648386Y156435D03*
X1651532Y137534D03*
X1590569Y152464D03*
X1595390Y151778D03*
X1638938Y109192D03*
X1638250Y125750D03*
X1651536Y121790D03*
X1638938Y118641D03*
X1645378Y128378D03*
X1638902Y112305D03*
X1648430Y150163D03*
X1638937Y131239D03*
Y143837D03*
Y137538D03*
X1638938Y153286D03*
X1648387Y115491D03*
X1651536D03*
X1645237D03*
X1641770Y112340D03*
X1645237Y112341D03*
X1651536D03*
Y128089D03*
X1642087Y124940D03*
X1645237D03*
X1637363Y149484D03*
X1651536Y140687D03*
Y143837D03*
Y131239D03*
Y124939D03*
X1645237Y118640D03*
X1642087Y153286D03*
X1642084Y115494D03*
X1648387Y112341D03*
Y109191D03*
X1651536D03*
X1645237D03*
X1600182Y148562D03*
X1607401Y146947D03*
X1604292Y150137D03*
X1600148Y142262D03*
X1610645Y143783D03*
X1613741Y118640D03*
X1629489Y153286D03*
X1620040Y134388D03*
Y128089D03*
X1616891D03*
X1607441Y112341D03*
X1610591Y118640D03*
X1600490Y110766D03*
X1607441Y115491D03*
X1598190Y110711D03*
X1610591Y112341D03*
X1613741Y153286D03*
X1616848Y115449D03*
X1616890Y112341D03*
X1632638Y115491D03*
Y112341D03*
X1632615Y109215D03*
X1629489Y115491D03*
X1610591Y121790D03*
X1613741D03*
X1620100Y153300D03*
X1613741Y146987D03*
X1616891Y150137D03*
X1616900Y153200D03*
X1629489Y150136D03*
X1616891Y146987D03*
X1616893Y140782D03*
X1635788Y137538D03*
Y143837D03*
Y131239D03*
X1616891Y134389D03*
X1629489Y137538D03*
Y143837D03*
Y131239D03*
X1620040Y106042D03*
X1623189Y118640D03*
X1629489D03*
X1610793Y109190D03*
X1607441Y118640D03*
X1616891Y124939D03*
X1596220Y109470D03*
X1613741Y115491D03*
X1602717Y102240D03*
X1610591Y115491D03*
Y128089D03*
X1604292Y134388D03*
X1607441Y137538D03*
X1607239Y131358D03*
X1604292Y137538D03*
X1607441Y121790D03*
X1626339Y124940D03*
X1626313Y153312D03*
X1632638Y153286D03*
X1620100Y150200D03*
X1620040Y146987D03*
Y140687D03*
X1632639Y124940D03*
Y118640D03*
X1635788D03*
X1626364Y121765D03*
X1626339Y150136D03*
X1635788Y153286D03*
X1623190Y146987D03*
Y140687D03*
Y134388D03*
Y128089D03*
Y124940D03*
X1607441Y124939D03*
X1623200Y153100D03*
X1626300Y112300D03*
X1626339Y109191D03*
Y118651D03*
X1613741Y128089D03*
X1626339Y115491D03*
X1613741Y156436D03*
Y150137D03*
X1607441Y106042D03*
X1610591Y146987D03*
X1607441Y143837D03*
X1608000Y99400D03*
X1613741Y134389D03*
X1613690Y124990D03*
X1613741Y140688D03*
X1610591Y134389D03*
X1600900Y131900D03*
X1607441Y153286D03*
X1613741Y137538D03*
X1610591Y150137D03*
Y124939D03*
Y137538D03*
Y140688D03*
X1607441Y134389D03*
X1616900Y143880D03*
X1616890Y118641D03*
X1613741Y109191D03*
Y106042D03*
X1607441Y156436D03*
X1610591Y153286D03*
X1604169Y156407D03*
X1610591Y156436D03*
X1600148Y151711D03*
X1651536Y146988D03*
Y156435D03*
X1629489Y112341D03*
X1629487Y109280D03*
X1629400Y106131D03*
X1648320Y172690D03*
X1635788Y162735D03*
X1591950Y158250D03*
X1595042Y172184D03*
X1600490Y158010D03*
X1596427Y157975D03*
X1645237Y165884D03*
X1648387Y159585D03*
X1651536D03*
X1645151Y162649D03*
X1642101Y162749D03*
X1651536Y165884D03*
X1642088Y165885D03*
X1638938Y165884D03*
X1651536Y162735D03*
X1642087Y159585D03*
X1645237D03*
X1648326Y162674D03*
X1648386Y165885D03*
X1635788Y159585D03*
X1629489D03*
X1616890Y162735D03*
X1613741Y159585D03*
X1613650Y173750D03*
X1609222Y173389D03*
X1620041Y165885D03*
X1620006Y168956D03*
X1615900Y172800D03*
X1608731Y180819D03*
X1635788Y165885D03*
X1597642Y172184D03*
X1616891Y165885D03*
X1613741D03*
X1610591Y159585D03*
X1622217Y177809D03*
X1610591Y162735D03*
X1611500Y172900D03*
X1629489Y165884D03*
X1621942Y173237D03*
X1624966Y172936D03*
X1629489Y162735D03*
X1600490Y167459D03*
X1623276Y165798D03*
X1626339Y162735D03*
X1607441D03*
X1613741D03*
X1607442Y159585D03*
X1620040Y162735D03*
X1627998Y172854D03*
X1601142Y172185D03*
X1616890Y159585D03*
X1626339Y165884D03*
X1623189Y159585D03*
X1623250Y162611D03*
X1626339Y159585D03*
X1620040D03*
X1610591Y165885D03*
X1643662Y172609D03*
X1638938Y162735D03*
Y159585D03*
X1616286Y176515D03*
X1674685Y134217D03*
X1693625Y133220D03*
X1680402Y128652D03*
X1678127Y117293D03*
X1673883Y124308D03*
X1660985Y156435D03*
X1667348Y156500D03*
X1660985Y118640D03*
X1667284Y115491D03*
X1654686Y109191D03*
X1654673Y118628D03*
X1654685Y112341D03*
X1653111Y102240D03*
X1654685Y146987D03*
X1654686Y156436D03*
X1654678Y137530D03*
X1657835Y134389D03*
X1671000Y103000D03*
X1670434Y115491D03*
X1657835Y112341D03*
X1660985Y115491D03*
X1657835Y118640D03*
X1664135Y115491D03*
Y118640D03*
X1709000Y127200D03*
X1691207Y139891D03*
X1681586Y141438D03*
X1660986Y137538D03*
X1667238Y112387D03*
X1667284Y137537D03*
X1657835Y124940D03*
Y150136D03*
X1667284Y121790D03*
Y128089D03*
Y150136D03*
X1658154Y99400D03*
X1657835Y115491D03*
Y109191D03*
X1660985D03*
Y112341D03*
X1664134Y140688D03*
Y156436D03*
X1664135Y112341D03*
X1695236Y135788D03*
Y138938D03*
X1676886Y120038D03*
Y123188D03*
X1660985Y146987D03*
X1657836Y137538D03*
X1654686Y153288D03*
Y134389D03*
X1693586Y142438D03*
X1654686Y150138D03*
X1660985Y131239D03*
X1657835Y121790D03*
X1660985D03*
X1667284Y131239D03*
X1654685D03*
X1664135Y128089D03*
X1657836Y140688D03*
X1660985Y124939D03*
X1654685Y140687D03*
X1664135Y153286D03*
X1664136Y137538D03*
X1657836Y153288D03*
X1657835Y143837D03*
X1664135Y121790D03*
X1660985Y128089D03*
Y150137D03*
X1664186Y147038D03*
X1657835Y146987D03*
X1654685Y143837D03*
X1660985D03*
X1677386Y132788D03*
Y129638D03*
X1660985Y140688D03*
X1654686Y124940D03*
X1657835Y162735D03*
X1660985D03*
X1654685D03*
X1654638Y159685D03*
X1668213Y172608D03*
X1657835Y165884D03*
X1660985Y165885D03*
X1657835Y159585D03*
X1665063Y172608D03*
X1660985Y159585D03*
X1688207Y168972D03*
X1689785Y161180D03*
X1729444Y123782D03*
X1726294Y101785D03*
X1735912Y123750D03*
X1742212Y117451D03*
X1717014Y148950D03*
X1714114D03*
X1717014Y97550D03*
Y104850D03*
Y108000D03*
Y111150D03*
Y133200D03*
Y139500D03*
X1743500Y96400D03*
X1739064Y108000D03*
X1742214Y101700D03*
X1735914D03*
X1745364Y117450D03*
Y114300D03*
Y98550D03*
X1745363Y108004D03*
X1746189Y153250D03*
X1755089Y150750D03*
X1752189Y136750D03*
X1746189Y134777D03*
Y131624D03*
X1752389Y132250D03*
X1754189Y124250D03*
X1757689Y123850D03*
X1752889Y146250D03*
X1745364Y145800D03*
Y142650D03*
X1731903Y133712D03*
X1745500Y104500D03*
X1726464Y117450D03*
X1720164Y97550D03*
Y111150D03*
X1723314D03*
X1720164Y117451D03*
X1723314Y117450D03*
X1720164Y120600D03*
Y123750D03*
X1723314D03*
X1720164Y133200D03*
Y126800D03*
X1751800Y141700D03*
X1745768Y111743D03*
X1742214Y98550D03*
Y126900D03*
X1745364Y123750D03*
X1742214D03*
X1745364Y120600D03*
X1742214Y114300D03*
Y111150D03*
X1739064Y114300D03*
X1720164Y139500D03*
X1723314Y101700D03*
X1731789Y139450D03*
X1717014Y142650D03*
X1723314Y133200D03*
Y108000D03*
X1726464Y111150D03*
X1723314Y139500D03*
X1739064D03*
X1726464Y133200D03*
X1735914Y108000D03*
X1739064Y123750D03*
X1726464Y120600D03*
X1742214D03*
X1739064Y130050D03*
Y142650D03*
X1726464Y123750D03*
X1720164Y104850D03*
X1742214Y142650D03*
X1726464Y145800D03*
X1723314Y104850D03*
X1720164Y108000D03*
X1734989Y142750D03*
X1723314Y98550D03*
X1735914Y117450D03*
X1728789Y136250D03*
X1723264Y145850D03*
X1739064Y145800D03*
X1723314Y130050D03*
X1735914Y104850D03*
X1735989Y149050D03*
X1742214Y130050D03*
X1726539Y139450D03*
X1720164Y145800D03*
X1739064Y117450D03*
X1723314Y126900D03*
X1735989Y133250D03*
X1739064Y120600D03*
X1723314Y120601D03*
X1739064Y126900D03*
X1735914Y139500D03*
X1739064Y136350D03*
X1723314Y142650D03*
X1742214Y145800D03*
G54D190*
X1261381Y427008D03*
X1253042Y422650D03*
G54D208*
X1405750Y568569D03*
Y585891D03*
G54D16*
X-15354Y109095D03*
Y124843D03*
Y140591D03*
Y156339D03*
Y365236D03*
Y380984D03*
Y396732D03*
Y412480D03*
X22835Y101221D03*
X6299D03*
X-10236D03*
X17716Y109095D03*
X1181D03*
X22835Y116969D03*
X6299D03*
X1181Y124843D03*
X22835Y132717D03*
X1181Y140591D03*
X22835Y148465D03*
X6299D03*
X-10236D03*
X17716Y156339D03*
X1181D03*
X-10236Y116969D03*
X-4725D03*
X23228Y124843D03*
X17716D03*
X-10236Y132717D03*
X-4725D03*
X6299D03*
X11811D03*
X17716Y140591D03*
X23228D03*
X-9843Y156339D03*
X23228Y109095D03*
X6693D03*
Y124843D03*
X-9843Y109095D03*
Y124843D03*
X-4725Y101221D03*
X11811Y148465D03*
Y101221D03*
Y116969D03*
X28346Y101221D03*
Y116969D03*
Y132717D03*
X6693Y140591D03*
X-9843D03*
X28346Y148465D03*
X6693Y156339D03*
X-4725Y148465D03*
X23228Y156339D03*
X22835Y357362D03*
X6299D03*
X-10236D03*
X17716Y365236D03*
X1181D03*
X22835Y373110D03*
X6299D03*
X1181Y380984D03*
X22835Y388858D03*
X1181Y396732D03*
X22835Y404606D03*
X6299D03*
X-10236D03*
Y373110D03*
X-4725D03*
X23228Y380984D03*
X17716D03*
X-10236Y388858D03*
X-4725D03*
X6299D03*
X11811D03*
X17716Y396732D03*
X23228D03*
Y365236D03*
X6693D03*
Y380984D03*
X-9843Y365236D03*
Y380984D03*
X-4725Y357362D03*
X11811Y404606D03*
Y357362D03*
Y373110D03*
X28346Y357362D03*
Y373110D03*
Y388858D03*
X6693Y396732D03*
X-9843D03*
X28346Y404606D03*
X-4725D03*
X17716Y412480D03*
X1181D03*
X-9843D03*
X6693D03*
X23228D03*
G54D25*
G01X-6100Y464840D02*
X-8390Y467130D01*
X-14822D01*
X-16362Y465590D01*
Y462160D01*
G01X-14190Y473840D02*
X-15312D01*
X-16362Y474890D01*
Y478340D01*
G01X-18160Y522609D02*
X-18484Y522285D01*
Y518084D01*
X-17200Y516800D01*
G01X-16000Y534300D02*
Y532100D01*
X-17300Y530800D01*
G01X-16000Y570300D02*
Y565639D01*
X-17397Y564242D01*
G01X-1959Y577474D02*
X-5726D01*
X-6900Y576300D01*
X-10700D01*
X-13000Y574000D01*
X-17500D01*
G01X28871Y-20458D02*
X25838D01*
G01X12334Y27947D02*
Y26234D01*
X11200Y25100D01*
X10600D01*
G01X-1347Y23809D02*
X46D01*
X1068Y24831D01*
G01X31907Y-19337D02*
X30786Y-20458D01*
X28871D01*
G01X19400Y24944D02*
X18972D01*
X17649Y26267D01*
Y27947D01*
G01X15878D02*
Y25266D01*
X16400Y24744D01*
G01X8660Y27274D02*
X9333Y27947D01*
X10563D01*
G01X14106D02*
Y25251D01*
X13716Y24861D01*
G01X43536Y-19703D02*
Y-19102D01*
X45113Y-17525D01*
Y-16137D01*
G01X38227Y-20485D02*
X42754D01*
X43536Y-19703D01*
G01X40287Y-13102D02*
X39600Y-13789D01*
Y-17198D01*
X38298Y-18500D01*
X36244D01*
X35407Y-19337D01*
G01X35399Y-14906D02*
X35563Y-14742D01*
Y-12657D01*
G01X37410Y-16300D02*
X36752Y-16958D01*
X28871D01*
G01X602Y30502D02*
X4100Y34000D01*
X4699D01*
X5517Y34818D01*
X8141D01*
G01X25827Y-16958D02*
X28871D01*
G01X-1190Y53240D02*
X-1080Y53350D01*
Y57100D01*
G01X-1000Y78900D02*
Y81500D01*
G01X12659Y59314D02*
Y57659D01*
X11167Y56167D01*
X10925D01*
G01X19225Y56198D02*
Y56566D01*
X17974Y57817D01*
Y59314D01*
G01X8141Y36590D02*
X3990D01*
X3600Y36200D01*
G01X8466Y67957D02*
X6538D01*
X6181Y67600D01*
X6173D01*
X4473Y65900D01*
X3100D01*
G01X16203Y59314D02*
Y56633D01*
X16625Y56211D01*
G01X10888Y59314D02*
X10025D01*
X9025Y58314D01*
Y58267D01*
X8988D01*
G01X8141Y41905D02*
X6460D01*
X5460Y42905D01*
Y50870D01*
X5670Y51080D01*
G01X14025Y56211D02*
X14431Y56617D01*
Y59314D01*
G01X8141Y38361D02*
X3526D01*
X3472Y38307D01*
X1572D01*
G01X5834Y69234D02*
X5026D01*
X3892Y68100D01*
X1382D01*
G01X-1470Y63910D02*
X4690D01*
X6965Y66185D01*
X8466D01*
G01X2940Y41740D02*
X2960D01*
X4567Y40133D01*
X8141D01*
G01X5600Y71700D02*
X5800Y71500D01*
X8466D01*
G01X63600Y163400D02*
X35801D01*
X28740Y156339D01*
G01X1500Y295000D02*
X-1758Y291742D01*
Y268783D01*
X-2Y267027D01*
X7088D01*
X8000Y267939D01*
Y272000D01*
G01D02*
X11000D01*
G01X5560Y280500D02*
Y276498D01*
X5120Y276058D01*
G01D02*
Y273364D01*
X4742Y272986D01*
Y270027D01*
G01X1242D02*
Y272505D01*
X2269Y273532D01*
G01D02*
Y276988D01*
X3000Y277719D01*
Y280500D01*
G01X10680Y290500D02*
Y288070D01*
X7995Y285385D01*
G01X3000Y290500D02*
Y293500D01*
X1500Y295000D01*
G01X47100Y327000D02*
X47500Y327400D01*
Y331200D01*
X43500Y335200D01*
Y340500D01*
X37000Y347000D01*
Y417263D01*
X43434Y423697D01*
Y426001D01*
X45933Y428500D01*
Y441763D01*
X47900Y443730D01*
X53839D01*
G01X59000Y327000D02*
Y327852D01*
X57126Y329726D01*
X51574D01*
X45250Y336050D01*
Y341050D01*
X38718Y347582D01*
Y416917D01*
X44956Y423155D01*
Y425543D01*
X47333Y427920D01*
Y428379D01*
X47336Y428382D01*
Y432866D01*
X50326Y435856D01*
X64839D01*
G01X53839Y427982D02*
X49382D01*
X46356Y424956D01*
Y422415D01*
X40417Y416476D01*
Y348483D01*
X46750Y342150D01*
Y339100D01*
X47850Y338000D01*
X52500D01*
X53025Y337475D01*
G01X-8682Y462160D02*
X-7712Y461190D01*
X-6104D01*
G01X9450Y451000D02*
Y460687D01*
X10365Y461602D01*
G01X23718Y460866D02*
Y461095D01*
X24512Y461889D01*
G01D02*
Y470955D01*
X23519Y471948D01*
X16404D01*
X15742Y472610D01*
Y472636D01*
X14500Y473878D01*
Y475500D01*
G01X11100Y446200D02*
X12812Y447912D01*
Y459274D01*
X15888Y462350D01*
Y469635D01*
X13742Y471781D01*
Y471807D01*
X11972Y473577D01*
Y475417D01*
G01X280Y524350D02*
X710Y523920D01*
Y521890D01*
G01X5000Y469000D02*
Y468344D01*
X3727Y467071D01*
X2407D01*
G01X43882Y499319D02*
Y504215D01*
X44050Y504383D01*
G01X-14190Y473840D02*
Y473742D01*
X-12370Y471922D01*
X-12330D01*
X-12298Y471890D01*
X-9240D01*
X-5690Y468340D01*
Y467840D01*
G01X-2390Y521840D02*
Y524300D01*
X-2430Y524340D01*
G01X-12690Y523090D02*
Y524390D01*
X-14400Y526100D01*
X-14800D01*
G01X33000Y505500D02*
X31365Y507135D01*
X28870D01*
G01X25388Y507977D02*
X25835Y507530D01*
X27263D01*
X27658Y507135D01*
X28870D01*
G01X25388Y507977D02*
X21740D01*
X21500Y507737D01*
G01X33000Y505500D02*
X36282Y502218D01*
Y499319D01*
G01X30428Y485956D02*
X33225D01*
X36224Y488955D01*
Y491552D01*
G01D02*
X32899Y494877D01*
Y499606D01*
X28870Y503635D01*
G01X47550Y504367D02*
Y495278D01*
X43824Y491552D01*
G01X2234Y570603D02*
Y569034D01*
X0Y566800D01*
G01X-10200Y558200D02*
X-10842Y557558D01*
Y554878D01*
G01X1040Y531218D02*
Y531640D01*
X2234Y532834D01*
Y534603D01*
G01X7549Y570603D02*
Y568851D01*
X9100Y567300D01*
Y566900D01*
G01X7549Y534603D02*
Y533151D01*
X7871Y532829D01*
Y532809D01*
X8427Y532253D01*
X8447D01*
X9400Y531300D01*
G01X-1959Y579246D02*
X-7554D01*
X-8200Y578600D01*
G01X5778Y534603D02*
Y531722D01*
X6200Y531300D01*
G01X6700Y528800D02*
Y530800D01*
X6200Y531300D01*
G01X5778Y570603D02*
Y567722D01*
X6200Y567300D01*
G01X-1959Y543246D02*
X-4351D01*
X-4662Y542935D01*
X-7599D01*
X-8318Y542216D01*
G01X463Y534603D02*
Y534000D01*
X-537Y533000D01*
X-2109D01*
X-3100Y533991D01*
G01X463Y570603D02*
X-465D01*
X-1568Y569500D01*
X-2500D01*
G01X-5091Y549518D02*
X-4134Y548561D01*
X-1959D01*
G01X4006Y534603D02*
Y532607D01*
X3600Y532201D01*
Y531300D01*
G01X-1959Y545017D02*
X-4559D01*
X-5241Y544335D01*
X-8644D01*
X-8862Y544117D01*
X-10947D01*
G01X-1959Y581017D02*
X-8462D01*
X-10579Y578900D01*
X-12600D01*
G01X1439Y553783D02*
X-240Y552104D01*
X-1959D01*
G01X-5681Y586369D02*
X-3873Y584561D01*
X-1959D01*
G01X4006Y570603D02*
Y568607D01*
X3600Y568201D01*
Y567300D01*
G01X-1959Y541474D02*
X-6381D01*
X-7655Y540200D01*
X-14771D01*
X-14971Y540000D01*
G01X-1959Y546789D02*
X-6410D01*
G01X-5719Y582948D02*
X-5560Y582789D01*
X-1959D01*
G01X58389Y-10601D02*
Y-13808D01*
G01D02*
X60096D01*
X61152Y-12752D01*
G01X57204Y4716D02*
X58063Y5575D01*
X62076D01*
G01X52793Y-1762D02*
X53382Y-1173D01*
G01X52906Y20334D02*
X52776Y20464D01*
X50050D01*
G01X61446Y18238D02*
X59546D01*
X57450Y20334D01*
X52906D01*
G01Y17426D02*
Y20334D01*
G01X47036Y-19703D02*
Y-18974D01*
X48613Y-17397D01*
Y-16137D01*
G01X47036Y-19703D02*
X47163Y-19830D01*
X49729D01*
X50586Y-20687D01*
G01X108077Y90364D02*
Y91794D01*
X109057Y92774D01*
G01X108077Y90364D02*
X109457D01*
X109500Y90321D01*
X111189D01*
G01X111093Y122603D02*
X108185D01*
X106900Y123888D01*
Y127687D01*
X107254Y128041D01*
G01D02*
X106841Y128454D01*
X104289D01*
G01X77650Y178150D02*
X79480Y176320D01*
Y168538D01*
X79900Y168118D01*
G01X69200Y171900D02*
X67100Y169800D01*
Y163400D01*
G01X69200Y171900D02*
X65400D01*
X61402Y175898D01*
Y177773D01*
G01X72900Y163000D02*
X68996D01*
X68596Y163400D01*
X67100D01*
G01X86078Y266950D02*
X83750D01*
X83300Y267400D01*
G01X86078Y266950D02*
X88250D01*
X88422Y267122D01*
X90750D01*
G01X73500Y275500D02*
X77000D01*
G01X80500D02*
X77000D01*
G01D02*
Y274600D01*
X79300Y272300D01*
G01X84000Y275500D02*
Y272500D01*
G01Y275500D02*
X87500D01*
G01X91600Y278700D02*
X91300Y279000D01*
X87500D01*
G01D02*
X84000D01*
G01X78395Y288750D02*
X79425Y287720D01*
X81268D01*
X84000Y284988D01*
Y279000D01*
G01X69200Y272600D02*
Y277700D01*
X65600Y281300D01*
Y283324D01*
X64100Y284824D01*
Y286601D01*
X64605Y287106D01*
Y288750D01*
G01X86078Y270450D02*
X90376D01*
X90778Y270852D01*
G01X69200Y272600D02*
X75200D01*
X78058Y269742D01*
X82542D01*
X83250Y270450D01*
X86078D01*
G01X73500Y279000D02*
Y280600D01*
X76800Y283900D01*
X77103D01*
G01X97800Y272900D02*
X95752Y270852D01*
X94278D01*
G01X97800Y272900D02*
Y276169D01*
X101550Y279919D01*
Y281400D01*
G01X94250Y267122D02*
X96922D01*
X102700Y272900D01*
X105300D01*
G01X113250Y272650D02*
X108750D01*
X108500Y272900D01*
X105300D01*
G01X99770Y325249D02*
X98391D01*
X97250Y326390D01*
Y327382D01*
G01X106200Y303900D02*
Y302700D01*
X105600Y302100D01*
X103500D01*
G01X53500Y307300D02*
X53700Y307500D01*
X56000D01*
G01X85300Y335750D02*
Y335600D01*
X84419Y334719D01*
Y332500D01*
G01X70700Y330349D02*
Y332106D01*
X70306Y332500D01*
X68500D01*
G01X92370Y327770D02*
Y326949D01*
X94938Y324381D01*
Y323467D01*
G01X91000Y285300D02*
X92064D01*
X92364Y285000D01*
X93500D01*
G01X91000Y285300D02*
Y282200D01*
G01Y297000D02*
X92400D01*
X93400Y296000D01*
G01X84000Y318520D02*
Y316083D01*
G01X63382Y325500D02*
X61400Y327482D01*
Y328000D01*
X61300Y328100D01*
Y328600D01*
G01X55500Y334500D02*
X54057D01*
X52804Y333247D01*
G01X55500Y323500D02*
X53000D01*
G01X58400Y314600D02*
X56750Y316250D01*
X55500D01*
G01X87500Y318500D02*
X84020D01*
X84000Y318520D01*
G01X93500Y285000D02*
X95000D01*
X96000Y286000D01*
Y287700D01*
G01X84000Y322020D02*
Y324542D01*
G01X53400Y298100D02*
X53600D01*
X55200Y296500D01*
X56000D01*
G01X84000Y324542D02*
X84419Y324961D01*
Y327900D01*
G01X55500Y327000D02*
X53100D01*
G01X62250Y291105D02*
X61900Y290755D01*
Y289200D01*
G01X68545Y288750D02*
Y281845D01*
X68300Y281600D01*
G01X70515Y288750D02*
Y281985D01*
X70900Y281600D01*
G01X87500Y297000D02*
Y300500D01*
G01Y297000D02*
X87485Y297015D01*
X80750D01*
G01X66575Y288750D02*
Y286125D01*
X66300Y285850D01*
G01X72485Y288750D02*
Y285317D01*
X72904Y284898D01*
G01X87500Y289000D02*
X84300D01*
G01X87500D02*
Y285300D01*
G01D02*
Y282200D01*
G01X80750Y291105D02*
X82855Y289000D01*
X84300D01*
G01X62250Y297015D02*
X58785D01*
X58600Y297200D01*
G01X76425Y288750D02*
Y287275D01*
X77450Y286250D01*
X79550D01*
X81755Y284045D01*
X81956D01*
X82050Y283951D01*
G01X96000Y291200D02*
X99200D01*
X100800Y292800D01*
G01X96000Y291200D02*
X94426Y292774D01*
Y293500D01*
G01X91000Y289000D02*
Y292400D01*
G01Y309500D02*
Y313500D01*
G01Y300500D02*
X92100D01*
G01X80750Y293075D02*
X82225D01*
X83800Y291500D01*
X90100D01*
X91000Y292400D01*
G01Y293500D02*
X94426D01*
G01X92100Y300500D02*
X93600Y302000D01*
Y306900D01*
X91000Y309500D01*
G01Y292400D02*
Y293500D01*
G01X94426D02*
X95500Y294574D01*
Y297100D01*
X92100Y300500D01*
G01X62250Y298985D02*
X59515D01*
X58700Y299800D01*
G01D02*
X58500Y300000D01*
X56000D01*
G01X74455Y288750D02*
Y286945D01*
X77000Y284400D01*
Y284003D01*
X77103Y283900D01*
G01X81324Y316119D02*
X80500Y316943D01*
Y318520D01*
G01X66000Y341500D02*
Y339100D01*
X65800Y338900D01*
G01X82500Y341400D02*
X80600D01*
X80350Y341150D01*
X80050D01*
X79950Y341050D01*
X78000D01*
G01D02*
Y339600D01*
X79200Y338400D01*
X80250D01*
X80550Y338700D01*
X81150D01*
G01X104600Y316602D02*
X103500Y317702D01*
Y319000D01*
G01X100000D02*
X103500D01*
G01X103200Y335190D02*
Y333550D01*
X104250Y332500D01*
G01X65941Y325500D02*
Y323941D01*
X64500Y322500D01*
X60000D01*
X59000Y323500D01*
G01X47100Y327000D02*
X47700Y326400D01*
Y324000D01*
X50200Y321500D01*
X57800D01*
X59000Y322700D01*
Y323500D01*
G01X76500Y324500D02*
X78500D01*
X79400Y325400D01*
G01X87500Y293500D02*
X85579D01*
X84866Y294213D01*
G01X80750Y295045D02*
X83854D01*
X84686Y294213D01*
X84866D01*
G01X76500Y324500D02*
Y326008D01*
X75600Y326908D01*
Y328600D01*
G01X65941Y332500D02*
Y334160D01*
X64301Y335800D01*
X62300D01*
X61000Y334500D01*
X59000D01*
G01X53025Y337475D02*
X54000Y336500D01*
X57900D01*
X59000Y335400D01*
Y334500D01*
G01X80750Y298985D02*
X84285D01*
X84300Y299000D01*
G01X75600Y332100D02*
X74235D01*
X73435Y331300D01*
Y329335D01*
X72300Y328200D01*
X70000D01*
X69700Y328500D01*
X65500D01*
X63382Y330618D01*
Y332500D01*
G01X75600Y332100D02*
Y335561D01*
X76000Y335961D01*
G01X68500Y325500D02*
X70112D01*
X71112Y324500D01*
X73000D01*
G01X62250Y300955D02*
X60545D01*
X58900Y302600D01*
X58800D01*
X58700Y302700D01*
X58600D01*
G01X88840Y324740D02*
X89220Y325120D01*
Y327730D01*
G01X91500Y321300D02*
X89882Y322918D01*
Y323698D01*
X88840Y324740D01*
G01X87500Y322000D02*
X88300D01*
X89455Y320845D01*
Y319017D01*
X90672Y317800D01*
X91500D01*
G01X94810Y318710D02*
X93900Y317800D01*
X91500D01*
G01X89220Y331230D02*
X92330D01*
X92370Y331270D01*
G01X86387Y332500D02*
X87950D01*
X89220Y331230D01*
G01X91185Y334900D02*
X92370Y333715D01*
Y331270D01*
G01X82450Y332500D02*
Y335500D01*
X82150Y335800D01*
G01X84650Y338700D02*
Y337858D01*
X83696Y336904D01*
X83254D01*
X82150Y335800D01*
G01X96840Y282050D02*
X97490Y281400D01*
X101550D01*
G01X54500Y354600D02*
X52100D01*
X52000Y354500D01*
G01X77300Y386614D02*
Y390600D01*
G01X80800Y386614D02*
Y388900D01*
X79100Y390600D01*
X77300D01*
G01X72000Y388600D02*
Y385500D01*
G01Y391500D02*
Y388600D01*
G01X59599Y365600D02*
X58590D01*
X57395Y366795D01*
G01X68200Y378800D02*
X69413Y377587D01*
G01X91996Y373774D02*
X95396D01*
G01X90507Y371087D02*
X91996Y372576D01*
Y373774D01*
G01X100153Y376214D02*
X97713Y373774D01*
X95396D01*
G01X91996Y377274D02*
X90884D01*
X89570Y375960D01*
Y373280D01*
G01X91996Y377274D02*
X93712Y378990D01*
Y380507D01*
G01X95396Y377274D02*
X97472Y379350D01*
Y380934D01*
G01X54500Y351500D02*
X52400D01*
X51900Y351000D01*
G01X77300Y383114D02*
X74800D01*
G01X118629Y381193D02*
X117788Y380352D01*
X115500D01*
X113972Y381880D01*
X106704D01*
X97720Y390864D01*
X88170D01*
X83000Y385694D01*
Y384100D01*
X82014Y383114D01*
X80800D01*
G01X117354Y90529D02*
X119325Y92500D01*
X120273D01*
G01X128450Y129700D02*
Y126461D01*
X127220Y125231D01*
X125077D01*
X122005Y128303D01*
X113156D01*
X112664Y128795D01*
G01X118935Y122603D02*
X126696D01*
X128450Y120849D01*
Y118700D01*
G01X109622Y128879D02*
X109703Y128798D01*
Y127345D01*
X110703Y126345D01*
X111093D01*
G01X124895Y212033D02*
X126358Y213496D01*
Y215136D01*
G01X129902D02*
Y212455D01*
X130324Y212033D01*
G01X124587Y215136D02*
X123659D01*
X122542Y214019D01*
G01X130150Y203950D02*
X129450D01*
X126600Y206800D01*
Y209200D01*
G01X128130Y215136D02*
Y212589D01*
X127754Y212213D01*
Y211853D01*
G01X113100Y266763D02*
Y269163D01*
G01X126358Y279136D02*
Y277358D01*
X124948Y275948D01*
X123074D01*
G01X123624Y240533D02*
Y241390D01*
X124750Y242516D01*
Y243750D01*
X126358Y245358D01*
Y247136D01*
G01X113100Y234713D02*
Y237022D01*
X112904Y237218D01*
G01X134324Y241333D02*
Y242826D01*
X131673Y245477D01*
Y247136D01*
G01X122165Y255779D02*
X119009D01*
X118230Y255000D01*
X116357D01*
X116000Y254643D01*
G01X122165Y223779D02*
X119009D01*
X118352Y223122D01*
X116492D01*
X116310Y222940D01*
G01X129902Y247136D02*
Y244455D01*
X130324Y244033D01*
G01X129902Y279136D02*
Y276455D01*
X130324Y276033D01*
G01X130424Y273300D02*
Y275933D01*
X130324Y276033D01*
G01X124587Y247136D02*
X123659D01*
X123198Y246675D01*
X122203D01*
G01X124587Y279136D02*
X123659D01*
X123194Y278671D01*
X122400D01*
G01X122165Y229094D02*
X119256D01*
X118225Y230125D01*
G01X119030Y261470D02*
X119406Y261094D01*
X122165D01*
G01X128130Y247136D02*
Y244130D01*
X127500Y243500D01*
G01X128130Y279136D02*
Y276945D01*
X127500Y276315D01*
Y275500D01*
G01X117080Y225330D02*
X117160Y225410D01*
X117457D01*
X117597Y225550D01*
X122165D01*
G01Y257550D02*
X117597D01*
X117063Y257016D01*
G01X122165Y254007D02*
X119537D01*
X118521Y252991D01*
X118008D01*
G01X122165Y222007D02*
X119537D01*
X118521Y220991D01*
X118008D01*
G01X115527Y227500D02*
X117589D01*
G01D02*
X119931D01*
X120109Y227322D01*
X122165D01*
G01X116342Y259500D02*
X117300D01*
G01D02*
X119250D01*
X119428Y259322D01*
X122165D01*
G01X110180Y280920D02*
X110817Y281557D01*
Y283595D01*
G01X108462Y316200D02*
Y314498D01*
X109770Y313190D01*
X109960D01*
G01X126358Y311136D02*
Y309588D01*
X124814Y308044D01*
X123301D01*
G01X113100Y330563D02*
Y333106D01*
G01X111000Y301000D02*
Y302396D01*
X112604Y304000D01*
X113000D01*
G01X121519Y336550D02*
Y337860D01*
X124159Y340500D01*
X125500D01*
X126358Y341358D01*
Y343136D01*
G01X122165Y319779D02*
X118505D01*
X117848Y319122D01*
X116479D01*
X116000Y318643D01*
G01X129902Y311136D02*
Y308455D01*
X130324Y308033D01*
G01X129902Y343136D02*
Y340554D01*
X129700Y340352D01*
Y340152D01*
G01X122165Y287779D02*
X119009D01*
X118352Y287122D01*
X116479D01*
X116000Y286643D01*
G01X124587Y311136D02*
X123659D01*
X123156Y310633D01*
X122493D01*
G01X122165Y293094D02*
X120641D01*
X119282Y294453D01*
G01X122165Y325094D02*
X120124D01*
X119223Y325995D01*
G01X128130Y311136D02*
Y308960D01*
X127500Y308330D01*
Y307500D01*
G01X122165Y289550D02*
X117597D01*
X117063Y289016D01*
G01X122165Y321550D02*
X117597D01*
X117063Y321016D01*
G01X128130Y343136D02*
Y341600D01*
X127800Y341270D01*
Y339800D01*
X127000Y339000D01*
G01X122165Y318007D02*
X119537D01*
X118521Y316991D01*
X118008D01*
G01X122165Y286007D02*
X119537D01*
X118521Y284991D01*
X118008D01*
G01X117320Y291322D02*
X116133D01*
X115143Y290332D01*
X114562D01*
G01X122165Y291322D02*
X117320D01*
G01X122165Y323322D02*
X117352D01*
G01X115681D02*
X117352D01*
G01X126358Y375136D02*
Y373398D01*
X125390Y372430D01*
X122630D01*
X122300Y372100D01*
G01X109866Y348586D02*
Y345304D01*
X110670Y344500D01*
G01X109640Y376070D02*
Y378230D01*
X110120Y378710D01*
G01X111000Y363700D02*
Y365300D01*
X112000Y366300D01*
X112600D01*
G01X122165Y383779D02*
X119009D01*
X118352Y383122D01*
X116479D01*
X116000Y382643D01*
G01X129902Y375136D02*
Y372768D01*
X130585Y372085D01*
G01X122165Y351779D02*
X119009D01*
X118352Y351122D01*
X116479D01*
X116000Y350643D01*
G01X124587Y343136D02*
X123659D01*
X123234Y342711D01*
X122423D01*
X122361Y342649D01*
G01X124587Y375136D02*
X123659D01*
X123239Y374716D01*
X122473D01*
G01X122165Y353550D02*
X117597D01*
X117063Y353016D01*
G01X118975Y390765D02*
X120646Y389094D01*
X122165D01*
G01Y385550D02*
X117597D01*
X117063Y385016D01*
G01X128130Y375136D02*
Y372300D01*
X127420Y371590D01*
G01X122165Y357094D02*
X120690D01*
X119690Y358094D01*
Y359030D01*
X118220Y360500D01*
G01X122165Y350007D02*
X119537D01*
X118521Y348991D01*
X118008D01*
G01X122165Y382007D02*
X119537D01*
X118723Y381193D01*
X118629D01*
G01X118635Y355611D02*
X118924Y355322D01*
X122165D01*
G01Y387322D02*
X118968D01*
X118290Y388000D01*
G01X159875Y407446D02*
X156446D01*
X156392Y407500D01*
G01D02*
X153392D01*
G01X156392Y404000D02*
X157618D01*
X158064Y404446D01*
X159875D01*
G01X156392Y404000D02*
X153392D01*
G01X167680Y408440D02*
X166686Y407446D01*
X163375D01*
G01X167640Y404842D02*
X167244Y404446D01*
X163375D01*
G01X113200Y405500D02*
X112044D01*
X110452Y407092D01*
G01D02*
X111960Y408600D01*
X113200D01*
G01X173700Y207870D02*
X173650Y207820D01*
G01D02*
Y202100D01*
G01X266729Y269560D02*
X261860D01*
X209750Y217450D01*
G01D02*
X194400Y202100D01*
X179150D01*
G01X270109Y216909D02*
X274619D01*
G01X270109Y213009D02*
X270400Y212508D01*
X271239Y211060D01*
G01X280249Y207159D02*
X277999D01*
G01X280249Y203260D02*
X277999D01*
G01X280249Y214960D02*
X277999D01*
G01X280249Y211060D02*
X277999D01*
G01X276869Y213009D02*
X274619D01*
G01X293769Y214960D02*
X291519D01*
G01X290389Y216909D02*
X288139D01*
G01X283629Y213009D02*
X281379D01*
G01X287009Y207159D02*
X284759D01*
G01X287009Y199360D02*
X284759D01*
G01X283629Y201309D02*
X281379D01*
G01X287009Y214960D02*
X284759D01*
G01X293769Y207159D02*
X291519D01*
G01X293769Y199360D02*
X291519D01*
G01X266729Y211060D02*
X268160D01*
X270109Y213009D01*
G01X291519Y199360D02*
X290389Y197409D01*
G01X271239Y211060D02*
X273489D01*
G01X270109Y232509D02*
X274619D01*
G01X270109Y224709D02*
X274619D01*
G01X270109Y236409D02*
X274619D01*
G01X273489Y265660D02*
X271239D01*
G01X273489Y269560D02*
X271239D01*
G01X273489Y273460D02*
X271239D01*
G01X290389Y252009D02*
X288139D01*
G01X283629D02*
X281379D01*
G01X290389Y255909D02*
X288139D01*
G01X293769Y253960D02*
X291519D01*
G01X293769Y261760D02*
X291519D01*
G01X283629Y259809D02*
X281379D01*
G01X287009Y265660D02*
X284759D01*
G01X293769Y277360D02*
X291519D01*
G01X293769Y265660D02*
X291519D01*
G01X290389Y271509D02*
X288139D01*
G01X287009Y253960D02*
X284759D01*
G01X276869Y263709D02*
X274619D01*
G01X276869Y275409D02*
X274619D01*
G01X276869Y267609D02*
X274619D01*
G01X280249Y253960D02*
X277999D01*
G01X276869Y259809D02*
X274619D01*
G01X276869Y255909D02*
X274619D01*
G01X280249Y269560D02*
X277999D01*
G01X280249Y277360D02*
X277999D01*
G01X293769Y257860D02*
X291519D01*
G01X293769Y269560D02*
X291519D01*
G01X290389Y275409D02*
X288139D01*
G01X287009Y273460D02*
X284759D01*
G01X287009Y277360D02*
X284759D01*
G01X283629Y271509D02*
X281379D01*
G01X283629Y275409D02*
X281379D01*
G01X276869Y252009D02*
X274619D01*
G01X293769Y218860D02*
X291519D01*
G01X276869Y240309D02*
X274619D01*
G01X280249Y250060D02*
X277999D01*
G01X280249Y230559D02*
X277999D01*
G01X276869Y228610D02*
X274619D01*
G01X276869Y220809D02*
X274619D01*
G01X280249Y234460D02*
X277999D01*
G01X276869Y248109D02*
X274619D01*
G01X276869Y244209D02*
X274619D01*
G01X293769Y230559D02*
X291519D01*
G01X293769Y222760D02*
X291519D01*
G01X293769Y234460D02*
X291519D01*
G01X287009Y246160D02*
X284759D01*
G01X283629Y220809D02*
X281379D01*
G01X283629Y232509D02*
X281379D01*
G01X290389D02*
X288139D01*
G01X287009Y234460D02*
X284759D01*
G01X290389Y236409D02*
X288139D01*
G01X287009Y226660D02*
X284759D01*
G01X293769Y238360D02*
X291519D01*
G01X293769Y226660D02*
X291519D01*
G01X293769Y250060D02*
X291519D01*
G01X283629Y240309D02*
X281379D01*
G01X293769Y242260D02*
X291519D01*
G01X273489Y238360D02*
X271239D01*
G01X293769Y246160D02*
X291519D01*
G01X266729Y226660D02*
X264179D01*
G01X266729Y222760D02*
X264142D01*
X264092Y222710D01*
G01X266729Y238360D02*
X264179D01*
G01X266729Y250060D02*
X264179D01*
G01X270109Y244209D02*
X267859D01*
G01X270109Y240309D02*
X267859D01*
G01X270109Y263709D02*
X267859D01*
G01X270109Y259809D02*
X267859D01*
G01X266729Y265660D02*
X264179D01*
G01X266729Y253960D02*
X264179D01*
G01X270109Y252009D02*
X267859D01*
G01X274619Y236409D02*
X276869D01*
G01X273489Y277360D02*
X271239D01*
G01X283629Y279310D02*
X281379D01*
G01X276869D02*
X274619D01*
G01X290389D02*
X288139D01*
G01X270109D02*
X267359D01*
G01X270109Y275409D02*
X267983D01*
X267392Y276000D01*
G01X266729Y269560D02*
X267859Y267609D01*
X270109D01*
G01X273489Y328060D02*
X271239D01*
G01X276869Y337809D02*
X274619D01*
G01X276869Y330009D02*
X274619D01*
G01X276869Y326110D02*
X274619D01*
G01X276869Y322209D02*
X274619D01*
G01X280249Y316360D02*
X277999D01*
G01X283629Y337809D02*
X281379D01*
G01X287009Y331960D02*
X284759D01*
G01X283629Y326110D02*
X281379D01*
G01X290389D02*
X288139D01*
G01X283629Y318309D02*
X281379D01*
G01X293769Y316360D02*
X291519D01*
G01X293769Y339760D02*
X291519D01*
G01X293769Y335860D02*
X291519D01*
G01X287009Y316360D02*
X284759D01*
G01X290389Y318309D02*
X288139D01*
G01X280249Y328060D02*
X277999D01*
G01X280249Y320260D02*
X277999D01*
G01X276869Y333909D02*
X274619D01*
G01X293769Y331960D02*
X291519D01*
G01X293769Y328060D02*
X291519D01*
G01X287009Y324160D02*
X284759D01*
G01X287009Y292959D02*
X284759D01*
G01X287009Y300760D02*
X284759D01*
G01X293769D02*
X291519D01*
G01X293769Y308560D02*
X291519D01*
G01X287009D02*
X284759D01*
G01X280249Y300760D02*
X277999D01*
G01X280249Y308560D02*
X277999D01*
G01X280249Y285160D02*
X277999D01*
G01X280249Y292959D02*
X277999D01*
G01X287009Y285160D02*
X284759D01*
G01X293769D02*
X291519D01*
G01X293769Y292959D02*
X291519D01*
G01X270109Y330009D02*
X267859D01*
G01X270109Y333909D02*
X267859D01*
G01X266729Y328060D02*
X264179D01*
G01X266729Y339760D02*
X264179D01*
G01X273489Y324160D02*
X271239D01*
G01X273489Y320260D02*
X271239D01*
G01X293769Y312460D02*
X291519D01*
G01X287009D02*
X284759D01*
G01X280249D02*
X277999D01*
G01X276869Y314409D02*
X274619D01*
G01X276869Y318309D02*
X274619D01*
G01X283629Y314409D02*
X281379D01*
G01X290389D02*
X288139D01*
G01X273489Y296860D02*
X270892D01*
G01X273489Y289060D02*
X270892D01*
G01X273489Y292959D02*
X270892D01*
G01X273489Y281260D02*
X271239D01*
G01X273489Y300760D02*
X270892D01*
G01X273489Y304660D02*
X270892D01*
G01X273489Y308560D02*
X270892D01*
G01X283629Y283209D02*
X281379D01*
G01X287009Y304660D02*
X284759D01*
G01X283629Y306609D02*
X281379D01*
G01X280249Y296860D02*
X277999D01*
G01X290389Y302709D02*
X288139D01*
G01X283629D02*
X281379D01*
G01X290389Y310509D02*
X288139D01*
G01X283629Y294909D02*
X281379D01*
G01X290389D02*
X288139D01*
G01X287009Y296860D02*
X284759D01*
G01X293769D02*
X291519D01*
G01X293769Y281260D02*
X291519D01*
G01X283629Y298809D02*
X281379D01*
G01X290389D02*
X288139D01*
G01X290389Y283209D02*
X288139D01*
G01X293769Y289060D02*
X291519D01*
G01X290389Y287109D02*
X288139D01*
G01X283629Y291009D02*
X281379D01*
G01X283629Y287109D02*
X281379D01*
G01X290389Y291009D02*
X288139D01*
G01X287009Y289060D02*
X284759D01*
G01X287009Y281260D02*
X284759D01*
G01X290389Y306609D02*
X288139D01*
G01X293769Y304660D02*
X291519D01*
G01X283629Y310509D02*
X281379D01*
G01X280249Y281260D02*
X277999D01*
G01X280249Y289060D02*
X277999D01*
G01X276869Y287109D02*
X274619D01*
G01X276869Y291009D02*
X274619D01*
G01X276869Y283209D02*
X274619D01*
G01X276869Y306609D02*
X274619D01*
G01X280249Y304660D02*
X277999D01*
G01X276869Y310509D02*
X274619D01*
G01X276869Y302709D02*
X274619D01*
G01X276869Y298809D02*
X274619D01*
G01X276869Y294909D02*
X274619D01*
G01X270109Y283209D02*
X267359D01*
G01X270109Y326110D02*
X267859D01*
G01X270109Y318309D02*
X267359D01*
G01X273489Y312460D02*
X272989Y311960D01*
X270892D01*
G01X273489Y316360D02*
X271139D01*
X270939Y316160D01*
G01X273489Y285160D02*
X271232D01*
X270892Y285500D01*
G01X270109Y322209D02*
X267601D01*
X267392Y322000D01*
G01X273489Y367060D02*
X277999D01*
G01X273489Y386560D02*
X277999D01*
G01X276869Y372909D02*
X274619D01*
G01X280249Y394359D02*
X277999D01*
G01X276869Y376809D02*
X274619D01*
G01X280249Y382660D02*
X277999D01*
G01X276869Y380709D02*
X274619D01*
G01X291519Y398260D02*
X293769D01*
G01X283629Y376809D02*
X281379D01*
G01X283629Y384609D02*
X281379D01*
G01X287009Y382660D02*
X284759D01*
G01X290389Y380709D02*
X288139D01*
G01X293769Y382660D02*
X291519D01*
G01X293769Y374860D02*
X291519D01*
G01X293769Y378760D02*
X291519D01*
G01X273489Y355360D02*
X271239D01*
G01X293769Y363160D02*
X291519D01*
G01X287009Y390460D02*
X284759D01*
G01X290389Y400209D02*
X288139D01*
G01X287009Y398260D02*
X284759D01*
G01X283629Y396309D02*
X281379D01*
G01X293769Y390460D02*
X291519D01*
G01X276869Y392410D02*
X274619D01*
G01X280249Y390460D02*
X277999D01*
G01X273489D02*
X271239D01*
G01X273489Y382660D02*
X271239D01*
G01X283629Y345609D02*
X281379D01*
G01X287009Y370959D02*
X284759D01*
G01X290389Y365109D02*
X288139D01*
G01X283629D02*
X281379D01*
G01X293769Y367060D02*
X291519D01*
G01X293769Y370959D02*
X291519D01*
G01X290389Y361209D02*
X288139D01*
G01X293769Y359260D02*
X291519D01*
G01X293769Y355360D02*
X291519D01*
G01X293769Y351460D02*
X291519D01*
G01X293769Y347560D02*
X291519D01*
G01X293769Y343660D02*
X291519D01*
G01X287009D02*
X284759D01*
G01X290389Y341709D02*
X288139D01*
G01X287009Y363160D02*
X284759D01*
G01X276869Y345609D02*
X274619D01*
G01X280249Y347560D02*
X277999D01*
G01X276869Y353409D02*
X274619D01*
G01X280249Y343660D02*
X277999D01*
G01X280249Y363160D02*
X277999D01*
G01X276869Y341709D02*
X274619D01*
G01X276869Y365109D02*
X274619D01*
G01X276869Y369010D02*
X274619D01*
G01X276869Y361209D02*
X274619D01*
G01X276869Y357309D02*
X274619D01*
G01X276869Y349509D02*
X274619D01*
G01X283629Y357309D02*
X281379D01*
G01X290389Y345609D02*
X288139D01*
G01X287009Y351460D02*
X284759D01*
G01X270109Y341709D02*
X267859D01*
G01X266729Y343660D02*
X264179D01*
G01X266729Y355360D02*
X264179D01*
G01X270109Y369010D02*
X267559D01*
G01X270109Y361209D02*
X267559D01*
G01X270109Y353409D02*
X267859D01*
G01X270109Y349509D02*
X267859D01*
G01X270109Y388509D02*
X267859D01*
G01X270109Y380709D02*
X267492D01*
G01X277999Y386560D02*
X280249D01*
G01X277999Y367060D02*
X280249D01*
G01X314368Y84735D02*
X315076Y85443D01*
Y86857D01*
X314541Y87392D01*
X314368D01*
G01X337708Y209109D02*
X338838Y211058D01*
G01X335458Y216909D02*
X337708D01*
G01X351228Y209109D02*
Y209931D01*
X352357Y211060D01*
G01X344468Y209109D02*
X348978D01*
G01X307289Y211060D02*
X305039D01*
G01X297149Y213009D02*
X294899D01*
G01X300529Y203260D02*
X298279D01*
G01X300529Y207159D02*
X298279D01*
G01X314048Y214960D02*
X311798D01*
G01X314048Y211060D02*
X311798D01*
G01X324188Y213009D02*
X325318Y211060D01*
G01X303909Y209109D02*
X301659D01*
G01X317428Y213009D02*
X315178D01*
G01X317428Y216909D02*
X315178D01*
G01X298279Y211060D02*
X300529D01*
G01X307289Y203260D02*
X308418Y201309D01*
G01X303909Y197409D02*
Y196817D01*
X301966Y194874D01*
X301648Y194841D01*
G01X300529Y199360D02*
X298279D01*
G01X310668Y213009D02*
X308418D01*
G01X314048Y203260D02*
X312918Y205210D01*
G01X317428Y209109D02*
X315178D01*
G01X330948Y213009D02*
X329818Y214958D01*
G01X293769Y199360D02*
X294899Y201309D01*
G01X338838Y211058D02*
X337708Y213009D01*
G01X294899Y201309D02*
X297149D01*
G01X341088Y203260D02*
X345598D01*
G01X347848Y214960D02*
X345598D01*
G01X354607D02*
X352357D01*
G01X354607Y203260D02*
X355737Y205210D01*
G01X345598Y203260D02*
X347848D01*
G01X334328Y269560D02*
X332078D01*
G01X337708Y252009D02*
X335458D01*
G01X337708Y259809D02*
X335458D01*
G01X341088Y253960D02*
X338838D01*
G01X337708Y267609D02*
X335458D01*
G01X341088Y265660D02*
X338838D01*
G01X347848Y269560D02*
X345598D01*
G01X354607Y261760D02*
X352357D01*
G01X347848Y273460D02*
X345598D01*
G01X344468Y271509D02*
X342218D01*
G01X344468Y275409D02*
X342218D01*
G01X344468Y279310D02*
X342218D01*
G01X344468Y255909D02*
X342218D01*
G01X344468Y259809D02*
X342218D01*
G01X344468Y267609D02*
X342218D01*
G01X351228Y263709D02*
X348978D01*
G01X347848Y265660D02*
X345598D01*
G01X344468Y263709D02*
X342218D01*
G01X334328Y242260D02*
X332078D01*
G01X334328Y250060D02*
X332078D01*
G01X334328Y218860D02*
X332078D01*
G01X334328Y234460D02*
X332078D01*
G01X341088Y246160D02*
X338838D01*
G01X341088Y242260D02*
X338838D01*
G01X337708Y248109D02*
X335458D01*
G01X341088Y234460D02*
X338838D01*
G01X337708Y224709D02*
X335458D01*
G01X341088Y238360D02*
X338838D01*
G01X337708Y236409D02*
X335458D01*
G01X351228Y248109D02*
X348978D01*
G01X344468Y220809D02*
X342218D01*
G01X347848Y238360D02*
X345598D01*
G01X354607D02*
X352357D01*
G01X351228Y220809D02*
X348978D01*
G01X310668Y252009D02*
X308418D01*
G01X330948D02*
X328698D01*
G01X303909Y267609D02*
X301659D01*
G01X314048Y269560D02*
X311798D01*
G01X320808D02*
X318558D01*
G01X307289D02*
X305039D01*
G01X327568D02*
X325318D01*
G01X327568Y265660D02*
X325318D01*
G01X297149Y275409D02*
X294899D01*
G01X297149Y263709D02*
X294899D01*
G01X300529Y277360D02*
X298279D01*
G01X320808D02*
X318558D01*
G01X317428Y279310D02*
X315178D01*
G01X324188Y275409D02*
X321938D01*
G01X314048Y277360D02*
X311798D01*
G01X300529Y253960D02*
X298279D01*
G01X307289Y277360D02*
X305039D01*
G01X307289Y273460D02*
X305039D01*
G01X327568D02*
X325318D01*
G01X330948Y267609D02*
X328698D01*
G01X330948Y259809D02*
X328698D01*
G01X303909Y275409D02*
X301659D01*
G01X310668D02*
X308418D01*
G01X300529Y265660D02*
X298279D01*
G01X303909Y259809D02*
X301659D01*
G01X324188D02*
X321938D01*
G01X314048Y261760D02*
X311798D01*
G01X310668Y255909D02*
X308418D01*
G01X310668Y259809D02*
X308418D01*
G01X324188Y255909D02*
X321938D01*
G01X327568Y253960D02*
X325318D01*
G01X307289Y265660D02*
X305039D01*
G01X310668Y263709D02*
X308418D01*
G01X324188D02*
X321938D01*
G01X297149Y224709D02*
X294899D01*
G01X297149Y248109D02*
X294899D01*
G01X300529Y246160D02*
X298279D01*
G01X297149Y244209D02*
X294899D01*
G01X327568Y242260D02*
X325318D01*
G01X327568Y230559D02*
X325318D01*
G01X327568Y234460D02*
X325318D01*
G01X300529Y218860D02*
X298279D01*
G01X300529Y234460D02*
X298279D01*
G01X314048Y222760D02*
X311798D01*
G01X314048Y218860D02*
X311798D01*
G01X307289Y230559D02*
X305039D01*
G01X310668Y224709D02*
X308418D01*
G01X310668Y228610D02*
X308418D01*
G01X307289Y226660D02*
X305039D01*
G01X320808Y238360D02*
X318558D01*
G01X314048D02*
X311798D01*
G01X324188Y236409D02*
X321938D01*
G01X310668D02*
X308418D01*
G01X303909Y228610D02*
X301659D01*
G01X317428Y232509D02*
X315178D01*
G01X324188Y220809D02*
X321938D01*
G01X317428D02*
X315178D01*
G01X320808Y218860D02*
X318558D01*
G01X320808Y226660D02*
X318558D01*
G01X300529D02*
X298279D01*
G01X307289Y218860D02*
X305039D01*
G01X297149Y228610D02*
X294899D01*
G01X310668Y232509D02*
X308418D01*
G01X327568Y226660D02*
X325318D01*
G01X327568Y222760D02*
X325318D01*
G01X330948Y232509D02*
X328698D01*
G01X330948Y220809D02*
X328698D01*
G01X327568Y250060D02*
X325318D01*
G01X310668Y240309D02*
X308418D01*
G01X317428D02*
X315178D01*
G01X303909D02*
X301659D01*
G01X320808Y242260D02*
X318558D01*
G01X307289Y246160D02*
X305039D01*
G01X303909Y248109D02*
X301659D01*
G01X320808Y246160D02*
X318558D01*
G01X307289Y250060D02*
X305039D01*
G01X310668Y244209D02*
X308418D01*
G01X324188Y248109D02*
X321938D01*
G01X341088Y250060D02*
X338838D01*
G01X354607Y277360D02*
X357057D01*
G01X354607Y273460D02*
X357057D01*
G01X347848Y277360D02*
X345598D01*
G01X351228Y279310D02*
X348978D01*
G01X351228Y271509D02*
X348978D01*
G01X351228Y275409D02*
X348978D01*
G01X354607Y265660D02*
X352357D01*
G01X301659Y279310D02*
X303909D01*
G01X310668D02*
X308418D01*
G01X297149D02*
X294899D01*
G01X351228Y267609D02*
X348978D01*
G01X354607Y269560D02*
X355952D01*
X357092Y270700D01*
G01X341088Y230559D02*
Y231379D01*
X342218Y232509D01*
G01X347848Y226660D02*
X345598D01*
G01X351228Y244209D02*
X348978D01*
G01X344468D02*
X342218D01*
G01X351228Y232509D02*
X348978D01*
G01X354607Y226660D02*
X352357D01*
G01X341088Y218860D02*
X338838D01*
G01X342218Y232509D02*
X344468D01*
G01Y252009D02*
X342218D01*
G01X344468Y248109D02*
X342218D01*
G01X334328Y312460D02*
X332078D01*
G01X334328Y339760D02*
X332078D01*
G01X334328Y331960D02*
X332078D01*
G01X341088Y312460D02*
X338838D01*
G01X341088Y316360D02*
X338838D01*
G01X341088Y339760D02*
X338838D01*
G01X337708Y330009D02*
X335458D01*
G01X341088Y331960D02*
X338838D01*
G01X347848Y320260D02*
X345598D01*
G01X344468Y314409D02*
X342218D01*
G01X344468Y318309D02*
X342218D01*
G01X344468Y322209D02*
X342218D01*
G01X344468Y333909D02*
X342218D01*
G01X351228D02*
X348978D01*
G01X347848Y335860D02*
X345598D01*
G01X344468Y330009D02*
X342218D01*
G01X347848Y331960D02*
X345598D01*
G01X354607Y335860D02*
X352357D01*
G01X347848Y339760D02*
X345598D01*
G01X344468Y326110D02*
X342218D01*
G01X347848Y328060D02*
X345598D01*
G01X347848Y324160D02*
X345598D01*
G01X334328Y300760D02*
X332078D01*
G01X334328Y292959D02*
X332078D01*
G01X334328Y281260D02*
X332078D01*
G01X341088Y300760D02*
X338838D01*
G01X337708Y310509D02*
X335458D01*
G01X341088Y292959D02*
X338838D01*
G01X337708Y283209D02*
X335458D01*
G01X341088Y281260D02*
X338838D01*
G01X344468Y310509D02*
X342218D01*
G01X344468Y283209D02*
X342218D01*
G01X320808Y312460D02*
X318558D01*
G01X327568D02*
X325318D01*
G01X303909Y337809D02*
X301659D01*
G01X317428Y330009D02*
X315178D01*
G01X303909D02*
X301659D01*
G01X310668D02*
X308418D01*
G01X300529Y328060D02*
X298279D01*
G01X300529Y331960D02*
X298279D01*
G01X307289D02*
X305039D01*
G01X310668Y333909D02*
X308418D01*
G01X310668Y337809D02*
X308418D01*
G01X307289Y328060D02*
X305039D01*
G01X320808Y320260D02*
X318558D01*
G01X310668Y326110D02*
X308418D01*
G01X297149Y333909D02*
X294899D01*
G01X324188Y330009D02*
X321938D01*
G01X324188Y337809D02*
X321938D01*
G01X327568Y339760D02*
X325318D01*
G01X327568Y335860D02*
X325318D01*
G01X303909Y318309D02*
X301659D01*
G01X317428Y314409D02*
X315178D01*
G01X314048Y324160D02*
X311798D01*
G01X327568D02*
X325318D01*
G01X314048Y316360D02*
X311798D01*
G01X307289D02*
X305039D01*
G01X310668Y318309D02*
X308418D01*
G01X300529Y316360D02*
X298279D01*
G01X297149Y318309D02*
X294899D01*
G01X297149Y322209D02*
X294899D01*
G01X324188D02*
X321938D01*
G01X317428D02*
X315178D01*
G01X330948Y333909D02*
X328698D01*
G01X330948Y330009D02*
X328698D01*
G01X330948Y326110D02*
X328698D01*
G01X324188Y283209D02*
X321938D01*
G01X320808Y292959D02*
X318558D01*
G01X314048Y285160D02*
X311798D01*
G01X314048Y292959D02*
X311798D01*
G01X327568Y281260D02*
X325318D01*
G01X330948Y310509D02*
X328698D01*
G01X330948Y283209D02*
X328698D01*
G01X320808Y300760D02*
X318558D01*
G01X327568D02*
X325318D01*
G01X300529D02*
X298279D01*
G01X314048D02*
X311798D01*
G01X307289D02*
X305039D01*
G01X314048Y308560D02*
X311798D01*
G01X317428Y310509D02*
X315178D01*
G01X324188D02*
X321938D01*
G01X300529Y308560D02*
X298279D01*
G01X307289D02*
X305039D01*
G01X320808Y281260D02*
X318558D01*
G01X317428Y283209D02*
X315178D01*
G01X307289Y292959D02*
X305039D01*
G01X300529Y285160D02*
X298279D01*
G01X300529Y292959D02*
X298279D01*
G01X327568D02*
X325318D01*
G01X307289Y285160D02*
X305039D01*
G01X354607Y328060D02*
X357987Y327609D01*
G01X354607Y312460D02*
X357057D01*
G01X354607Y316360D02*
X357057D01*
G01X354607Y320260D02*
X357057D01*
G01X351228Y326110D02*
X348978D01*
G01X351228Y330009D02*
X348978D01*
G01X354607Y331960D02*
X352357D01*
G01X347848Y316360D02*
X345598D01*
G01X351228Y314409D02*
X348978D01*
G01X351228Y322209D02*
X348978D01*
G01X351228Y318309D02*
X348978D01*
G01X354607Y324160D02*
X357057D01*
G01X334328Y304660D02*
X332078D01*
G01X334328Y308560D02*
X332078D01*
G01X334328Y289060D02*
X332078D01*
G01X334328Y296860D02*
X332078D01*
G01X334328Y285160D02*
X332078D01*
G01X354607Y296860D02*
X357057D01*
G01X354607Y281260D02*
X357057D01*
G01X354607Y304660D02*
X357057D01*
G01X347848Y308560D02*
X345598D01*
G01X347848Y304660D02*
X345598D01*
G01X351228Y306609D02*
X348978D01*
G01X351228Y310509D02*
X348978D01*
G01X344468Y306609D02*
X342218D01*
G01X347848Y300760D02*
X345598D01*
G01X344468Y302709D02*
X342218D01*
G01X351228D02*
X348978D01*
G01X354607Y308560D02*
X357057D01*
G01X351228Y287109D02*
X348978D01*
G01X344468Y298809D02*
X342218D01*
G01X344468Y291009D02*
X342218D01*
G01X344468Y287109D02*
X342218D01*
G01X354607Y292959D02*
X357057D01*
G01X354607Y289060D02*
X357057D01*
G01X354607Y285160D02*
X357057D01*
G01X341088Y308560D02*
X338838D01*
G01X341088Y304660D02*
X338838D01*
G01X337708Y306609D02*
X335458D01*
G01X337708Y302709D02*
X335458D01*
G01X337708Y298809D02*
X335458D01*
G01X337708Y287109D02*
X335458D01*
G01X341088Y289060D02*
X338838D01*
G01X341088Y285160D02*
X338838D01*
G01X337708Y291009D02*
X335458D01*
G01X341088Y296860D02*
X338838D01*
G01X337708Y294909D02*
X335458D01*
G01X347848Y285160D02*
X345598D01*
G01X347848Y281260D02*
X345598D01*
G01X351228Y283209D02*
X348978D01*
G01X351228Y291009D02*
X348978D01*
G01X347848Y296860D02*
X345598D01*
G01X351228Y294909D02*
X348978D01*
G01X351228Y298809D02*
X348978D01*
G01X344468Y294909D02*
X342218D01*
G01X347848Y289060D02*
X345598D01*
G01X347848Y292959D02*
X345598D01*
G01X347848Y312460D02*
X345598D01*
G01X307289D02*
X305039D01*
G01X300529D02*
X298279D01*
G01X314048D02*
X311798D01*
G01X310668Y314409D02*
X308418D01*
G01X301659D02*
X303909D01*
G01X297149D02*
X294899D01*
G01X317428Y287109D02*
X315178D01*
G01X320808Y285160D02*
X318558D01*
G01X324188Y287109D02*
X321938D01*
G01X317428Y291009D02*
X315178D01*
G01X324188D02*
X321938D01*
G01X301659Y287109D02*
X303909D01*
G01X301659Y291009D02*
X303909D01*
G01X327568Y285160D02*
X325318D01*
G01X330948Y306609D02*
X328698D01*
G01X330948Y302709D02*
X328698D01*
G01X330948Y294909D02*
X328698D01*
G01X330948Y298809D02*
X328698D01*
G01X330948Y287109D02*
X328698D01*
G01X330948Y291009D02*
X328698D01*
G01X314048Y281260D02*
X311798D01*
G01X307289D02*
X305039D01*
G01X310668Y283209D02*
X308418D01*
G01X297149D02*
X294899D01*
G01X297149Y298809D02*
X294899D01*
G01X300529Y296860D02*
X298279D01*
G01X317428Y298809D02*
X315178D01*
G01X301659Y294909D02*
X303909D01*
G01X317428D02*
X315178D01*
G01X320808Y296860D02*
X318558D01*
G01X307289D02*
X305039D01*
G01X314048D02*
X311798D01*
G01X310668Y294909D02*
X308418D01*
G01X301659Y298809D02*
X303909D01*
G01X310668D02*
X308418D01*
G01X297149Y294909D02*
X294899D01*
G01X324188D02*
X321938D01*
G01X320808Y289060D02*
X318558D01*
G01X324188Y298809D02*
X321938D01*
G01X327568Y296860D02*
X325318D01*
G01X307289Y289060D02*
X305039D01*
G01X324188Y306609D02*
X321938D01*
G01X320808Y304660D02*
X318558D01*
G01X317428Y306609D02*
X315178D01*
G01X310668D02*
X308418D01*
G01X301659D02*
X303909D01*
G01X314048Y304660D02*
X311798D01*
G01X307289D02*
X305039D01*
G01X300529D02*
X298279D01*
G01X297149Y306609D02*
X294899D01*
G01X310668Y310509D02*
X308418D01*
G01X301659D02*
X303909D01*
G01X297149D02*
X294899D01*
G01X320808Y308560D02*
X318558D01*
G01X327568Y304660D02*
X325318D01*
G01X317428Y302709D02*
X315178D01*
G01X297149D02*
X294899D01*
G01X324188D02*
X321938D01*
G01X310668D02*
X308418D01*
G01X301659D02*
X303909D01*
G01X327568Y289060D02*
X325318D01*
G01X300529D02*
X298279D01*
G01X297149Y287109D02*
X294899D01*
G01X297149Y291009D02*
X294899D01*
G01X300529Y281260D02*
X298279D01*
G01X301659Y283209D02*
X303909D01*
G01X310668Y291009D02*
X308418D01*
G01X310668Y287109D02*
X308418D01*
G01X314048Y289060D02*
X311798D01*
G01X327568Y308560D02*
X325318D01*
G01X354607Y300760D02*
X355124Y300243D01*
X356540D01*
G01X334328Y316360D02*
X332078D01*
G01X334328Y320260D02*
X332078D01*
G01X334328Y324160D02*
X332078D01*
G01X334328Y328060D02*
X332078D01*
G01X341088Y320260D02*
X338838D01*
G01X337708Y322209D02*
X335458D01*
G01X337708Y314409D02*
X335458D01*
G01X337708Y318309D02*
X335458D01*
G01X341088Y324160D02*
X338838D01*
G01X341088Y328060D02*
X338838D01*
G01X337708Y326110D02*
X335458D01*
G01X314048Y320260D02*
X311798D01*
G01X307289D02*
X305039D01*
G01X327568D02*
X325318D01*
G01X327568Y316360D02*
X325318D01*
G01X303909Y322209D02*
X301659D01*
G01X320808Y316360D02*
X318558D01*
G01X324188Y314409D02*
X321938D01*
G01X317428Y318309D02*
X315178D01*
G01X330948Y322209D02*
X328698D01*
G01X330948Y314409D02*
X328698D01*
G01X330948Y318309D02*
X328698D01*
G01X307289Y324160D02*
X305039D01*
G01X303909Y326110D02*
X301659D01*
G01X324188Y318309D02*
X321938D01*
G01X310668Y322209D02*
X308418D01*
G01X341088Y386560D02*
X342218Y388509D01*
G01X334328Y378760D02*
X332078D01*
G01X337708Y372909D02*
X335458D01*
G01X337708Y392410D02*
X341088Y390460D01*
G01X334328Y386560D02*
X335458Y384609D01*
G01X337708Y380709D02*
X335458D01*
G01X342218Y388509D02*
X344468D01*
G01X342218D02*
X341088Y390460D01*
G01X351228Y376809D02*
X348978D01*
G01X345598Y390460D02*
X344468Y388509D01*
G01X351228D02*
X352357Y386560D01*
G01X344468Y376809D02*
X342218D01*
G01X334328Y363160D02*
X332078D01*
G01X334328Y355360D02*
X332078D01*
G01X334328Y347560D02*
X332078D01*
G01X354607Y359260D02*
X352357D01*
G01X347848D02*
X345598D01*
G01X344468Y345609D02*
X342218D01*
G01X337708Y361209D02*
X335458D01*
G01X341088Y351460D02*
X338838D01*
G01X341088Y359260D02*
X338838D01*
G01X341088Y355360D02*
X338838D01*
G01X337708Y349509D02*
X335458D01*
G01X341088Y347560D02*
X338838D01*
G01X347848Y343660D02*
X345598D01*
G01X351228Y349509D02*
X348978D01*
G01X297149Y372909D02*
X294899D01*
G01X310668D02*
X308418D01*
G01X324188Y392410D02*
Y396309D01*
G01X320808Y386560D02*
X318558D01*
G01X320808Y390460D02*
X318558D01*
G01X320808Y394359D02*
X318558D01*
G01X327568Y386560D02*
X325318D01*
G01X300529D02*
X298279D01*
G01X330948Y376809D02*
X328698D01*
G01X300529Y390460D02*
X298279D01*
G01X300529Y394359D02*
X298279D01*
G01X300529Y398260D02*
X298279D01*
G01X297149Y396309D02*
X294899D01*
G01X317428Y388509D02*
X315178D01*
G01X314048Y386560D02*
X311798D01*
G01X307289D02*
X308418Y388509D01*
G01X303909D02*
X301659D01*
G01X307289Y394359D02*
X305039D01*
G01X303909Y400209D02*
X302608Y402421D01*
G01X314048Y394359D02*
X315178Y392410D01*
G01X327568Y378760D02*
X325318D01*
G01X327568Y374860D02*
X325318D01*
G01X300529Y378760D02*
X298279D01*
G01X297149Y384609D02*
X294899D01*
G01X307289Y378760D02*
X305039D01*
G01X310668Y384609D02*
X308418D01*
G01X314048Y374860D02*
X311798D01*
G01X314048Y382660D02*
X311798D01*
G01X314048Y378760D02*
X311798D01*
G01X317428Y376809D02*
X315178D01*
G01X324188Y380709D02*
X321938D01*
G01X324188Y376809D02*
X321938D01*
G01X320808Y382660D02*
X318558D01*
G01X320808Y378760D02*
X318558D01*
G01X320808Y398260D02*
Y401941D01*
G01X307289Y347560D02*
X305039D01*
G01X310668Y361209D02*
X308418D01*
G01X324188D02*
X321938D01*
G01X300529Y343660D02*
X298279D01*
G01X310668Y341709D02*
X308418D01*
G01X310668Y345609D02*
X308418D01*
G01X327568Y343660D02*
X325318D01*
G01X310668Y357309D02*
X308418D01*
G01X314048Y359260D02*
X311798D01*
G01X324188Y349509D02*
X321938D01*
G01X320808Y359260D02*
X318558D01*
G01X303909Y357309D02*
X301659D01*
G01X303909Y349509D02*
X301659D01*
G01X297149D02*
X294899D01*
G01X300529Y351460D02*
X298279D01*
G01X317428Y357309D02*
X315178D01*
G01X307289Y351460D02*
X305039D01*
G01X310668Y353409D02*
X308418D01*
G01X320808Y351460D02*
X318558D01*
G01X320808Y355360D02*
X318558D01*
G01X327568Y347560D02*
X325318D01*
G01X327568Y355360D02*
X325318D01*
G01X330948Y365109D02*
X328698D01*
G01X330948Y345609D02*
X328698D01*
G01X327568Y367060D02*
X325318D01*
G01X327568Y370959D02*
X325318D01*
G01X300529D02*
X298279D01*
G01X297149Y369010D02*
X294899D01*
G01X307289Y370959D02*
X305039D01*
G01X310668Y365109D02*
X308418D01*
G01X310668Y369010D02*
X308418D01*
G01X307289Y367060D02*
X305039D01*
G01X327568Y363160D02*
X325318D01*
G01X300529D02*
X298279D01*
G01X317428Y365109D02*
X315178D01*
G01X303909Y369010D02*
X301659D01*
G01X320808Y370959D02*
X318558D01*
G01X297149Y353409D02*
X294899D01*
G01X320808Y401941D02*
X317428Y400209D01*
G01X341088Y382660D02*
X345598D01*
G01X341088Y367060D02*
X338838D01*
G01X344468Y365109D02*
X342218D01*
G01X354607Y370959D02*
X352357D01*
G01X351228Y365109D02*
X348978D01*
G01X347848Y370959D02*
X345598D01*
G01X338838Y382660D02*
X341088D01*
G01X354607D02*
X352357D01*
G01X347848Y394359D02*
X348978Y392410D01*
G01X354607Y394359D02*
X355737Y392410D01*
G01X344468Y353409D02*
X342218D01*
G01X351228D02*
X348978D01*
G01X345598Y382660D02*
X347848D01*
G01X375792Y6500D02*
X376060Y6232D01*
X378524D01*
X378792Y6500D01*
G01X358107Y84115D02*
X358943Y84951D01*
Y86429D01*
X357872Y87500D01*
G01X408069Y84475D02*
X407361Y85183D01*
Y86685D01*
X408068Y87392D01*
G01X375337Y83877D02*
Y86377D01*
G01X371507Y209109D02*
X376017D01*
G01X418084Y208397D02*
X415634D01*
G01X405306Y209109D02*
X407706D01*
G01X418084Y212296D02*
X415634D01*
G01X418084Y204496D02*
X415634D01*
G01X398546Y209109D02*
X396296D01*
G01X391787D02*
X389537D01*
G01X357987D02*
X355737D01*
G01X385027D02*
X382777D01*
G01X364747D02*
X362497D01*
G01X376017D02*
X378267D01*
G01X395166Y214960D02*
X392916D01*
G01X395166Y203260D02*
X392916D01*
G01X405306Y201309D02*
Y200014D01*
X404392Y199100D01*
G01X398546Y197409D02*
X396346D01*
X396296Y197359D01*
G01X401926Y203260D02*
X399676D01*
G01X401926Y214960D02*
X399676D01*
G01X388407Y203260D02*
X386157Y207159D01*
G01Y214960D02*
X388407D01*
G01X374887D02*
X372637D01*
G01X381647D02*
X379397D01*
G01X391787Y197409D02*
X392908Y195070D01*
X392898Y195041D01*
G01X368127Y214960D02*
X365877D01*
G01X361367Y203260D02*
X362497Y205210D01*
G01X374887Y203260D02*
X376017Y205211D01*
G01X368127Y203260D02*
X365877D01*
G01X361367Y214960D02*
X359117D01*
G01X381647Y203260D02*
X382777Y201309D01*
G01X404392Y199100D02*
X404132Y199360D01*
X401926D01*
G01X395166Y250060D02*
X392916D01*
G01X395166Y238360D02*
X392916D01*
G01X398546Y220809D02*
X396296D01*
G01X418084Y247396D02*
X415634D01*
G01X405306Y248109D02*
X407706D01*
G01X405306Y220809D02*
X407706D01*
G01X418084Y223996D02*
X415634D01*
G01X418084Y235696D02*
X415634D01*
G01X398546Y248109D02*
X396296D01*
G01X401926Y250060D02*
X399676D01*
G01X371507Y252009D02*
X369257D01*
G01X357987Y259809D02*
X355737D01*
G01X368127Y253960D02*
X365877D01*
G01X364747Y255909D02*
X362497D01*
G01X361367Y257860D02*
X359117D01*
G01X391787Y248109D02*
X389537D01*
G01X391787Y220809D02*
X389537D01*
G01X388407Y250060D02*
X386157D01*
G01X357987Y248109D02*
X355737D01*
G01X378267D02*
X376017D01*
G01X385027D02*
X382777D01*
G01X381647Y250060D02*
X379397D01*
G01X374887D02*
X372637D01*
G01X381647Y238360D02*
X379397D01*
G01X374887D02*
X372637D01*
G01X388407D02*
X386157D01*
G01X361367D02*
X359117D01*
G01X357987Y220809D02*
X355737D01*
G01X378267D02*
X376017D01*
G01X385027D02*
X382777D01*
G01X371507D02*
X369257D01*
G01X368127Y238360D02*
X365877D01*
G01X364747Y220809D02*
X362497D01*
G01X418084Y239596D02*
X415634D01*
G01Y243496D02*
X418084D01*
G01X395166Y253960D02*
Y256400D01*
G01X401926Y253960D02*
Y256500D01*
G01X398546Y252009D02*
Y254259D01*
G01X405306Y252009D02*
Y254500D01*
G01X378267Y252009D02*
X376017D01*
G01X385027D02*
Y254259D01*
G01X391787Y252009D02*
Y254259D01*
G01X374887Y253960D02*
X372637D01*
G01X371507Y255909D02*
X369257D01*
G01X368127Y257860D02*
X365877D01*
G01X364747Y259809D02*
X362497D01*
G01X378267Y255909D02*
Y258400D01*
G01X371507Y259809D02*
Y262300D01*
G01X368127Y261760D02*
Y264300D01*
G01X361367Y261760D02*
X359117D01*
G01X357987Y267609D02*
X359648Y269777D01*
G01X364747Y263709D02*
Y266300D01*
G01X357987Y263709D02*
X355737D01*
G01X374887Y257860D02*
Y260300D01*
G01X388407Y253960D02*
Y256500D01*
G01X381647Y253960D02*
Y256400D01*
G01X361367Y265660D02*
Y267975D01*
G01X388407Y226660D02*
X392916D01*
G01X401926D02*
X399676D01*
G01X405306Y240309D02*
X407706D01*
G01X405306Y232509D02*
X407706D01*
G01X398546D02*
X396296D01*
G01X385027D02*
X382777D01*
G01X368127Y226660D02*
X365877D01*
G01X374887D02*
X372637D01*
G01X386157D02*
X388407D01*
G01X381647D02*
X379397D01*
G01X364747Y232509D02*
X362497D01*
G01X371507D02*
X369257D01*
G01X391787D02*
X389537D01*
G01X357987Y244209D02*
X355737D01*
G01X364747D02*
X362497D01*
G01X371507D02*
X369257D01*
G01X357987Y232509D02*
X355737D01*
G01X361367Y226660D02*
X359117D01*
G01X378267Y232509D02*
X376017D01*
G01X392916Y226660D02*
X395166D01*
G01X357987Y337809D02*
X355737D01*
G01X361367Y339760D02*
X359117D01*
G01X364747Y333909D02*
Y331509D01*
G01X368127Y339760D02*
X365877D01*
G01X374887D02*
Y337360D01*
G01X361367Y335860D02*
X359117D01*
G01X357987Y333909D02*
X355737D01*
G01X361367Y331960D02*
Y329560D01*
G01X381647Y343660D02*
Y341260D01*
G01X378267Y341709D02*
Y339309D01*
G01X371507Y337809D02*
Y335409D01*
G01X364747Y337809D02*
X362497D01*
G01X368127Y335860D02*
Y333460D01*
G01X357987Y327609D02*
Y330009D01*
G01X356540Y300243D02*
X357057Y300760D01*
G01X408686Y374860D02*
X411086D01*
G01X405306Y388509D02*
X403056D01*
G01X395166Y351460D02*
X392916D01*
G01X395166Y359260D02*
X392916D01*
G01X398546Y353409D02*
X396296D01*
G01X401926Y351460D02*
X399676D01*
G01X408686D02*
X411086D01*
G01X405306Y349509D02*
Y347109D01*
G01X398546Y376809D02*
X396296D01*
G01X398546Y388509D02*
X396296D01*
G01X405306Y376809D02*
X403056D01*
G01X391787Y388509D02*
X389537D01*
G01X391787Y376809D02*
X389537D01*
G01X385027Y388509D02*
X382777D01*
G01X371507D02*
X369257D01*
G01X364747D02*
X362497D01*
G01X378267D02*
X376017D01*
G01X357987D02*
X355737D01*
G01X385027Y376809D02*
X382777D01*
G01X371507D02*
X369257D01*
G01X364747D02*
X362497D01*
G01X378267D02*
X376017D01*
G01X357987D02*
X355737D01*
G01X388407Y351460D02*
X386157D01*
G01X388407Y359260D02*
X386157D01*
G01X371507Y345609D02*
X369257D01*
G01X374887Y347560D02*
X372637D01*
G01Y359260D02*
X374887D01*
G01X368127D02*
X365877D01*
G01X378267Y345609D02*
X376017D01*
G01X361367Y359260D02*
X359117D01*
G01X364747Y341709D02*
X362497D01*
G01X368127Y343660D02*
X365877D01*
G01X391787Y353409D02*
X389537D01*
G01X381647Y347560D02*
X379397D01*
G01X357987Y349509D02*
X355737D01*
G01X381647Y359260D02*
X379397D01*
G01X385027Y349509D02*
X382777D01*
G01X395166Y347560D02*
Y345160D01*
G01X398546Y349509D02*
Y347109D01*
G01X401926Y347560D02*
Y345160D01*
G01X374887Y343660D02*
X372637D01*
G01X385027Y345609D02*
Y343209D01*
G01X388407Y347560D02*
Y345160D01*
G01X391787Y349509D02*
Y347109D01*
G01X371507Y341709D02*
X369257D01*
G01X401926Y382660D02*
X399676D01*
G01X401926Y394359D02*
X403056Y392410D01*
G01X395166Y394359D02*
X392916Y390460D01*
G01X395166Y382660D02*
X392916D01*
G01X408686Y398260D02*
Y400353D01*
X406568Y402471D01*
G01X395166Y370959D02*
X392916D01*
G01X398546Y365109D02*
X396296D01*
G01X401926Y370959D02*
X399676D01*
G01X405306Y357309D02*
X403056D01*
G01X405306Y365109D02*
X403056D01*
G01X371507D02*
X369257D01*
G01X391787D02*
X389537D01*
G01X364747D02*
X362497D01*
G01X378267D02*
X376017D01*
G01X361367Y370959D02*
X359117D01*
G01X357987Y365109D02*
X355737D01*
G01X391787Y400209D02*
Y402800D01*
G01X361367Y382660D02*
X359117D01*
G01X381647Y394359D02*
X379397Y390460D01*
G01X378267Y400209D02*
Y402800D01*
G01X374887Y394359D02*
X376017Y392410D01*
G01X357987Y400209D02*
Y402800D01*
G01X368127Y394359D02*
X368892Y393040D01*
X369257Y392410D01*
G01X361367Y394359D02*
X362497Y392410D01*
G01X381647Y382660D02*
X379397D01*
G01X388407D02*
X386157D01*
G01X372637D02*
X374887D01*
G01X368127D02*
X365877D01*
G01X388407Y394359D02*
X390657D01*
G01X385027Y365109D02*
X382777D01*
G01X381647Y370959D02*
X379397D01*
G01X388407D02*
X386157D01*
G01X357987Y353409D02*
X355737D01*
G01X371507D02*
X369257D01*
G01X364747D02*
X362497D01*
G01X378267D02*
X376017D01*
G01X372637Y370959D02*
X374887D01*
G01X368127D02*
X365877D01*
G01X406568Y402471D02*
X405306Y400209D01*
G01X381480Y619400D02*
Y621400D01*
X382630Y622550D01*
G01X384730D02*
X385981D01*
X386970Y623539D01*
G01X469792Y9300D02*
X474998Y9114D01*
G01X469832Y17114D02*
X464692Y16900D01*
G01X469808Y84700D02*
X464732Y84698D01*
G01X441533Y81584D02*
Y82268D01*
X440807Y82994D01*
Y86666D01*
X441533Y87392D01*
G01X455263Y218147D02*
X453013D01*
G01X455263Y214247D02*
X453013D01*
G01X473292Y218147D02*
X475542D01*
G01X473292Y214247D02*
X475542D01*
G01X468783Y218147D02*
X466533D01*
G01X475542Y202547D02*
Y200050D01*
X475692Y199900D01*
G01X478922Y216196D02*
X476672D01*
G01X472163Y208397D02*
X469967Y212200D01*
X469912Y212296D01*
G01X472163Y216196D02*
X469913D01*
G01X463153D02*
X465403D01*
G01X478922Y212296D02*
X476672D01*
G01X466533Y206446D02*
X466540Y206471D01*
X465992Y207418D01*
X465429Y208390D01*
X465403Y208397D01*
G01X462023Y214247D02*
X459773D01*
G01X458643Y212296D02*
X456393D01*
G01X458643Y216196D02*
X456393D01*
G01X445123D02*
X442873D01*
G01X438363Y204496D02*
Y205029D01*
X438292Y205100D01*
Y208326D01*
X438363Y208397D01*
G01D02*
X439493Y210346D01*
G01X449633Y216196D02*
X451883D01*
G01Y208397D02*
X450992Y209941D01*
X450863Y210164D01*
X449688Y212200D01*
X449633Y212296D01*
G01X431604Y208397D02*
X431603D01*
X429408Y212200D01*
X429353Y212296D01*
G01X434983Y202547D02*
Y198931D01*
G01X441743Y202547D02*
Y199841D01*
G01X421464Y202547D02*
Y199583D01*
G01X446253Y218147D02*
X448503D01*
G01X428224D02*
X425974D01*
G01X434983D02*
X432733D01*
G01X431604Y216196D02*
X429354D01*
G01X434983Y214247D02*
X432733D01*
G01X438363Y212296D02*
X436113D01*
G01Y216196D02*
X438363D01*
G01X419214Y214247D02*
X421464D01*
G01X424844Y216196D02*
X422594D01*
G01X441743Y214247D02*
X439493D01*
G01X425974Y206446D02*
X425975Y206451D01*
X424844Y208397D01*
G01X446253Y206446D02*
X446254Y206450D01*
X445128Y208396D01*
X445123Y208397D01*
G01X455263Y261047D02*
X453013D01*
G01X455263Y257147D02*
X453013D01*
G01X463153Y251296D02*
X465403D01*
G01X478922D02*
X476672D01*
G01X472163D02*
X469913D01*
G01X458643D02*
X456393D01*
G01X458408Y278940D02*
X457248Y280100D01*
Y281341D01*
G01X458643Y262996D02*
X456393D01*
G01X458643Y266896D02*
Y269146D01*
G01X462023Y261047D02*
X459773D01*
G01X458643Y259096D02*
X456393D01*
G01X463153D02*
X465403D01*
G01X462023Y268847D02*
Y271097D01*
G01X468783Y257147D02*
X466533D01*
G01X468783Y272747D02*
Y274997D01*
G01X472163Y270796D02*
X469913D01*
G01X468783Y264947D02*
X466533D01*
G01X478922Y259096D02*
X476672D01*
G01X475542Y257147D02*
X473292D01*
G01X472163Y255196D02*
X469913D01*
G01X475542Y272747D02*
X477792D01*
G01X455263Y237647D02*
X453013D01*
G01X455263Y229847D02*
X453013D01*
G01X468783Y237647D02*
X466533D01*
G01X473292D02*
X475542D01*
G01X478922Y223996D02*
X476672D01*
G01X478922Y231797D02*
X476672D01*
G01X468783Y229847D02*
X466533D01*
G01X472163Y227896D02*
X469913D01*
G01X473292Y229847D02*
X475542D01*
G01X472163Y223996D02*
X469913D01*
G01X463153Y243496D02*
X465403D01*
G01X463153Y223996D02*
X465403D01*
G01X463153Y231797D02*
X465403D01*
G01X468783Y245447D02*
X466533D01*
G01X478922Y243496D02*
X476672D01*
G01X472163Y247396D02*
X469913D01*
G01X473292Y245447D02*
X475542D01*
G01X458643Y243496D02*
X456393D01*
G01X462023Y241547D02*
X459773D01*
G01X462023Y237647D02*
X459773D01*
G01X458643Y223996D02*
X456393D01*
G01X458643Y231797D02*
X456393D01*
G01X462023Y233746D02*
X459773D01*
G01X472163Y220096D02*
X469913D01*
G01X455263Y245447D02*
X453013D01*
G01X451883Y251296D02*
X449633D01*
G01X424844D02*
X422594D01*
G01X438363D02*
X436113D01*
G01X431604D02*
X429354D01*
G01X448900Y269600D02*
X448300D01*
X445600Y272300D01*
Y273300D01*
G01X451883Y259096D02*
X449633D01*
G01X451883Y255196D02*
X449633D01*
G01X445123D02*
X442873D01*
G01X441743Y253247D02*
X439493D01*
G01X448503Y257147D02*
X446253D01*
G01X432643Y264508D02*
X432375Y264776D01*
Y266125D01*
X432000Y266500D01*
Y268000D01*
G01X445123Y223996D02*
X442873D01*
G01X445123Y231797D02*
X442873D01*
G01X441743Y233746D02*
X439493D01*
G01X428224Y229847D02*
X425974D01*
G01X434983D02*
X432733D01*
G01X448503D02*
X446253D01*
G01X451883Y247396D02*
X449633D01*
G01X451883Y227896D02*
X449633D01*
G01X451883Y220096D02*
X449633D01*
G01X451883Y223996D02*
X449633D01*
G01X421464Y241547D02*
X419214D01*
G01X441743D02*
X439493D01*
G01X431604Y247396D02*
X429354D01*
G01X434983Y249347D02*
X432733D01*
G01X428224D02*
X425974D01*
G01X428224Y245447D02*
X425974D01*
G01X438363Y243496D02*
X436113D01*
G01X434983Y245447D02*
X432733D01*
G01X445123Y243496D02*
X442873D01*
G01X448503Y245447D02*
X446253D01*
G01X424844Y243496D02*
X422594D01*
G01X421464Y249347D02*
X419214D01*
G01X431604Y227896D02*
X429354D01*
G01Y220096D02*
X431604D01*
G01Y223996D02*
X429354D01*
G01X438363D02*
X436113D01*
G01X438363Y231797D02*
X436113D01*
G01X421464Y237647D02*
X419214D01*
G01X424844Y223996D02*
X422594D01*
G01X424844Y231797D02*
X422594D01*
G01X421464Y233746D02*
X419214D01*
G01X448503Y237647D02*
X446253D01*
G01X441743D02*
X439493D01*
G01X434983D02*
X432733D01*
G01X428224D02*
X425974D01*
G01X419214Y245447D02*
X421464D01*
G01X455263Y264947D02*
Y267197D01*
G01X448503Y261047D02*
Y263297D01*
G01X451883Y262996D02*
Y265246D01*
G01X431604Y255196D02*
Y257446D01*
G01X421464Y253247D02*
Y255497D01*
G01X438363Y255196D02*
Y257446D01*
G01X434983Y253247D02*
Y255497D01*
G01X441743Y257147D02*
Y259397D01*
G01X445123Y259096D02*
Y261346D01*
G01X428224Y253247D02*
Y255497D01*
G01X424844Y255196D02*
Y257446D01*
G01X463153Y262996D02*
X465403D01*
G01X474413Y274696D02*
X472163D01*
G01X468783Y268847D02*
X466533D01*
G01X468783Y261047D02*
X466533D01*
G01X475542Y276646D02*
X477792D01*
G01X472163Y278596D02*
X469913D01*
G01X448503Y249347D02*
X446253D01*
G01X438363Y247396D02*
X436113D01*
G01X441743Y245447D02*
X439493D01*
G01X445123Y247396D02*
X442873D01*
G01X441743Y249347D02*
X439493D01*
G01X448503Y253247D02*
X446253D01*
G01X445123Y251296D02*
X442873D01*
G01X428000Y271500D02*
Y268500D01*
X428500Y268000D01*
G01X429781Y264793D02*
X429834D01*
Y265766D01*
X428500Y267100D01*
Y268000D01*
G01X424844Y247396D02*
X422594D01*
G01X460748Y281341D02*
X461800Y280289D01*
Y274399D01*
X465403Y270796D01*
G01Y266896D02*
X464375Y267924D01*
Y269768D01*
X465403Y270796D01*
G01X475542Y264947D02*
X473292D01*
G01X475542Y268847D02*
X473292D01*
G01X478922Y266896D02*
X476672D01*
G01X478922Y262996D02*
X476672D01*
G01X472163Y340996D02*
X474413D01*
G01X472163Y321496D02*
X469913D01*
G01X475542Y319547D02*
X477792D01*
G01X474413Y337096D02*
X472163D01*
G01X475542Y327347D02*
X477792D01*
G01X465403Y340996D02*
X467653D01*
G01X475542Y315647D02*
X477792D01*
G01X472163Y305896D02*
X469913D01*
G01X475542Y303947D02*
X477792D01*
G01X475542Y307847D02*
X477788D01*
X477792Y307851D01*
G01X472163Y286396D02*
X469913D01*
G01X475542Y288347D02*
X477792D01*
G01X475542Y323446D02*
X477792D01*
G01X474413Y333196D02*
X472163D01*
G01X474413Y325396D02*
X472163D01*
G01X475542Y300047D02*
X477792D01*
G01X472163Y301996D02*
X469913D01*
G01X472163Y294196D02*
X469913D01*
G01X472163Y282496D02*
X469913D01*
G01X472163Y298096D02*
X469913D01*
G01X475542Y296147D02*
X477792D01*
G01X475542Y284447D02*
X477792D01*
G01X475542Y280547D02*
X477792D01*
G01X475542Y292247D02*
X477792D01*
G01X472163Y290296D02*
X469913D01*
G01X462023Y339047D02*
Y342947D01*
G01X465403Y337096D02*
X466832D01*
X468783Y339047D01*
G01D02*
X471033D01*
G01X475542D02*
X477792D01*
G01X475542Y335147D02*
X477792D01*
G01X475542Y331247D02*
X477792D01*
G01X445123Y395597D02*
X443993Y393647D01*
G01X421464Y401447D02*
X423713D01*
X423715Y401449D01*
G01X424844Y399496D02*
X423715Y397548D01*
G01X472163Y372197D02*
X474413D01*
G01X465403D02*
X467653D01*
G01X465403Y395597D02*
X464273Y393647D01*
G01X468783Y378047D02*
X471033D01*
G01X475542Y381947D02*
X477792D01*
G01X465403Y376096D02*
X467653D01*
G01X465403Y399496D02*
X464273Y397546D01*
G01X465403Y403396D02*
X464273Y401447D01*
G01X468783Y385847D02*
X471033D01*
G01Y393647D02*
X468783D01*
G01X472163Y391696D02*
X474413D01*
G01X475542Y385847D02*
X477792D01*
G01X475542Y389747D02*
X477792D01*
G01X462023Y378047D02*
X464273D01*
G01X462023Y385847D02*
X464273D01*
G01X458643Y399496D02*
X460893Y395595D01*
G01X458643Y379996D02*
X460893D01*
G01X455263Y381947D02*
X457513D01*
G01X458643Y391696D02*
X460893D01*
G01X455263Y389747D02*
X457513D01*
G01X455263Y385847D02*
X457513D01*
G01X472163Y379996D02*
X474413D01*
G01X458643Y364396D02*
X460893D01*
G01X455263Y362447D02*
X457513D01*
G01X458643Y352696D02*
X460893D01*
G01X455263Y354647D02*
X457513D01*
G01X455263Y358547D02*
X457513D01*
G01X455263Y346847D02*
X457513D01*
G01X472163Y364396D02*
X474413D01*
G01X468783Y366347D02*
X471033D01*
G01X465403Y368296D02*
X467653D01*
G01X475542Y362447D02*
X477792D01*
G01X465403Y348796D02*
X467653D01*
G01X472163D02*
X474413D01*
G01X468783Y350747D02*
X471033D01*
G01X472163Y352696D02*
X474413D01*
G01X468783Y358547D02*
X471033D01*
G01X475542Y354647D02*
X477792D01*
G01X475542Y358547D02*
X477792D01*
G01X475542Y342947D02*
X477792D01*
G01X462023Y366347D02*
X464273D01*
G01X462023Y358547D02*
X464273D01*
G01X462023Y350747D02*
X464273D01*
G01X421464Y374146D02*
X423714D01*
G01X441743Y378047D02*
X443993D01*
G01X423715Y397548D02*
X424844Y395597D01*
G01X423715Y397548D02*
X423713Y397546D01*
X421464D01*
G01X445123Y376096D02*
X447373D01*
G01X438363Y379996D02*
X440613D01*
G01X438363Y364396D02*
X440613D01*
G01X438363Y352696D02*
X440613D01*
G01X424844Y356596D02*
X427094D01*
G01X431604Y352696D02*
X433854D01*
G01X424844D02*
X427094D01*
G01X434983Y354647D02*
X437233D01*
G01X421464D02*
X423714D01*
G01X428224D02*
X430474D01*
G01X424844Y360496D02*
X427094D01*
G01X441743Y358547D02*
X443993D01*
G01X434983Y362447D02*
X437233D01*
G01X421464D02*
X423714D01*
G01X445123Y368296D02*
X447373D01*
G01X441743Y366347D02*
X443993D01*
G01X448503D02*
X450753D01*
G01X451883Y364396D02*
X454133D01*
G01X431604Y379996D02*
X433854D01*
G01X428224Y378047D02*
X430474D01*
G01X451883Y391696D02*
X454133D01*
G01X448503Y378047D02*
X450753D01*
G01X448503Y385847D02*
X450753D01*
G01X448503Y393647D02*
X450753D01*
G01X451883Y379996D02*
X454133D01*
G01X424844Y376096D02*
X427094D01*
G01X434983Y381947D02*
X437233D01*
G01X428224Y393647D02*
X430474D01*
G01X431604Y399496D02*
X429354D01*
G01X438363Y372197D02*
X440613D01*
G01X445123D02*
X447373D01*
G01X451883D02*
X454133D01*
G01X424844D02*
X427094D01*
G01X434983Y389747D02*
X437233D01*
G01X434983Y385847D02*
X437233D01*
G01X421464D02*
X423714D01*
G01X428224D02*
X430474D01*
G01X431604Y391696D02*
X433854D01*
G01X445123Y403396D02*
X443993Y401447D01*
G01X438363Y399496D02*
X440613Y395595D01*
G01X441743Y385847D02*
X443993D01*
G01X438363Y391696D02*
X440613D01*
G01X448503Y350747D02*
X450753D01*
G01X451883Y348796D02*
X454133D01*
G01X451883Y352696D02*
X454133D01*
G01X424844Y368296D02*
X427094D01*
G01X464273Y393647D02*
X462023D01*
G01X423715Y401449D02*
X424844Y403396D01*
G01X443993Y393647D02*
X441743D01*
G01X465403Y344896D02*
X464273Y346847D01*
G01D02*
X462023D01*
G01Y342947D02*
X464273D01*
G01X458643Y348796D02*
X457513Y350747D01*
G01D02*
X455263D01*
G01X462023Y405347D02*
X464273D01*
G01X441743D02*
X443993D01*
G01X428224D02*
Y407800D01*
G01X441533Y574742D02*
Y574759D01*
G01X538315Y16900D02*
X543455Y17114D01*
G01X538355Y9098D02*
X543415Y9300D01*
G01X506644Y17114D02*
X501504Y16900D01*
G01X511809Y9114D02*
X506604Y9300D01*
G01X506644Y54914D02*
X501492Y54700D01*
G01X525195Y46914D02*
X518502D01*
G01X543455Y54914D02*
X538304Y54700D01*
G01X506620Y84700D02*
X501544Y84698D01*
G01X511809Y46914D02*
X506592Y47000D01*
G01X536381Y210346D02*
X538631D01*
G01X536381Y214247D02*
X538631D01*
G01X526241Y216196D02*
X528491D01*
G01X526241Y208397D02*
X528491D01*
G01X529621Y206447D02*
X531871D01*
G01X538631D02*
X536381D01*
G01X516102D02*
X518350D01*
X518352Y206445D01*
G01X519481Y208397D02*
X521731D01*
G01X516102Y218147D02*
X518352D01*
G01X525111Y206447D02*
X522861D01*
G01X482302Y214247D02*
X480052D01*
G01X509342Y206447D02*
X511592D01*
G01X509342Y218147D02*
X511592D01*
G01X509342Y210346D02*
X511592D01*
G01X505962Y212296D02*
X508212D01*
G01X489062Y210346D02*
X486812D01*
G01X495822D02*
X497904D01*
X498350Y209900D01*
G01X489062Y218147D02*
X486812D01*
G01X489062Y214247D02*
X486812D01*
G01X499202Y212296D02*
X501452D01*
G01X478922Y204496D02*
X479892Y206171D01*
X479923Y206224D01*
X480052Y206447D01*
G01D02*
X478922Y208397D01*
G01X501452Y212296D02*
X502582Y211166D01*
Y210346D01*
G01X539761Y208397D02*
X542010D01*
X542011Y208396D01*
G01X519481Y216196D02*
X521731D01*
G01X529621Y218147D02*
X531871D01*
G01X526241Y204496D02*
X528491D01*
G01X525111Y202547D02*
X524611Y202046D01*
X523362D01*
X522861Y202547D01*
G01X538631Y202247D02*
X538364Y201980D01*
X536948D01*
X536381Y202547D01*
G01X531871D02*
X531370Y202046D01*
X530122D01*
X529621Y202547D01*
G01X533001Y251296D02*
X535251D01*
G01X529621Y276646D02*
X531871D01*
G01X536381Y257147D02*
X538631D01*
G01X533001Y259096D02*
X535251D01*
G01X529621Y261047D02*
X531871D01*
G01X529621Y268847D02*
X531871D01*
G01X526241Y274696D02*
X528491D01*
G01X522861Y253247D02*
X525111D01*
G01X516102D02*
X518352D01*
G01X519481Y259096D02*
X521731D01*
G01X519481Y274696D02*
X521731D01*
G01X519481Y266896D02*
X521731D01*
G01X533001D02*
X535251D01*
G01X539761Y274696D02*
X542011D01*
G01X539761Y239596D02*
X542011D01*
G01X539761Y247396D02*
X542011D01*
G01X526241D02*
X528491D01*
G01X526241Y243496D02*
X528491D01*
G01X536381Y249347D02*
X538631D01*
G01X533001Y247396D02*
X535251D01*
G01X526241Y220096D02*
X528491D01*
G01X529621Y222047D02*
X531871D01*
G01X536381Y237647D02*
X538631D01*
G01X533001Y235696D02*
X535251D01*
G01X526241Y227896D02*
X528491D01*
G01X526241Y235696D02*
X528491D01*
G01X536381Y225947D02*
X538631D01*
G01X519481Y247396D02*
X521731D01*
G01X519481Y231797D02*
X521731D01*
G01X519481Y235696D02*
X521731D01*
G01X516102Y229847D02*
X518352D01*
G01X519481Y220096D02*
X521731D01*
G01X522861Y237647D02*
X525111D01*
G01X533001Y239596D02*
X535251D01*
G01X485682Y251296D02*
X483432D01*
G01X492442D02*
X494692D01*
G01X478922Y278596D02*
X481172D01*
G01X478922Y274696D02*
X481172D01*
G01X485682Y278596D02*
X487932D01*
G01X499202Y274696D02*
X501452D01*
G01X505962Y270796D02*
X508212D01*
G01X512722D02*
X514972D01*
G01X512722Y278596D02*
X514972D01*
G01X499202Y259096D02*
X501452D01*
G01X492442Y255196D02*
X494692D01*
G01X499202Y266896D02*
X501452D01*
G01X494692Y270796D02*
X492442D01*
G01X505962Y278596D02*
X508212D01*
G01X492442D02*
X494692D01*
G01X485682Y274696D02*
X487932D01*
G01X502582Y253247D02*
X504832D01*
G01X489062Y257147D02*
X486812D01*
G01X482302Y268847D02*
X484552D01*
G01X482302Y261047D02*
X480052D01*
G01X485682Y259096D02*
X483432D01*
G01X489062Y233746D02*
X486812D01*
G01X495822D02*
X498072D01*
G01X482302D02*
X480052D01*
G01X505962Y223996D02*
X508212D01*
G01X489062Y229847D02*
X486812D01*
G01X509342Y249347D02*
X511592D01*
G01X509342Y241547D02*
X511592D01*
G01X512722Y239596D02*
X514972D01*
G01X512722Y247396D02*
X514972D01*
G01X512722Y227896D02*
X514972D01*
G01X512722Y235696D02*
X514972D01*
G01X512722Y223996D02*
X514972D01*
G01X499202Y247396D02*
X501452D01*
G01X502582Y245447D02*
X504832D01*
G01X492442Y247396D02*
X494692D01*
G01X492442Y243496D02*
X494692D01*
G01X485682D02*
X483432D01*
G01X489062Y245447D02*
X486812D01*
G01X502582Y241547D02*
X504832D01*
G01X489062D02*
X486812D01*
G01X482302D02*
X480052D01*
G01X505962Y239596D02*
X508212D01*
G01X485682Y223996D02*
X483432D01*
G01X485682Y235696D02*
X483432D01*
G01X482302Y237647D02*
X480052D01*
G01X505962Y220096D02*
X508212D01*
G01X505962Y231797D02*
X508212D01*
G01X499202Y223996D02*
X501452D01*
G01X489062Y237647D02*
X486812D01*
G01X489062Y222047D02*
X486812D01*
G01X495822Y225947D02*
X498072D01*
G01X495822Y222047D02*
X498072D01*
G01X489062Y225947D02*
X486812D01*
G01X502582Y229847D02*
X504832D01*
G01X492442Y235696D02*
X494692D01*
G01X539761Y270796D02*
X542011D01*
G01X529621Y264947D02*
X531871D01*
G01X526241Y270796D02*
X528491D01*
G01X526241Y278596D02*
X528491D01*
G01X533001Y255196D02*
X535251D01*
G01X516102Y222047D02*
X518352D01*
G01X516102Y233746D02*
X518352D01*
G01X533001Y223996D02*
X535251D01*
G01X526241D02*
X528491D01*
G01X539761D02*
X542011D01*
G01X529621Y249347D02*
X531871D01*
G01X529621Y241547D02*
X531871D01*
G01X529621Y237647D02*
X531871D01*
G01X512722Y220096D02*
X514972D01*
G01X509342Y222047D02*
X511592D01*
G01X495822Y245447D02*
X498072D01*
G01X502582Y225947D02*
X504832D01*
G01X492442Y223996D02*
X494692D01*
G01X495822Y268847D02*
X498072D01*
G01X502582Y264947D02*
X504832D01*
G01X492442Y262996D02*
X494692D01*
G01X478922Y270796D02*
X481172D01*
G01X482302Y264947D02*
X480052D01*
G01X489062D02*
X491312D01*
G01X485682Y266896D02*
X487932D01*
G01X491312Y268847D02*
X489062D01*
G01X485682Y270796D02*
X487932D01*
G01X536381Y311747D02*
X538631D01*
G01X529621D02*
X531871D01*
G01X516102Y339047D02*
X518352D01*
G01X516102Y315647D02*
X518352D01*
G01X519481Y317596D02*
X521731D01*
G01X516102Y323446D02*
X518352D01*
G01X516102Y319547D02*
X518352D01*
G01X519481Y325396D02*
X521731D01*
G01X516102Y327347D02*
X518352D01*
G01X536381Y319547D02*
X538631D01*
G01X533001Y321496D02*
X535251D01*
G01X529621Y319547D02*
X531871D01*
G01X526241Y317596D02*
X528491D01*
G01X526241Y337096D02*
X528491D01*
G01X522861Y335147D02*
X525111D01*
G01X522861Y315647D02*
X525111D01*
G01X533001Y329296D02*
X535251D01*
G01X536381Y339047D02*
X538631D01*
G01X536381Y335147D02*
X538631D01*
G01X542011Y321496D02*
X539761D01*
G01X529621Y335147D02*
X531871D01*
G01X536381Y292247D02*
X538631Y292245D01*
G01X536381Y284447D02*
X538631D01*
G01X536381Y288347D02*
X538631D01*
G01X526241Y294196D02*
X528491D01*
G01X529621Y292247D02*
X531871Y292245D01*
G01X522861Y300047D02*
X525111D01*
G01X522861Y284447D02*
X525111D01*
G01X533001Y290296D02*
X535251D01*
G01X533001Y294196D02*
X535251D01*
G01X526241Y298096D02*
X528491D01*
G01X522861Y280547D02*
X525111D01*
G01X526241Y286396D02*
X528491D01*
G01X519481Y301996D02*
X521731D01*
G01X533001Y309797D02*
X535251D01*
G01X529621Y307847D02*
X531871D01*
G01X529621Y303947D02*
X531871D01*
G01X533001Y301996D02*
X535251D01*
G01X529621Y300047D02*
X531871D01*
G01X539761Y294196D02*
X542011D01*
G01X539761Y298096D02*
X542011D01*
G01X529621Y288347D02*
X531871D01*
G01X505962Y313696D02*
X508212D01*
G01X478922D02*
X481172D01*
G01X482302Y323446D02*
X484552D01*
G01X512722Y325396D02*
X514972D01*
G01X512722Y337096D02*
X514972D01*
G01X512722Y333196D02*
X514972D01*
G01X512722Y329296D02*
X514972D01*
G01X512722Y317596D02*
X514972D01*
G01X512722Y321496D02*
X514972D01*
G01X509342Y327347D02*
X511592D01*
G01X509342Y331247D02*
X511592D01*
G01X509342Y335147D02*
X511592D01*
G01X509342Y339047D02*
X511592D01*
G01X509342Y323446D02*
X511592D01*
G01X509342Y319547D02*
X511592D01*
G01X509342Y315647D02*
X511592D01*
G01X502582Y339047D02*
X504832D01*
G01X502582Y335147D02*
X504832D01*
G01X505962Y329296D02*
X508212D01*
G01X499202Y333196D02*
X501452D01*
G01X502582Y323446D02*
X504832D01*
G01X499202Y340996D02*
X501452D01*
G01X485682Y317596D02*
X487932D01*
G01X502582Y319547D02*
X504832D01*
G01X502582Y315647D02*
X504832D01*
G01X505962Y317596D02*
X508212D01*
G01X495822Y319547D02*
X498072D01*
G01X505962Y325396D02*
X508212D01*
G01X489062Y331247D02*
X491312D01*
G01X492442Y340996D02*
X494692D01*
G01X489062Y339047D02*
X491312D01*
G01X492442Y337096D02*
X494692D01*
G01X495822Y327347D02*
X498072D01*
G01X502582Y331247D02*
X504832D01*
G01X505962Y337096D02*
X508212D01*
G01X505962Y333196D02*
X508212D01*
G01X478922Y290296D02*
X481172D01*
G01X482302Y292247D02*
X484552Y292245D01*
G01X509342Y307847D02*
X511592D01*
G01X512722Y301996D02*
X514972D01*
G01X509342Y284447D02*
X511592D01*
G01X512722Y286396D02*
X514972D01*
G01X512722Y290296D02*
X514972D01*
G01X489062Y300047D02*
X491312D01*
G01X482302D02*
X484552D01*
G01X478922Y301996D02*
X481172D01*
G01X495822Y303947D02*
X498072D01*
G01X485682Y309797D02*
X487932D01*
G01X492442D02*
X494692D01*
G01X502582Y307847D02*
X504832D01*
G01X478922Y309797D02*
X481172D01*
G01X492442Y286396D02*
X494692D01*
G01X485682Y282496D02*
X487932D01*
G01X505962Y294196D02*
X508212D01*
G01X489062Y292247D02*
X491312Y292245D01*
G01X499202Y282496D02*
X501452D01*
G01X499202Y290296D02*
X501452D01*
G01X505962D02*
X508212D01*
G01X499202Y298096D02*
X501452D01*
G01X492442Y294196D02*
X494692D01*
G01X533001Y333196D02*
X535251D01*
G01X533001Y325396D02*
X535251D01*
G01X519481Y321496D02*
X521731D01*
G01X516102Y331247D02*
X518352D01*
G01X522861Y339047D02*
X525111D01*
G01X512722Y340996D02*
X514972D01*
G01X505962Y321496D02*
X508212D01*
G01X502582Y327347D02*
X504832D01*
G01X495822Y339047D02*
X498072D01*
G01X478922Y305896D02*
X481172D01*
G01X485682Y290296D02*
X487932D01*
G01X478922Y298096D02*
X481172D01*
G01X478922Y294196D02*
X481172D01*
G01X482302Y296147D02*
X484552D01*
G01X482302Y288347D02*
X484552D01*
G01X482302Y280547D02*
X484552D01*
G01X502582Y311747D02*
X504832D01*
G01X505962Y305896D02*
X508212D01*
G01X505962Y301996D02*
X508212D01*
G01X502582Y303947D02*
X504832D01*
G01X502582Y300047D02*
X504830D01*
X504832Y300045D01*
G01X516102Y311747D02*
X518352D01*
G01X522861D02*
X525111D01*
G01X519481Y313696D02*
X521731D01*
G01X526241D02*
X528491D01*
G01X519481Y309797D02*
X521731D01*
G01X519481Y305896D02*
X521731D01*
G01X522861Y303947D02*
X525111D01*
G01X522861Y307847D02*
X525111D01*
G01X526241Y301996D02*
X528491D01*
G01X526241Y309797D02*
X528491D01*
G01X516102Y307847D02*
X518352D01*
G01X528491Y305896D02*
X526241D01*
G01X512722Y313696D02*
X514972D01*
G01X512722Y309797D02*
X514972D01*
G01X512722Y305896D02*
X514972D01*
G01X516102Y303947D02*
X518352D01*
G01Y296147D02*
X516102D01*
G01Y300047D02*
X518352D01*
G01X519481Y294196D02*
X521731D01*
G01X522861Y288347D02*
X525111D01*
G01X526241Y290296D02*
X528491D01*
G01X522861Y296147D02*
X525111D01*
G01X522861Y292247D02*
X525111Y292245D01*
G01X519481Y298096D02*
X521731D01*
G01X519481Y290296D02*
X521731D01*
G01X519481Y286396D02*
X521731D01*
G01X516102Y288347D02*
X518352D01*
G01X516102Y292247D02*
X518352Y292245D01*
G01X512722Y298096D02*
X514972D01*
G01X499202Y325396D02*
X501452D01*
G01X495822Y323446D02*
X498072D01*
G01X495822Y315647D02*
X498072D01*
G01X499202Y317596D02*
X501452D01*
G01X495822Y335147D02*
X498072D01*
G01X499202Y321496D02*
X501452D01*
G01X495822Y331247D02*
X498072D01*
G01X499202Y329296D02*
X501452D01*
G01X499202Y313696D02*
X501452D01*
G01X495822Y300047D02*
X498072D01*
G01X505962Y298096D02*
X508212D01*
G01X502582Y296147D02*
X504832D01*
G01X495822D02*
X498072D01*
G01X499202Y294196D02*
X501452D01*
G01X509342Y296147D02*
X511592D01*
G01X495822Y311747D02*
X498072D01*
G01X499202Y301996D02*
X501452D01*
G01X492442Y325396D02*
X494692D01*
G01X492442Y321496D02*
X494692D01*
G01X489062Y319547D02*
X491312D01*
G01X492442Y333196D02*
X494692D01*
G01X489062Y335147D02*
X491312D01*
G01X485682Y333196D02*
X487932D01*
G01X485682Y337096D02*
X487932D01*
G01X482302Y339047D02*
X484552D01*
G01X478922Y340996D02*
X481172D01*
G01X478922Y337096D02*
X481172D01*
G01X482302Y335147D02*
X484552D01*
G01X489062Y327347D02*
X491312D01*
G01X492442Y329296D02*
X494692D01*
G01X485682D02*
X487932D01*
G01X485682Y340996D02*
X487932D01*
G01X492442Y313696D02*
X494692D01*
G01X482302Y307847D02*
X484552D01*
G01X489062D02*
X491312D01*
G01X489062Y311747D02*
X491312D01*
G01X492442Y305896D02*
X494692D01*
G01X519481Y372197D02*
X521731D01*
G01X529621Y374146D02*
X531871D01*
G01X519481Y399496D02*
X521731D01*
G01X516102Y397546D02*
X518352D01*
G01X516102Y389747D02*
X518352D01*
G01X522861Y381947D02*
X525111D01*
G01X522861Y393647D02*
X525111D01*
G01X529621Y401447D02*
X531871D01*
G01X542011Y376096D02*
X539761D01*
G01X536381Y378047D02*
X538631D01*
G01X533001Y383896D02*
X535251D01*
G01X529621Y389747D02*
X531871D01*
G01X536381Y393647D02*
X538631D01*
G01X516102Y370247D02*
X518352D01*
G01X516102Y362447D02*
X518352D01*
G01X516102Y342947D02*
X518352D01*
G01X519481Y356596D02*
X521731D01*
G01X519481Y360496D02*
X521731D01*
G01X519481Y348796D02*
X521731D01*
G01X542011D02*
X539761D01*
G01X542011Y360496D02*
X539761D01*
G01X522861Y342947D02*
X525111D01*
G01X522861Y354647D02*
X525111D01*
G01X542011Y368296D02*
X539761D01*
G01X536381Y366347D02*
X538631D01*
G01X526241Y364396D02*
X528491D01*
G01X529621Y346847D02*
X531871D01*
G01X533001Y356596D02*
X535251D01*
G01X512722Y372197D02*
X514972D01*
G01X502582Y381947D02*
X504832D01*
G01X502582Y378047D02*
X504832D01*
G01X499202Y379996D02*
X501452D01*
G01X485682Y376096D02*
X487932D01*
G01X482302Y378047D02*
X484552D01*
G01X481172Y379996D02*
X478922D01*
G01X492442Y391696D02*
X494692D01*
G01X489062Y385847D02*
X491312D01*
G01X495822D02*
X498072D01*
G01X495822Y393647D02*
X498072D01*
G01X482302D02*
X484552D01*
G01X481172Y391696D02*
X478922D01*
G01X482302Y385847D02*
X484552D01*
G01X489062Y389747D02*
X491312D01*
G01X485682Y399496D02*
X487932D01*
G01X485682Y395597D02*
X487932D01*
G01X499202Y391696D02*
X501452D01*
G01X481172Y395596D02*
X480792Y396255D01*
X478922Y399496D01*
G01X509342Y378047D02*
X511592D01*
G01X509342Y397546D02*
X511592D01*
G01X512722Y379996D02*
X514972D01*
G01X499202Y395597D02*
X501452D01*
G01X505962Y387796D02*
X508212D01*
G01X509342Y370247D02*
X511592D01*
G01X512722Y356596D02*
X514972D01*
G01X492442Y364396D02*
X494692D01*
G01X499202D02*
X501452D01*
G01X502582Y366347D02*
X504832D01*
G01X499202Y368296D02*
X501452D01*
G01X489062Y370247D02*
X491312D01*
G01X485682Y368296D02*
X487932D01*
G01X489062Y366347D02*
X491312D01*
G01X502582Y342947D02*
X504832D01*
G01X482302Y366347D02*
X484552D01*
G01X495822Y362447D02*
X498072D01*
G01X489062D02*
X491312D01*
G01X502582Y346847D02*
X504832D01*
G01X499202Y348796D02*
X501452D01*
G01X499202Y352696D02*
X501452D01*
G01X502582Y354647D02*
X504832D01*
G01X495822Y346847D02*
X498072D01*
G01X492442Y344896D02*
X494692D01*
G01X489062Y346847D02*
X491312D01*
G01X498072Y358547D02*
X495822D01*
G01X489062D02*
X491312D01*
G01X481172Y352696D02*
X478922D01*
G01X495822Y350747D02*
X498072D01*
G01X492442Y348796D02*
X494692D01*
G01X489062Y350747D02*
X491312D01*
G01X492442Y360496D02*
X494692D01*
G01X495822Y354647D02*
X498072D01*
G01X499202Y344896D02*
X501452D01*
G01X505962Y352696D02*
X508212D01*
G01X505962Y360496D02*
X508212D01*
G01X499202D02*
X501452D01*
G01X502582Y358547D02*
X504832D01*
G01X499202Y356596D02*
X501452D01*
G01X478922Y344896D02*
X481172D01*
G01X482302Y346847D02*
X484552D01*
G01X495822Y342947D02*
X498072D01*
G01X542011Y372197D02*
X539761D01*
G01X522861Y397546D02*
X525111D01*
G01X526241Y391696D02*
X528491D01*
G01X536381Y381947D02*
X538631D01*
G01X529621Y385847D02*
X531871D01*
G01X536381Y370247D02*
X538631D01*
G01X542011Y352696D02*
X539761D01*
G01X519481Y368296D02*
X521731D01*
G01X516102Y366347D02*
X518352D01*
G01X516102Y358547D02*
X518352D01*
G01X519481Y344896D02*
X521731D01*
G01X522861Y350747D02*
X525111D01*
G01X542011Y364396D02*
X539761D01*
G01X509342Y374146D02*
X511592D01*
G01X512722Y399496D02*
X514972D01*
G01X492442Y376096D02*
X494692D01*
G01X505962Y379996D02*
X508212D01*
G01X499202Y383896D02*
X501452D01*
G01X495822Y389747D02*
X498072D01*
G01X502582Y362447D02*
X504832D01*
G01X492442Y368296D02*
X494692D01*
G01X492442Y352696D02*
X494692D01*
G01X505962Y356596D02*
X508212D01*
G01X502582Y350747D02*
X504832D01*
G01X485682Y344896D02*
X487932D01*
G01X485682Y352696D02*
X487932D01*
G01X482302Y354647D02*
X484552D01*
G01X482302Y350747D02*
X484552D01*
G01X482302Y358547D02*
X484552D01*
G01X481172Y356596D02*
X478922D01*
G01X485682Y348796D02*
X487932D01*
G01X482302Y342947D02*
X484552D01*
G01X526241Y403396D02*
X528491D01*
G01X512722D02*
X514972D01*
G01X529621Y405347D02*
X531871D01*
G01X543404Y47000D02*
X548620Y46914D01*
G01X543431Y84700D02*
X548620Y84714D01*
G01X580242Y84700D02*
X585431Y84714D01*
G01X599000Y102000D02*
X601192D01*
X603163Y103971D01*
G01X599000Y102000D02*
Y106500D01*
X595900Y109600D01*
Y120900D01*
X597700Y122700D01*
X600150D01*
G01X546521Y212296D02*
X548771D01*
G01X543141Y210346D02*
X545391D01*
G01X546521Y204496D02*
X548472Y206447D01*
X549901D01*
G01X553281Y208397D02*
X554103D01*
X555700Y206800D01*
X557000D01*
G01X553281Y216196D02*
X555531D01*
G01X552151Y218147D02*
X549901D01*
G01Y214247D02*
X552151D01*
G01X546521Y204496D02*
Y202479D01*
X547600Y201400D01*
X547800D01*
G01X556661Y218147D02*
X558911D01*
G01X577900Y178200D02*
Y189000D01*
X583300Y194400D01*
Y228000D01*
X612650Y257350D01*
Y282650D01*
X623550Y293550D01*
X628950D01*
G01X549901Y233746D02*
X552151D01*
G01X560041Y251296D02*
X562591D01*
G01X553281Y274696D02*
X555531D01*
G01X560041Y262996D02*
G03X559460Y264397I-1982J-1D01*
G01X558911Y264947D01*
G01X560041Y255196D02*
X562591D01*
G01X560041Y274696D02*
X561245Y275900D01*
X563800D01*
G01X549901Y261047D02*
X552151D01*
G01X556661Y272747D02*
X558911D01*
G01X549901Y257147D02*
X552151D01*
G01X546521Y266896D02*
X548771D01*
G01X543141Y272747D02*
X545391D01*
G01X543141Y264947D02*
X545391D01*
G01X546521Y255196D02*
X548771D01*
G01X546521Y278596D02*
X548771D01*
G01X546521Y243496D02*
X548771D01*
G01X546521Y235696D02*
X548771D01*
G01X543141Y225947D02*
X545391D01*
G01X543141Y222047D02*
X545391D01*
G01X543141Y233746D02*
X545391D01*
G01X549901Y241547D02*
X552151D01*
G01X549901Y249347D02*
X552151D01*
G01X560041Y243496D02*
X562591D01*
G01X553281Y247396D02*
X555531D01*
G01X549901Y229847D02*
X552151D01*
G01X556661D02*
X558911D01*
G01X560041Y235696D02*
X562500D01*
Y235685D01*
X564084D01*
G01X560041Y220096D02*
X562591D01*
G01X556661Y222047D02*
X558911D01*
G01X549901Y225947D02*
X552151D01*
G01X546521Y239596D02*
X548771D01*
G01X555531Y274696D02*
X556661Y275826D01*
Y276646D01*
G01X558911Y264947D02*
X556661D01*
G01X552151Y233746D02*
X556661D01*
G01X546521Y251296D02*
X548771D01*
G01X546521Y262996D02*
X548771D01*
G01X546521Y270796D02*
X548771D01*
G01X543141Y276646D02*
X545391D01*
G01X549901Y245447D02*
X552151D01*
G01X549901Y237647D02*
X552151D01*
G01X553281Y231797D02*
X555531D01*
G01X543141Y237647D02*
X545391D01*
G01X546521Y227896D02*
X548771D01*
G01X546521Y313696D02*
X548771D01*
G01X560041Y333196D02*
X562591D01*
G01X553281D02*
X555531D01*
G01X549901Y323446D02*
X552151D01*
G01X556661Y319547D02*
X559211D01*
G01X543141D02*
X545391D01*
G01X546521Y340996D02*
X548771D01*
G01X543141Y331247D02*
X545391D01*
G01X543141Y335147D02*
X545391D01*
G01X546521Y325396D02*
X548771D01*
G01X543141Y315647D02*
X545391D01*
G01X556661Y335147D02*
X558911D01*
G01X553281Y309797D02*
X555831D01*
G01X553281Y305896D02*
X555831D01*
G01X549901Y296147D02*
X552151D01*
G01X553281Y298096D02*
X555831D01*
G01X549901Y288347D02*
X552151D01*
G01X549901Y284447D02*
X552151D01*
G01X556661Y280547D02*
X559211D01*
G01X543141Y303947D02*
X545391D01*
G01X543141Y307847D02*
X545391D01*
G01X543141Y300047D02*
X545391D01*
G01X546521Y309797D02*
X548771D01*
G01X543141Y296147D02*
X545391D01*
G01X543141Y280547D02*
X545391D01*
G01X543141Y288347D02*
X545391D01*
G01X543141Y292247D02*
X545391Y292245D01*
G01X546521Y286396D02*
X548771D01*
G01X546521Y329296D02*
X548771D01*
G01X546521Y337096D02*
X548771D01*
G01X546521Y282496D02*
X548771D01*
G01X556661Y374146D02*
X559212D01*
G01X552151Y378047D02*
X549901D01*
G01X556661Y393647D02*
X559212D01*
G01X556661Y381947D02*
X558865D01*
X558912Y381900D01*
X559165D01*
X559212Y381947D01*
G01X553281Y387796D02*
X555530D01*
X555531Y387797D01*
G01X543141Y385847D02*
X545391D01*
G01X556661Y370247D02*
X559212D01*
G01X562591Y352696D02*
X560041D01*
G01X543141Y358547D02*
X545391D01*
G01X543141Y346847D02*
X545391D01*
G01X543141Y354647D02*
X545391D01*
G01X546521Y368296D02*
X548771D01*
G01X543141Y366347D02*
X545391D01*
G01X549901Y350747D02*
X552151D01*
G01X562591Y344896D02*
X560041D01*
G01X563200Y356596D02*
X560041D01*
G01X553281Y360496D02*
X554400Y359377D01*
Y358100D01*
X555904Y356596D01*
X560041D01*
G01X556661Y342947D02*
X558911D01*
G01X556661Y385847D02*
X559212D01*
G01X543141Y342947D02*
X545391D01*
G01X592216Y445152D02*
X598702Y438666D01*
X611234D01*
X619900Y430000D01*
X648091D01*
Y429925D01*
G01X649570Y3070D02*
Y943D01*
X647317Y-1310D01*
G01X659200Y31500D02*
X658700Y31000D01*
Y29100D01*
G01X660893Y35488D02*
X663162D01*
X664150Y34500D01*
G01X633308Y263808D02*
X634616Y262500D01*
X636800D01*
G01X639320Y268000D02*
Y271050D01*
G01X644066Y278324D02*
X645325D01*
X646641Y279640D01*
X646819D01*
X647487Y280308D01*
G01X646000Y275300D02*
Y276170D01*
X647469Y277639D01*
G01X652000Y284500D02*
X651500Y284000D01*
Y281600D01*
G01X647900Y286000D02*
X649800D01*
X652100Y288300D01*
G01X654221Y301548D02*
Y298879D01*
X654500Y298600D01*
G01X664066Y301548D02*
Y299466D01*
X663200Y298600D01*
G01X652252Y335948D02*
Y336748D01*
X649600Y339400D01*
X649000D01*
G01X649819Y315795D02*
X655195D01*
G01D02*
X655900Y316500D01*
G01X658500Y281600D02*
Y284500D01*
G01X640900Y286000D02*
X641634Y286734D01*
Y291366D01*
X637800Y295200D01*
G01X632869Y293720D02*
X634349Y295200D01*
X637800D01*
G01X649819Y333516D02*
Y335681D01*
X648900Y336600D01*
G01X649819Y317764D02*
X647364D01*
X646900Y317300D01*
G01X649819Y319733D02*
X647267D01*
X646900Y320100D01*
G01X656042Y287439D02*
X655500Y287981D01*
Y290000D01*
G01X658638Y287623D02*
X656226D01*
X656042Y287439D01*
G01X648091Y439925D02*
Y440000D01*
X644300D01*
X641900Y437600D01*
X640300D01*
G01X645230Y490250D02*
X647450D01*
X649600Y492400D01*
G01X656900Y482290D02*
Y483030D01*
G01D02*
X654800Y485130D01*
X652230D01*
G01X618430Y491550D02*
X619430Y492550D01*
X621930D01*
G01X632250Y487050D02*
X629300Y490000D01*
G01X655900Y587500D02*
X655400Y587000D01*
X653100D01*
G01X665795Y580430D02*
X658662D01*
X656099Y582993D01*
G01X712500Y21000D02*
Y21287D01*
X714823Y23610D01*
G01X676700Y12500D02*
Y10748D01*
X678161Y9287D01*
X680330D01*
G01D02*
X681787D01*
X683500Y11000D01*
G01X700500Y29000D02*
Y26600D01*
G01X722000Y16750D02*
X722139D01*
X724837Y14052D01*
Y13852D01*
G01X722968Y10652D02*
Y11983D01*
X724837Y13852D01*
G01X717063Y-652D02*
X715548D01*
X714300Y-1900D01*
G01X724937Y10652D02*
X726951D01*
X728200Y11901D01*
Y15050D01*
X726500Y16750D01*
G01X676700Y14469D02*
X678831D01*
X680200Y13100D01*
G01D02*
X681600Y14500D01*
X683500D01*
G01X665396Y20374D02*
Y23000D01*
G01X664300Y31550D02*
X664150Y31700D01*
Y34500D01*
G01X664300Y28050D02*
X667800D01*
G01X693250Y31000D02*
X693000Y30750D01*
X689500D01*
G01X691400Y25800D02*
Y27000D01*
X689500Y28900D01*
Y30750D01*
G01X699300Y36012D02*
Y34400D01*
X700500Y33200D01*
Y32500D01*
G01X719031Y10652D02*
Y13931D01*
X719400Y14300D01*
G01X676700Y18406D02*
X679936D01*
G01X696750Y31000D02*
Y25873D01*
X696803Y25820D01*
G01X696750Y34500D02*
Y31000D01*
G01X690100Y93200D02*
X695172Y98272D01*
X700465D01*
G01X685000Y50100D02*
X686416Y51516D01*
X688350D01*
G01X692610Y41350D02*
Y37240D01*
X693250Y36600D01*
Y34500D01*
G01X689500Y34250D02*
Y37900D01*
G01Y34250D02*
X686000D01*
G01X693250Y34500D02*
X691674D01*
X691424Y34250D01*
X689500D01*
G01X699300Y36012D02*
Y36913D01*
X697492Y38721D01*
G01X690642Y41350D02*
X690121D01*
X687500Y38729D01*
Y38173D01*
X686346Y37019D01*
X683895D01*
X682500Y35624D01*
Y34250D01*
G01X688350Y47579D02*
X685929D01*
X685000Y46650D01*
G01X688350Y45610D02*
X686639D01*
X685100Y44071D01*
Y43000D01*
G01X694579Y41350D02*
Y38200D01*
X696750Y36029D01*
Y34500D01*
G01X703965Y98272D02*
X701695Y96002D01*
X696502D01*
X693000Y92500D01*
G01X700465Y98272D02*
X704258Y102065D01*
X722987D01*
X724915Y100137D01*
X726376D01*
X727500Y101261D01*
Y104000D01*
G01X718916Y96188D02*
X722584D01*
X722630Y96234D01*
X725875D01*
X727500Y94609D01*
G01X711074Y99930D02*
X705573D01*
X703965Y98322D01*
Y98272D01*
G01X718000Y203100D02*
X718270D01*
X720369Y205199D01*
G01X722050Y221150D02*
X722300Y220900D01*
Y218100D01*
G01X709959Y214754D02*
X713336D01*
X714391Y215809D01*
G01X709959Y209439D02*
X712011D01*
X713175Y208275D01*
G01X709959Y212983D02*
X714739D01*
X715100Y213344D01*
G01X709959Y216526D02*
X712427D01*
X713845Y217944D01*
X715444D01*
X715700Y218200D01*
Y218267D01*
X715727D01*
G01D02*
X715894Y218100D01*
X718800D01*
G01X709959Y211211D02*
X712309D01*
X712768Y210752D01*
X714761D01*
G01X700900Y264100D02*
Y264500D01*
X701900Y265500D01*
X703500D01*
G01X702222Y223397D02*
Y226078D01*
X701700Y226600D01*
G01X707537Y223397D02*
X708465D01*
X709568Y224500D01*
X710500D01*
G01X703500Y262000D02*
X701500D01*
X700800Y261300D01*
G01X703994Y223397D02*
Y224893D01*
X704144Y225043D01*
Y226294D01*
X704450Y226600D01*
G01X707130Y310150D02*
Y305630D01*
X705000Y303500D01*
X701000D01*
G01X706300Y318400D02*
Y319282D01*
X703082Y322500D01*
X701000D01*
G01X672500Y281600D02*
X676000D01*
G01X672150Y288350D02*
X670500Y290000D01*
X669200D01*
X669000Y290200D01*
G01D02*
X668600Y290600D01*
Y293600D01*
X669200Y294200D01*
Y295000D01*
G01X676000Y281600D02*
X676200D01*
X676600Y282000D01*
X677950D01*
X678050Y281900D01*
X680000D01*
G01X684219Y315795D02*
X686005D01*
X686400Y315400D01*
X689540D01*
X692140Y318000D01*
X695400D01*
G01X681787Y335948D02*
Y336487D01*
X683500Y338200D01*
X684100D01*
G01X666900Y329700D02*
X665974Y330626D01*
G01D02*
Y335887D01*
X666035Y335948D01*
G01X687556Y295292D02*
Y294346D01*
X691762Y290140D01*
X692470D01*
G01D02*
X694360D01*
X695000Y289500D01*
G01X684219Y333516D02*
X684516D01*
X686600Y335600D01*
G01X684219Y319733D02*
X687300D01*
X687400Y319833D01*
G01X684219Y317764D02*
X686771D01*
X687138Y317397D01*
G01X677124Y295168D02*
Y294416D01*
X674208Y291500D01*
X673500D01*
G01X668004Y335948D02*
Y338896D01*
X667900Y339000D01*
G01X665500Y290200D02*
Y288200D01*
X668700Y285000D01*
G01X725400Y296950D02*
X724300D01*
X723300Y297950D01*
Y303161D01*
X730000Y309861D01*
Y319300D01*
X733000Y322300D01*
X740400D01*
G01X725400Y296950D02*
Y293900D01*
G01X688600Y365100D02*
Y366400D01*
X689900Y367700D01*
G01X690040Y412030D02*
Y410240D01*
X687527Y407727D01*
Y402676D01*
G01X698560Y374430D02*
X696208D01*
X695207Y375431D01*
Y379176D01*
G01X691270Y412030D02*
X695207Y408093D01*
Y402676D01*
G01X682272Y359140D02*
Y363701D01*
X683446Y364875D01*
Y364972D01*
X683417D01*
G01X677563Y365496D02*
X679400Y367333D01*
Y367700D01*
G01X679847Y402676D02*
X679850Y402679D01*
Y406922D01*
X683400Y410472D01*
Y411200D01*
G01X690040Y412030D02*
X687370Y414700D01*
X683400D01*
G01X690040Y412030D02*
X691270D01*
G01X687400Y411200D02*
X683400D01*
G01X727916Y499895D02*
X724552D01*
X723748Y499091D01*
G01X721319Y492800D02*
X732422D01*
X735122Y490100D01*
X739456D01*
X741333Y491977D01*
Y503558D01*
X742756Y504981D01*
X749162D01*
X754456Y499687D01*
X754459D01*
X754576Y499570D01*
X757602D01*
X758603Y498569D01*
Y495177D01*
G01X718546Y500283D02*
X718877Y499952D01*
Y495292D01*
X721319Y492850D01*
Y492800D01*
G01X682899Y534899D02*
X685766Y537766D01*
X688350D01*
G01X700500Y515250D02*
Y512850D01*
G01X671750Y512500D02*
Y509376D01*
X670516Y508142D01*
X667857D01*
G01X672400Y515750D02*
X669450D01*
X669400Y515700D01*
G01X667857Y508142D02*
Y510742D01*
X669400Y512285D01*
Y515700D01*
G01X675500Y515750D02*
Y512750D01*
X675250Y512500D01*
G01X672452Y505805D02*
X675250Y508603D01*
Y512500D01*
G01X689500Y517250D02*
Y513400D01*
X690600Y512300D01*
X691000D01*
G01D02*
X691400D01*
X693250Y514150D01*
Y517000D01*
G01Y521000D02*
X690950Y523300D01*
X690500D01*
G01X675500Y519250D02*
Y521900D01*
G01X672400Y519250D02*
X675500D01*
G01X689500Y520750D02*
X693000D01*
X693250Y521000D01*
G01X686000Y517750D02*
Y518200D01*
X688550Y520750D01*
X689500D01*
G01X692610Y527600D02*
Y525410D01*
X690500Y523300D01*
G01X696547Y527600D02*
Y525311D01*
X699088Y522770D01*
Y520862D01*
X700500Y519450D01*
Y518750D01*
G01X690642Y527600D02*
X688342Y525300D01*
Y523542D01*
X684600Y519800D01*
X684550D01*
X682500Y517750D01*
G01X696750Y521000D02*
Y517000D01*
G01X691332Y507278D02*
X696750Y512696D01*
Y517000D01*
G01X694579Y527600D02*
Y524398D01*
X696750Y522227D01*
Y521000D01*
G01X727916Y503637D02*
X724185D01*
X721894Y501346D01*
G01D02*
X721348Y500800D01*
Y498329D01*
X721319Y498300D01*
Y496300D01*
G01X690100Y575860D02*
X689300Y576660D01*
Y577300D01*
X688100Y578500D01*
X686500D01*
G01X719100Y572000D02*
X718900D01*
X716300Y569400D01*
G01X714600Y574500D02*
X712600Y572500D01*
Y571900D01*
G01X686599Y573493D02*
X689193D01*
G01X712600Y571900D02*
X711000Y573500D01*
Y574500D01*
G01X671447Y580430D02*
X665795D01*
G01X677099D02*
X671447D01*
G01X693126Y581380D02*
Y581473D01*
X692099Y582500D01*
X689690D01*
X689680Y582490D01*
G01X696600Y581400D02*
Y584000D01*
X692800Y587800D01*
X690000D01*
G01X699500Y542700D02*
X704434Y537766D01*
G01D02*
X710650D01*
G01X705800Y576400D02*
Y576800D01*
X707000Y578000D01*
X711000D01*
G01X716106Y584050D02*
Y583550D01*
X715106Y582550D01*
X713606D01*
X711000Y579944D01*
Y578000D01*
G01X677099Y576493D02*
X677507D01*
X680507Y573493D01*
X683099D01*
G01X692340Y572850D02*
X690740Y571250D01*
X684099D01*
X683099Y572250D01*
Y573493D01*
G01X718075Y584050D02*
Y581125D01*
X718200Y581000D01*
G01D02*
X717056D01*
X714600Y578544D01*
Y578000D01*
G01X677099Y578462D02*
X679070D01*
X680029Y577503D01*
G01D02*
X682003D01*
X683000Y578500D01*
G01X665795Y584367D02*
Y592305D01*
X668260Y594770D01*
G01X688350Y531860D02*
X686410D01*
X685200Y530650D01*
Y530500D01*
G01X684500Y532900D02*
X685429Y533829D01*
X688350D01*
G01X719100Y577500D02*
X721500D01*
X722500Y578500D01*
Y580900D01*
G01X722012Y584050D02*
Y581788D01*
X722500Y581300D01*
Y580900D01*
G01X684180Y582490D02*
X683690Y582000D01*
X680910D01*
G01D02*
X680761Y582149D01*
X677349D01*
X677099Y582399D01*
G01X720043Y589702D02*
Y595354D01*
G01D02*
Y599883D01*
X722606Y602446D01*
G01D02*
Y605050D01*
G01X668260Y594770D02*
Y596132D01*
X665892Y598500D01*
X665000D01*
G01X786364Y16900D02*
X791274D01*
X791488Y17114D01*
G01X729500Y23500D02*
X732198Y20802D01*
Y11602D01*
X734852Y8948D01*
Y2656D01*
X732316Y120D01*
G01D02*
Y-1587D01*
G01X769881Y92500D02*
X766389D01*
X766000Y92111D01*
G01X727500Y94609D02*
Y93000D01*
G01X775966Y215136D02*
Y213577D01*
X774582Y212193D01*
Y212033D01*
G01X783317Y211600D02*
X781281Y213636D01*
Y215136D01*
G01X779510D02*
Y212455D01*
X779932Y212033D01*
G01X774195Y215136D02*
X773267D01*
X772164Y214033D01*
X771232D01*
G01X777738Y215136D02*
Y212589D01*
X777182Y212033D01*
G01X776232Y209533D02*
Y205368D01*
X777100Y204500D01*
G01X763250Y235500D02*
X760631D01*
X760304Y235827D01*
G01D02*
Y237047D01*
X762799Y239542D01*
X764341D01*
G01X775966Y279136D02*
Y277566D01*
X772519Y274119D01*
Y272931D01*
G01X775966Y247136D02*
Y245466D01*
X772351Y241851D01*
Y240966D01*
G01X761600Y245520D02*
Y242840D01*
X761480Y242720D01*
G01X761850Y275560D02*
Y270879D01*
X762616Y270113D01*
G01X783045Y272906D02*
Y275056D01*
X781281Y276820D01*
Y279136D01*
G01X766532Y254652D02*
X766632Y254752D01*
X767908D01*
X768935Y255779D01*
X771773D01*
G01X779510Y247136D02*
Y244455D01*
X779932Y244033D01*
G01X771773Y223779D02*
X768001D01*
X766811Y222589D01*
X766632D01*
G01X779510Y279136D02*
Y276619D01*
X779400Y276509D01*
Y276200D01*
G01X779985Y240623D02*
Y243980D01*
X779932Y244033D01*
G01X774195Y279136D02*
X773267D01*
X772582Y278451D01*
X771650D01*
G01X774195Y247136D02*
X773267D01*
X772582Y246451D01*
X771650D01*
G01X768743Y230057D02*
X769706Y229094D01*
X771773D01*
G01Y261094D02*
X770106D01*
X768100Y263100D01*
G01X777738Y247136D02*
Y244238D01*
X777000Y243500D01*
G01X771773Y225550D02*
X767205D01*
X766844Y225189D01*
X766732D01*
G01X766632Y257252D02*
X766930Y257550D01*
X771773D01*
G01X731662Y247716D02*
Y245421D01*
X730241Y244000D01*
X728291D01*
G01X776019Y272931D02*
Y274819D01*
X776700Y275500D01*
G01X777738Y279136D02*
Y277138D01*
X776700Y276100D01*
Y275500D01*
G01X751300Y247600D02*
Y227288D01*
X758428Y220160D01*
X761580D01*
G01X771773Y254007D02*
X769349D01*
X767631Y252289D01*
X765081D01*
X765007Y252363D01*
G01X761580Y220160D02*
X761764Y220344D01*
X767686D01*
X769349Y222007D01*
X771773D01*
G01X751300Y247600D02*
X755066Y251366D01*
X757003D01*
X758000Y252363D01*
G01D02*
X757549Y252814D01*
Y254882D01*
X755413Y257018D01*
Y262287D01*
X754200Y263500D01*
Y267857D01*
X759220Y272877D01*
Y277151D01*
X755889Y280482D01*
Y283016D01*
X756726Y283853D01*
G01X758000Y252363D02*
X765007D01*
G01X766800Y228000D02*
X767478Y227322D01*
X771773D01*
G01X767300Y260105D02*
X769095D01*
X769878Y259322D01*
X771773D01*
G01X774347Y339983D02*
X775966Y341602D01*
Y343136D01*
G01X758917Y316392D02*
X756297D01*
X756114Y316209D01*
G01X765730Y335064D02*
X765726Y335068D01*
X764311D01*
X763200Y333957D01*
Y331900D01*
G01X763232Y299033D02*
X762842Y299423D01*
Y302434D01*
G01X775966Y311136D02*
Y309566D01*
X774400Y308000D01*
X771360D01*
X771278Y307918D01*
G01X762350Y343730D02*
Y339910D01*
X762760Y339500D01*
G01X779510Y311136D02*
Y308310D01*
X779100Y307900D01*
G01X779510Y343136D02*
Y340455D01*
X779932Y340033D01*
G01X771773Y287779D02*
X768579D01*
X767530Y286730D01*
X767510D01*
X767310Y286530D01*
G01X771773Y319779D02*
X768001D01*
X767000Y318778D01*
Y318500D01*
G01X774195Y311136D02*
X773267D01*
X772731Y310600D01*
X771600D01*
G01X777738Y343136D02*
Y340589D01*
X777182Y340033D01*
G01X771773Y289550D02*
X767790D01*
X766850Y288610D01*
X766580D01*
X765950Y287980D01*
X764980D01*
G01X771773Y321550D02*
X767205D01*
X766844Y321189D01*
X766732D01*
G01X768803Y293897D02*
X769606Y293094D01*
X771773D01*
G01X768682Y326318D02*
X769906Y325094D01*
X771773D01*
G01X777738Y311136D02*
Y309338D01*
X776270Y307870D01*
Y307100D01*
G01X740400Y322300D02*
X745982Y327882D01*
X751998D01*
X760066Y335950D01*
Y348346D01*
X761450Y349730D01*
X763640D01*
X765007Y348363D01*
G01X756726Y283853D02*
X756176Y284403D01*
Y286916D01*
X752269Y290823D01*
Y314864D01*
X750113Y317020D01*
G01X765007Y316363D02*
Y317522D01*
X763129Y319400D01*
X752493D01*
X750113Y317020D01*
G01X771773Y318007D02*
X769349D01*
X767631Y316289D01*
X765081D01*
X765007Y316363D01*
G01X771773Y286007D02*
X770237D01*
X768519Y284289D01*
X765081D01*
X765007Y284363D01*
G01X756726Y283853D02*
X759014D01*
X760639Y285478D01*
X763882D01*
X764997Y284363D01*
X765007D01*
G01X740400Y322300D02*
X745680Y317020D01*
X750113D01*
G01X728900Y296950D02*
X728800Y296850D01*
Y294300D01*
G01X728900Y296950D02*
X730450D01*
X731600Y298100D01*
Y303700D01*
X733900Y306000D01*
X741700D01*
X743600Y304100D01*
G01X771773Y291322D02*
X766162D01*
X765850Y291010D01*
G01X771773Y323322D02*
X769612D01*
X769276Y323658D01*
X768230D01*
G01X758952Y380738D02*
Y384100D01*
G01X775916Y375136D02*
Y373516D01*
X774376Y371976D01*
X772443D01*
G01X763232Y363033D02*
X760354D01*
X760140Y362819D01*
G01X783182Y369533D02*
Y371618D01*
X781231Y373569D01*
Y375136D01*
G01X771773Y351779D02*
X768477D01*
X767477Y350779D01*
Y350708D01*
G01X771723Y383779D02*
X769016D01*
X767961Y382724D01*
X766643D01*
G01X779460Y375136D02*
Y373436D01*
X779882Y373014D01*
Y372033D01*
G01X774195Y343136D02*
X773267D01*
X772632Y342501D01*
X771700D01*
G01X774145Y375136D02*
X773217D01*
X772481Y374400D01*
X771400D01*
G01X768674Y357926D02*
X769506Y357094D01*
X771773D01*
G01Y353550D02*
X767205D01*
X766844Y353189D01*
X766732D01*
G01X771723Y389094D02*
X769373D01*
X768215Y390252D01*
Y391485D01*
G01X767155Y385550D02*
X771723D01*
G01X777688Y375136D02*
Y373188D01*
X777100Y372600D01*
Y372000D01*
G01X771773Y350007D02*
X769679D01*
X767961Y348289D01*
X765081D01*
X765007Y348363D01*
G01X771723Y382007D02*
X769659D01*
X767941Y380289D01*
X765031D01*
X764957Y380363D01*
G01X766700Y355850D02*
X768650D01*
X769178Y355322D01*
X771773D01*
G01X767746Y387954D02*
X768378Y387322D01*
X771723D01*
G01X728091Y454925D02*
X728100D01*
G01X728091Y449925D02*
X728100Y450000D01*
Y454925D01*
G01D02*
Y455000D01*
X728940Y457806D01*
G01X753000Y512000D02*
Y515470D01*
X752496Y515974D01*
G01X758603Y506177D02*
Y502381D01*
X757792Y501570D01*
X755405D01*
X749975Y507000D01*
X741809D01*
X739309Y504500D01*
Y500591D01*
X738613Y499895D01*
X735758D01*
G01X726500Y574000D02*
X727400Y573100D01*
Y571300D01*
G01X753343Y589678D02*
Y585993D01*
X752500Y585150D01*
G01X753343Y551878D02*
Y554833D01*
X754910Y556400D01*
G01X786364Y555700D02*
X791274D01*
X791488Y555914D01*
G01X726800Y604000D02*
Y606400D01*
X727000Y606600D01*
G01X791464Y9100D02*
X796639D01*
X796653Y9114D01*
G01Y46914D02*
X791464Y46900D01*
G01X828275D02*
X833450D01*
X833464Y46914D01*
G01X828299Y54914D02*
X823389D01*
X823175Y54700D01*
G01X816582Y46914D02*
X823183D01*
X823199Y46898D01*
G01X824000Y202292D02*
Y205200D01*
G01X863850Y224150D02*
X836492Y196792D01*
X824000D01*
G01X840871Y391380D02*
X840629D01*
X839797Y392212D01*
Y394551D01*
X835277Y399071D01*
X822653D01*
X821483Y400241D01*
Y404622D01*
X819605Y406500D01*
X817500D01*
X816500Y407500D01*
X815500D01*
G01X837272Y391420D02*
X837560D01*
X838297Y392157D01*
Y393929D01*
X834655Y397571D01*
X822031D01*
X819983Y399619D01*
Y404000D01*
X818983Y405000D01*
X817500D01*
X816500Y404000D01*
X815500D01*
G01X796653Y547914D02*
X791464Y547900D01*
G01X901921Y17114D02*
X897011D01*
X896797Y16900D01*
G01X916337Y269560D02*
X909260D01*
X863850Y224150D01*
G01X943377Y199360D02*
X944507Y201309D01*
G01X939997Y197409D02*
X941127Y199360D01*
G01X939997Y216909D02*
X937747D01*
G01X956897Y211060D02*
X954647D01*
G01X950137Y207159D02*
X947887D01*
G01X950137Y203260D02*
X947887D01*
G01X946757Y213009D02*
X944507D01*
G01X943377Y214960D02*
X941127D01*
G01X943377Y207159D02*
X941127D01*
G01X950137Y199360D02*
X947887D01*
G01Y211060D02*
X950137D01*
G01X960276Y213009D02*
X958026D01*
G01X953517Y209109D02*
X951267D01*
G01X963656Y211060D02*
X961406D01*
G01X963656Y214960D02*
X961406D01*
G01X963656Y203260D02*
X962526Y205210D01*
G01X956897Y203260D02*
X958026Y201309D01*
G01X953517Y197409D02*
Y196817D01*
X951574Y194874D01*
X951256Y194841D01*
G01X967036Y216909D02*
X964786D01*
G01X967036Y213009D02*
X964786D01*
G01X967036Y209109D02*
X964786D01*
G01X923097Y211060D02*
X920847D01*
G01X929857Y214960D02*
X927607D01*
G01X929857Y203260D02*
X927607D01*
G01X916337Y211060D02*
X917768D01*
X919717Y213009D01*
G01X933237D02*
X930987D01*
G01X936617Y214960D02*
X934367D01*
G01X936617Y207159D02*
X934367D01*
G01X929857D02*
X927607D01*
G01X933237Y201309D02*
X930987D01*
G01X936617Y199360D02*
X934367D01*
G01X926477Y213009D02*
X924227D01*
G01X929857Y211060D02*
X927607D01*
G01X941127Y199360D02*
X943377D01*
G01X944507Y201309D02*
X946757D01*
G01X924227Y216909D02*
X919717D01*
G01X920847Y211060D02*
X920008Y212508D01*
X919717Y213009D01*
G01Y236409D02*
X924227D01*
G01X939997Y252009D02*
X937747D01*
G01X939997Y271509D02*
X937747D01*
G01X939997Y275409D02*
X937747D01*
G01X939997Y255909D02*
X937747D01*
G01X960276Y252009D02*
X958026D01*
G01X953517Y267609D02*
X951267D01*
G01X963656Y269560D02*
X961406D01*
G01X956897D02*
X954647D01*
G01X963656Y277360D02*
X961406D01*
G01X960276Y275409D02*
X958026D01*
G01X956897Y273460D02*
X954647D01*
G01X956897Y277360D02*
X954647D01*
G01X953517Y275409D02*
X951267D01*
G01X960276Y259809D02*
X958026D01*
G01X953517D02*
X951267D01*
G01X960276Y255909D02*
X958026D01*
G01X963656Y261760D02*
X961406D01*
G01X973796Y263709D02*
X971546D01*
G01X970416Y269560D02*
X968166D01*
G01X967036Y279310D02*
X964786D01*
G01X950137Y277360D02*
X947887D01*
G01X946757Y263709D02*
X944507D01*
G01X943377Y265660D02*
X941127D01*
G01X950137D02*
X947887D01*
G01X950137Y253960D02*
X947887D01*
G01X946757Y275409D02*
X944507D01*
G01X943377Y277360D02*
X941127D01*
G01X943377Y261760D02*
X941127D01*
G01X943377Y257860D02*
X941127D01*
G01X943377Y253960D02*
X941127D01*
G01X943377Y269560D02*
X941127D01*
G01X970416Y277360D02*
X968166D01*
G01X973796Y275409D02*
X971546D01*
G01X973796Y255909D02*
X971546D01*
G01X973796Y259809D02*
X971546D01*
G01X956897Y265660D02*
X954647D01*
G01X960276Y263709D02*
X958026D01*
G01X939997Y236409D02*
X937747D01*
G01X939997Y232509D02*
X937747D01*
G01X960276D02*
X958026D01*
G01X956897Y218860D02*
X954647D01*
G01X946757Y224709D02*
X944507D01*
G01X946757Y228610D02*
X944507D01*
G01X943377Y222760D02*
X941127D01*
G01X943377Y218860D02*
X941127D01*
G01X943377Y226660D02*
X941127D01*
G01X943377Y230559D02*
X941127D01*
G01X943377Y234460D02*
X941127D01*
G01X943377Y238360D02*
X941127D01*
G01X950137Y234460D02*
X947887D01*
G01X950137Y218860D02*
X947887D01*
G01X950137Y226660D02*
X947887D01*
G01X946757Y248109D02*
X944507D01*
G01X946757Y244209D02*
X944507D01*
G01X943377Y246160D02*
X941127D01*
G01X943377Y250060D02*
X941127D01*
G01X950137Y246160D02*
X947887D01*
G01X943377Y242260D02*
X941127D01*
G01X956897Y226660D02*
X954647D01*
G01X970416Y246160D02*
X968166D01*
G01X960276Y244209D02*
X958026D01*
G01X953517Y248109D02*
X951267D01*
G01X956897Y250060D02*
X954647D01*
G01X956897Y246160D02*
X954647D01*
G01X967036Y240309D02*
X964786D01*
G01X960276D02*
X958026D01*
G01X953517D02*
X951267D01*
G01X970416Y242260D02*
X968166D01*
G01X973796Y248109D02*
X971546D01*
G01X963656Y238360D02*
X961406D01*
G01X960276Y236409D02*
X958026D01*
G01X960276Y224709D02*
X958026D01*
G01X963656Y218860D02*
X961406D01*
G01X963656Y222760D02*
X961406D01*
G01X956897Y230559D02*
X954647D01*
G01X953517Y228610D02*
X951267D01*
G01X960276D02*
X958026D01*
G01X970416Y238360D02*
X968166D01*
G01X973796Y236409D02*
X971546D01*
G01X970416Y218860D02*
X968166D01*
G01X967036Y220809D02*
X964786D01*
G01X967036Y232509D02*
X964786D01*
G01X973796Y220809D02*
X971546D01*
G01X970416Y226660D02*
X968166D01*
G01X933237Y252009D02*
X930987D01*
G01X926477D02*
X924227D01*
G01X919717D02*
X917467D01*
G01X926477Y259809D02*
X924227D01*
G01X936617Y253960D02*
X934367D01*
G01X926477Y255909D02*
X924227D01*
G01X916337Y253960D02*
X913787D01*
G01X919717Y259809D02*
X917467D01*
G01X936617Y273460D02*
X934367D01*
G01X933237Y271509D02*
X930987D01*
G01X936617Y277360D02*
X934367D01*
G01X933237Y275409D02*
X930987D01*
G01X926477Y263709D02*
X924227D01*
G01X923097Y273460D02*
X920847D01*
G01X929857Y277360D02*
X927607D01*
G01X926477Y275409D02*
X924227D01*
G01X936617Y265660D02*
X934367D01*
G01X923097D02*
X920847D01*
G01X926477Y267609D02*
X924227D01*
G01X916337Y265660D02*
X913787D01*
G01X919717Y263709D02*
X917467D01*
G01X929857Y269560D02*
X927607D01*
G01X923097D02*
X920847D01*
G01X929857Y253960D02*
X927607D01*
G01X933237Y259809D02*
X930987D01*
G01X933237Y220809D02*
X930987D01*
G01X926477Y228610D02*
X924227D01*
G01X936617Y246160D02*
X934367D01*
G01X926477Y244209D02*
X924227D01*
G01X926477Y248109D02*
X924227D01*
G01X929857Y250060D02*
X927607D01*
G01X916337D02*
X913787D01*
G01X933237Y240309D02*
X930987D01*
G01X926477D02*
X924227D01*
G01X919717D02*
X917467D01*
G01X919717Y244209D02*
X917467D01*
G01X936617Y234460D02*
X934367D01*
G01X933237Y232509D02*
X930987D01*
G01X929857Y234460D02*
X927607D01*
G01X929857Y230559D02*
X927607D01*
G01X923097Y238360D02*
X920847D01*
G01X916337D02*
X913787D01*
G01X916337Y222760D02*
X913750D01*
X913700Y222710D01*
G01X916337Y226660D02*
X913787D01*
G01X936617D02*
X934367D01*
G01X926477Y220809D02*
X924227D01*
G01Y224709D02*
X919717D01*
G01X924227Y232509D02*
X919717D01*
G01X924227Y236409D02*
X926477D01*
G01X937747Y279310D02*
X939997D01*
G01X958026D02*
X960276D01*
G01X953517D02*
X951267D01*
G01X946757D02*
X944507D01*
G01X919717D02*
X916967D01*
G01X933237D02*
X930987D01*
G01X926477D02*
X924227D01*
G01X923097Y277360D02*
X920847D01*
G01X917000Y276000D02*
X917591Y275409D01*
X919717D01*
G01Y267609D02*
X918288D01*
X916337Y269560D01*
G01X939997Y318309D02*
X937747D01*
G01X939997Y326110D02*
X937747D01*
G01X970416Y312460D02*
X968166D01*
G01X963656Y316360D02*
X961406D01*
G01X956897D02*
X954647D01*
G01X953517Y318309D02*
X951267D01*
G01X960276D02*
X958026D01*
G01X960276Y326110D02*
X958026D01*
G01X960276Y333909D02*
X958026D01*
G01X960276Y337809D02*
X958026D01*
G01X953517D02*
X951267D01*
G01X973796D02*
X971546D01*
G01X967036Y322209D02*
X964786D01*
G01X970416Y320260D02*
X968166D01*
G01X967036Y314409D02*
X964786D01*
G01X967036Y330009D02*
X964786D01*
G01X973796D02*
X971546D01*
G01X973796Y322209D02*
X971546D01*
G01X956897Y328060D02*
X954647D01*
G01X956897Y331960D02*
X954647D01*
G01X953517Y330009D02*
X951267D01*
G01X943377Y331960D02*
X941127D01*
G01X950137Y316360D02*
X947887D01*
G01X946757Y318309D02*
X944507D01*
G01X946757Y322209D02*
X944507D01*
G01X943377Y316360D02*
X941127D01*
G01X943377Y328060D02*
X941127D01*
G01X946757Y333909D02*
X944507D01*
G01X950137Y331960D02*
X947887D01*
G01X950137Y328060D02*
X947887D01*
G01X943377Y339760D02*
X941127D01*
G01X943377Y335860D02*
X941127D01*
G01X960276Y330009D02*
X958026D01*
G01X963656Y324160D02*
X961406D01*
G01X963656Y292959D02*
X961406D01*
G01X956897Y285160D02*
X954647D01*
G01X956897Y292959D02*
X954647D01*
G01X950137D02*
X947887D01*
G01X943377D02*
X941127D01*
G01X943377Y285160D02*
X941127D01*
G01X943377Y308560D02*
X941127D01*
G01X950137D02*
X947887D01*
G01X943377Y300760D02*
X941127D01*
G01X950137Y285160D02*
X947887D01*
G01X950137Y300760D02*
X947887D01*
G01X967036Y283209D02*
X964786D01*
G01X970416Y292959D02*
X968166D01*
G01X970416Y281260D02*
X968166D01*
G01X973796Y283209D02*
X971546D01*
G01X963656Y285160D02*
X961406D01*
G01X963656Y308560D02*
X961406D01*
G01X956897D02*
X954647D01*
G01X967036Y310509D02*
X964786D01*
G01X973796D02*
X971546D01*
G01X956897Y300760D02*
X954647D01*
G01X963656D02*
X961406D01*
G01X970416D02*
X968166D01*
G01X926477Y330009D02*
X924227D01*
G01X933237Y326110D02*
X930987D01*
G01X926477Y337809D02*
X924227D01*
G01X929857Y328060D02*
X927607D01*
G01X933237Y337809D02*
X930987D01*
G01X936617Y331960D02*
X934367D01*
G01X926477Y326110D02*
X924227D01*
G01X919717Y330009D02*
X917467D01*
G01X923097Y328060D02*
X920847D01*
G01X916337D02*
X913787D01*
G01X919717Y333909D02*
X917467D01*
G01X916337Y339760D02*
X913787D01*
G01X926477Y333909D02*
X924227D01*
G01X936617Y324160D02*
X934367D01*
G01X929857Y316360D02*
X927607D01*
G01X936617D02*
X934367D01*
G01X933237Y318309D02*
X930987D01*
G01X929857Y320260D02*
X927607D01*
G01X926477Y322209D02*
X924227D01*
G01X936617Y308560D02*
X934367D01*
G01X929857D02*
X927607D01*
G01X929857Y300760D02*
X927607D01*
G01X936617D02*
X934367D01*
G01X936617Y292959D02*
X934367D01*
G01X929857D02*
X927607D01*
G01X929857Y285160D02*
X927607D01*
G01X936617D02*
X934367D01*
G01X937747Y314409D02*
X939997D01*
G01X950137Y312460D02*
X947887D01*
G01X943377D02*
X941127D01*
G01X956897D02*
X954647D01*
G01X963656D02*
X961406D01*
G01X946757Y314409D02*
X944507D01*
G01X953517D02*
X951267D01*
G01X958026D02*
X960276D01*
G01X937747Y287109D02*
X939997D01*
G01X937747Y294909D02*
X939997D01*
G01X937747Y298809D02*
X939997D01*
G01X937747Y283209D02*
X939997D01*
G01X937747Y291009D02*
X939997D01*
G01X937747Y302709D02*
X939997D01*
G01X937747Y306609D02*
X939997D01*
G01X937747Y310509D02*
X939997D01*
G01X950137Y281260D02*
X947887D01*
G01X950137Y296860D02*
X947887D01*
G01X946757Y298809D02*
X944507D01*
G01X946757Y294909D02*
X944507D01*
G01X943377Y296860D02*
X941127D01*
G01X950137Y304660D02*
X947887D01*
G01X946757Y306609D02*
X944507D01*
G01X943377Y304660D02*
X941127D01*
G01X946757Y310509D02*
X944507D01*
G01X946757Y302709D02*
X944507D01*
G01X956897Y304660D02*
X954647D01*
G01X963656D02*
X961406D01*
G01X958026Y310509D02*
X960276D01*
G01X953517D02*
X951267D01*
G01X958026Y306609D02*
X960276D01*
G01X953517D02*
X951267D01*
G01X953517Y302709D02*
X951267D01*
G01X958026D02*
X960276D01*
G01X973796D02*
X971546D01*
G01X967036D02*
X964786D01*
G01X970416Y308560D02*
X968166D01*
G01X970416Y304660D02*
X968166D01*
G01X973796Y306609D02*
X971546D01*
G01X953517Y287109D02*
X951267D01*
G01X956897Y296860D02*
X954647D01*
G01X958026Y298809D02*
X960276D01*
G01X953517D02*
X951267D01*
G01X967036Y294909D02*
X964786D01*
G01X967036Y298809D02*
X964786D01*
G01X973796D02*
X971546D01*
G01X973796Y294909D02*
X971546D01*
G01X970416Y296860D02*
X968166D01*
G01X967036Y287109D02*
X964786D01*
G01X958026Y283209D02*
X960276D01*
G01X956897Y281260D02*
X954647D01*
G01X963656D02*
X961406D01*
G01X953517Y283209D02*
X951267D01*
G01X963656Y289060D02*
X961406D01*
G01X958026Y287109D02*
X960276D01*
G01X958026Y291009D02*
X960276D01*
G01X953517D02*
X951267D01*
G01X956897Y289060D02*
X954647D01*
G01X970416D02*
X968166D01*
G01X967036Y306609D02*
X964786D01*
G01X950137Y289060D02*
X947887D01*
G01X946757Y287109D02*
X944507D01*
G01X946757Y291009D02*
X944507D01*
G01X943377Y289060D02*
X941127D01*
G01X943377Y281260D02*
X941127D01*
G01X946757Y283209D02*
X944507D01*
G01X973796Y291009D02*
X971546D01*
G01X973796Y287109D02*
X971546D01*
G01X967036Y291009D02*
X964786D01*
G01X958026Y294909D02*
X960276D01*
G01X953517D02*
X951267D01*
G01X963656Y296860D02*
X961406D01*
G01X936617Y312460D02*
X934367D01*
G01X929857D02*
X927607D01*
G01X923097Y324160D02*
X920847D01*
G01X919717Y326110D02*
X917467D01*
G01X926477Y314409D02*
X924227D01*
G01X923097Y320260D02*
X920847D01*
G01X919717Y322209D02*
X917167D01*
G01X919717Y318309D02*
X917167D01*
G01X926477D02*
X924227D01*
G01X933237Y314409D02*
X930987D01*
G01X936617Y289060D02*
X934367D01*
G01X936617Y296860D02*
X934367D01*
G01X933237Y294909D02*
X930987D01*
G01X929857Y296860D02*
X927607D01*
G01X926477Y298809D02*
X924227D01*
G01X933237D02*
X930987D01*
G01X923097Y292959D02*
X920500D01*
G01X923097Y296860D02*
X920500D01*
G01X923097Y289060D02*
X920500D01*
G01X933237Y283209D02*
X930987D01*
G01X936617Y281260D02*
X934367D01*
G01X929857D02*
X927607D01*
G01X926477Y283209D02*
X924227D01*
G01X923097Y281260D02*
X920847D01*
G01X933237Y302709D02*
X930987D01*
G01X926477D02*
X924227D01*
G01X929857Y304660D02*
X927607D01*
G01X926477Y306609D02*
X924227D01*
G01X926477Y310509D02*
X924227D01*
G01X923097Y308560D02*
X920500D01*
G01X933237Y306609D02*
X930987D01*
G01X936617Y304660D02*
X934367D01*
G01X933237Y310509D02*
X930987D01*
G01X923097Y304660D02*
X920500D01*
G01X923097Y300760D02*
X920500D01*
G01X926477Y287109D02*
X924227D01*
G01X933237D02*
X930987D01*
G01X926477Y291009D02*
X924227D01*
G01X933237D02*
X930987D01*
G01X929857Y289060D02*
X927607D01*
G01X920547Y316160D02*
X920747Y316360D01*
X923097D01*
G01X920500Y311960D02*
X922597D01*
X923097Y312460D01*
G01X920500Y285500D02*
X920840Y285160D01*
X923097D01*
G01X953517Y326110D02*
X951267D01*
G01X960276Y322209D02*
X958026D01*
G01X956897Y320260D02*
X954647D01*
G01X963656D02*
X961406D01*
G01X956897Y324160D02*
X954647D01*
G01X953517Y322209D02*
X951267D01*
G01X967036Y318309D02*
X964786D01*
G01X973796D02*
X971546D01*
G01X970416Y316360D02*
X968166D01*
G01X973796Y314409D02*
X971546D01*
G01X929857Y367060D02*
X927607D01*
G01X929857Y386560D02*
X927607D01*
G01X967036Y400209D02*
X970416Y401941D01*
G01X939997Y400209D02*
X937747D01*
G01X939997Y380709D02*
X937747D01*
G01X960276Y372909D02*
X958026D01*
G01X946757D02*
X944507D01*
G01X946757Y396309D02*
X944507D01*
G01X950137Y390460D02*
X947887D01*
G01X950137Y386560D02*
X947887D01*
G01X950137Y394359D02*
X947887D01*
G01X943377Y390460D02*
X941127D01*
G01X950137Y378760D02*
X947887D01*
G01X943377Y374860D02*
X941127D01*
G01X943377Y382660D02*
X941127D01*
G01X943377Y378760D02*
X941127D01*
G01X970416Y390460D02*
X968166D01*
G01X973796Y380709D02*
X971546D01*
G01X960276Y384609D02*
X958026D01*
G01X963656Y378760D02*
X961406D01*
G01X963656Y382660D02*
X961406D01*
G01X973796Y376809D02*
X971546D01*
G01X967036D02*
X964786D01*
G01X970416Y378760D02*
X968166D01*
G01X970416Y382660D02*
X968166D01*
G01X956897Y386560D02*
X958026Y388509D01*
G01X963656Y386560D02*
X961406D01*
G01X956897Y394359D02*
X954647D01*
G01X963656D02*
X964786Y392410D01*
G01X953517Y388509D02*
X951267D01*
G01X963656Y374860D02*
X961406D01*
G01X956897Y378760D02*
X954647D01*
G01X967036Y388509D02*
X964786D01*
G01X970416Y386560D02*
X968166D01*
G01X970416Y394359D02*
X968166D01*
G01X953517Y400209D02*
X952216Y402421D01*
G01X946757Y384609D02*
X944507D01*
G01X950137Y398260D02*
X947887D01*
G01X941127D02*
X943377D01*
G01X939997Y341709D02*
X937747D01*
G01X939997Y345609D02*
X937747D01*
G01X939997Y361209D02*
X937747D01*
G01X939997Y365109D02*
X937747D01*
G01X960276Y357309D02*
X958026D01*
G01X953517D02*
X951267D01*
G01X960276Y345609D02*
X958026D01*
G01X953517Y349509D02*
X951267D01*
G01X956897Y351460D02*
X954647D01*
G01X960276Y353409D02*
X958026D01*
G01X956897Y347560D02*
X954647D01*
G01X963656Y359260D02*
X961406D01*
G01X960276Y341709D02*
X958026D01*
G01X970416Y355360D02*
X968166D01*
G01X970416Y351460D02*
X968166D01*
G01X967036Y357309D02*
X964786D01*
G01X973796Y349509D02*
X971546D01*
G01X970416Y359260D02*
X968166D01*
G01X967036Y365109D02*
X964786D01*
G01X970416Y370959D02*
X968166D01*
G01X960276Y365109D02*
X958026D01*
G01X953517Y369010D02*
X951267D01*
G01X956897Y370959D02*
X954647D01*
G01X956897Y367060D02*
X954647D01*
G01X960276Y369010D02*
X958026D01*
G01X973796Y361209D02*
X971546D01*
G01X960276D02*
X958026D01*
G01X950137Y351460D02*
X947887D01*
G01X943377Y355360D02*
X941127D01*
G01X943377Y347560D02*
X941127D01*
G01X943377Y351460D02*
X941127D01*
G01X943377Y359260D02*
X941127D01*
G01X950137Y343660D02*
X947887D01*
G01X946757Y349509D02*
X944507D01*
G01X946757Y353409D02*
X944507D01*
G01X943377Y343660D02*
X941127D01*
G01X950137Y370959D02*
X947887D01*
G01X943377D02*
X941127D01*
G01X943377Y367060D02*
X941127D01*
G01X946757Y369010D02*
X944507D01*
G01X943377Y363160D02*
X941127D01*
G01X950137D02*
X947887D01*
G01X926477Y372909D02*
X924227D01*
G01X936617Y382660D02*
X934367D01*
G01X933237Y384609D02*
X930987D01*
G01X929857Y394359D02*
X927607D01*
G01X929857Y390460D02*
X927607D01*
G01X933237Y396309D02*
X930987D01*
G01X936617Y398260D02*
X934367D01*
G01X936617Y390460D02*
X934367D01*
G01X919717Y388509D02*
X917467D01*
G01X923097Y390460D02*
X920847D01*
G01X926477Y392410D02*
X924227D01*
G01X933237Y376809D02*
X930987D01*
G01X919717Y380709D02*
X917100D01*
G01X926477Y376809D02*
X924227D01*
G01X926477Y380709D02*
X924227D01*
G01X923097Y382660D02*
X920847D01*
G01X929857D02*
X927607D01*
G01X933237Y345609D02*
X930987D01*
G01X929857Y347560D02*
X927607D01*
G01X936617Y351460D02*
X934367D01*
G01X919717Y353409D02*
X917467D01*
G01X919717Y349509D02*
X917467D01*
G01X916337Y355360D02*
X913787D01*
G01X926477Y357309D02*
X924227D01*
G01X923097Y355360D02*
X920847D01*
G01X926477Y349509D02*
X924227D01*
G01X926477Y345609D02*
X924227D01*
G01X936617Y370959D02*
X934367D01*
G01X933237Y365109D02*
X930987D01*
G01X919717Y369010D02*
X917167D01*
G01X926477D02*
X924227D01*
G01X926477Y365109D02*
X924227D01*
G01X936617Y363160D02*
X934367D01*
G01X929857D02*
X927607D01*
G01X919717Y361209D02*
X917167D01*
G01X926477D02*
X924227D01*
G01X926477Y353409D02*
X924227D01*
G01X926477Y341709D02*
X924227D01*
G01X936617Y343660D02*
X934367D01*
G01X929857D02*
X927607D01*
G01X919717Y341709D02*
X917467D01*
G01X916337Y343660D02*
X913787D01*
G01X933237Y357309D02*
X930987D01*
G01X970416Y401941D02*
Y398260D01*
G01X927607Y386560D02*
X923097D01*
G01X927607Y367060D02*
X923097D01*
G01X1020868Y41033D02*
Y46682D01*
X1020650Y46900D01*
G01X1024945Y86377D02*
Y83877D01*
G01X987316Y209109D02*
X988446Y211058D01*
G01X1021115Y209109D02*
X1025625D01*
G01X1007595D02*
X1005345D01*
G01X1000836D02*
Y209931D01*
X1001965Y211060D01*
G01X1034635Y209109D02*
X1032385D01*
G01X1014355D02*
X1012105D01*
G01X980556Y213009D02*
X979426Y214958D01*
G01X973796Y213009D02*
X974926Y211060D01*
G01X994076Y209109D02*
X998586D01*
G01X985066Y216909D02*
X987316D01*
G01X1025625Y209109D02*
X1027875D01*
G01X988446Y211058D02*
X987316Y213009D01*
G01X990696Y203260D02*
X995206D01*
G01X1031255Y214960D02*
X1029005D01*
G01X1031255Y203260D02*
X1032385Y201309D01*
G01X1010975Y203260D02*
X1012105Y205210D01*
G01X1024495Y214960D02*
X1022245D01*
G01X1017735D02*
X1015485D01*
G01X1017735Y203260D02*
X1015485D01*
G01X1024495D02*
X1025625Y205211D01*
G01X1010975Y214960D02*
X1008725D01*
G01X1004215Y203260D02*
X1005345Y205210D01*
G01X1004215Y214960D02*
X1001965D01*
G01X997456D02*
X995206D01*
G01Y203260D02*
X997456D01*
G01X1000836Y263709D02*
X998586D01*
G01X1021115Y252009D02*
X1018865D01*
G01X1004215Y261760D02*
X1001965D01*
G01X1007595Y259809D02*
X1005345D01*
G01X1010975Y257860D02*
X1008725D01*
G01X1014355Y255909D02*
X1012105D01*
G01X1017735Y253960D02*
X1015485D01*
G01X1000836Y220809D02*
X998586D01*
G01X1000836Y248109D02*
X998586D01*
G01X1014355Y220809D02*
X1012105D01*
G01X1024495Y250060D02*
X1022245D01*
G01X1004215Y238360D02*
X1001965D01*
G01X1010975D02*
X1008725D01*
G01X1007595Y220809D02*
X1005345D01*
G01X1007595Y248109D02*
X1005345D01*
G01X1034635Y220809D02*
X1032385D01*
G01X1031255Y238360D02*
X1029005D01*
G01X1034635Y248109D02*
X1032385D01*
G01X1031255Y250060D02*
X1029005D01*
G01X1025625Y220809D02*
X1027875D01*
G01X1025625Y248109D02*
X1027875D01*
G01X1021115Y220809D02*
X1018865D01*
G01X1024495Y238360D02*
X1022245D01*
G01X1017735D02*
X1015485D01*
G01X980556Y252009D02*
X978306D01*
G01X987316D02*
X985066D01*
G01X994076Y263709D02*
X991826D01*
G01X987316Y267609D02*
X985066D01*
G01X994076D02*
X991826D01*
G01X997456Y265660D02*
X995206D01*
G01X997456Y269560D02*
X995206D01*
G01X994076Y255909D02*
X991826D01*
G01X990696Y253960D02*
X988446D01*
G01X997456Y273460D02*
X995206D01*
G01X994076Y271509D02*
X991826D01*
G01X977176Y269560D02*
X974926D01*
G01X980556Y267609D02*
X978306D01*
G01X983936Y269560D02*
X981686D01*
G01X977176Y273460D02*
X974926D01*
G01X994076Y275409D02*
X991826D01*
G01X994076Y279310D02*
X991826D01*
G01X990696Y265660D02*
X988446D01*
G01X977176Y253960D02*
X974926D01*
G01X980556Y259809D02*
X978306D01*
G01X987316D02*
X985066D01*
G01X994076D02*
X991826D01*
G01X980556Y220809D02*
X978306D01*
G01X977176Y250060D02*
X974926D01*
G01X983936Y242260D02*
X981686D01*
G01X990696D02*
X988446D01*
G01X977176D02*
X974926D01*
G01X987316Y248109D02*
X985066D01*
G01X990696Y246160D02*
X988446D01*
G01X983936Y250060D02*
X981686D01*
G01X983936Y218860D02*
X981686D01*
G01X980556Y232509D02*
X978306D01*
G01X983936Y234460D02*
X981686D01*
G01X977176Y226660D02*
X974926D01*
G01X977176Y222760D02*
X974926D01*
G01X977176Y234460D02*
X974926D01*
G01X977176Y230559D02*
X974926D01*
G01X990696Y238360D02*
X988446D01*
G01X997456D02*
X995206D01*
G01X987316Y236409D02*
X985066D01*
G01X987316Y224709D02*
X985066D01*
G01X994076Y220809D02*
X991826D01*
G01X990696Y234460D02*
X988446D01*
G01X990696Y250060D02*
X988446D01*
G01X1000836Y279310D02*
X998586D01*
G01X1000836Y275409D02*
X998586D01*
G01X1000836Y271509D02*
X998586D01*
G01X1025625Y252009D02*
X1027875D01*
G01X1004215Y265660D02*
X1001965D01*
G01X1007595Y263709D02*
X1005345D01*
G01X1004215Y277360D02*
X1006665D01*
G01X1007595Y267609D02*
X1009256Y269777D01*
G01X1031255Y253960D02*
Y256400D01*
G01X1027875Y255909D02*
Y258400D01*
G01X1017735Y261760D02*
Y264300D01*
G01X1021115Y259809D02*
Y262300D01*
G01X1017735Y257860D02*
X1015485D01*
G01X1024495D02*
Y260300D01*
G01X1014355Y263709D02*
Y266300D01*
G01Y259809D02*
X1012105D01*
G01X1021115Y255909D02*
X1018865D01*
G01X1024495Y253960D02*
X1022245D01*
G01X1000836Y267609D02*
X998586D01*
G01X997456Y277360D02*
X995206D01*
G01X1004215Y273460D02*
X1006665D01*
G01X1006700Y270700D02*
X1005560Y269560D01*
X1004215D01*
G01X1011100Y268100D02*
X1010975Y267975D01*
G01D02*
Y265660D01*
G01X1000836Y232509D02*
X998586D01*
G01X1000836Y244209D02*
X998586D01*
G01X1034635Y232509D02*
X1032385D01*
G01X1031255Y226660D02*
X1029005D01*
G01X1025625Y232509D02*
X1027875D01*
G01X1014355D02*
X1012105D01*
G01X1024495Y226660D02*
X1022245D01*
G01X1017735D02*
X1015485D01*
G01X1021115Y232509D02*
X1018865D01*
G01X1007595D02*
X1005345D01*
G01X1010975Y226660D02*
X1008725D01*
G01X1004215D02*
X1001965D01*
G01X1007595Y244209D02*
X1005345D01*
G01X1014355D02*
X1012105D01*
G01X1021115D02*
X1018865D01*
G01X990696Y230559D02*
Y231379D01*
X991826Y232509D01*
G01X990696Y218860D02*
X988446D01*
G01X997456Y226660D02*
X995206D01*
G01X994076Y244209D02*
X991826D01*
G01Y232509D02*
X994076D01*
G01Y252009D02*
X991826D01*
G01X994076Y248109D02*
X991826D01*
G01X1000836Y333909D02*
X998586D01*
G01X1007595Y337809D02*
X1005345D01*
G01X1004215Y335860D02*
X1001965D01*
G01X1010975Y339760D02*
X1008725D01*
G01X977176Y312460D02*
X974926D01*
G01X983936D02*
X981686D01*
G01X990696D02*
X988446D01*
G01X997456Y324160D02*
X995206D01*
G01X977176D02*
X974926D01*
G01X997456Y328060D02*
X995206D01*
G01X994076Y326110D02*
X991826D01*
G01X994076Y333909D02*
X991826D01*
G01X997456Y335860D02*
X995206D01*
G01X997456Y339760D02*
X995206D01*
G01X977176Y335860D02*
X974926D01*
G01X980556Y326110D02*
X978306D01*
G01X997456Y331960D02*
X995206D01*
G01X987316Y330009D02*
X985066D01*
G01X977176Y339760D02*
X974926D01*
G01X983936D02*
X981686D01*
G01X990696Y331960D02*
X988446D01*
G01X980556Y333909D02*
X978306D01*
G01X980556Y330009D02*
X978306D01*
G01X983936Y331960D02*
X981686D01*
G01X994076Y330009D02*
X991826D01*
G01X994076Y322209D02*
X991826D01*
G01X997456Y320260D02*
X995206D01*
G01X994076Y318309D02*
X991826D01*
G01X994076Y314409D02*
X991826D01*
G01X990696Y316360D02*
X988446D01*
G01X990696Y339760D02*
X988446D01*
G01X980556Y283209D02*
X978306D01*
G01X983936Y292959D02*
X981686D01*
G01X994076Y283209D02*
X991826D01*
G01X990696Y292959D02*
X988446D01*
G01X983936Y281260D02*
X981686D01*
G01X977176D02*
X974926D01*
G01X977176Y292959D02*
X974926D01*
G01X987316Y283209D02*
X985066D01*
G01X990696Y281260D02*
X988446D01*
G01X990696Y300760D02*
X988446D01*
G01X977176D02*
X974926D01*
G01X983936D02*
X981686D01*
G01X987316Y310509D02*
X985066D01*
G01X994076D02*
X991826D01*
G01X980556D02*
X978306D01*
G01X1000836Y326110D02*
X998586D01*
G01X1000836Y330009D02*
X998586D01*
G01X1000836Y318309D02*
X998586D01*
G01X1000836Y314409D02*
X998586D01*
G01X1000836Y322209D02*
X998586D01*
G01X1004215Y312460D02*
X1006665D01*
G01X1007595Y330009D02*
Y327609D01*
G01X1004215Y324160D02*
X1006665D01*
G01X1010975Y335860D02*
X1008725D01*
G01X1007595Y333909D02*
X1005345D01*
G01X1004215Y331960D02*
X1001965D01*
G01X1004215Y316360D02*
X1006665D01*
G01X1004215Y320260D02*
X1006665D01*
G01X1027875Y341709D02*
Y339309D01*
G01X1031255Y343660D02*
Y341260D01*
G01X1024495Y339760D02*
Y337360D01*
G01X1021115Y337809D02*
Y335409D01*
G01X1017735Y335860D02*
Y333460D01*
G01Y339760D02*
X1015485D01*
G01X1000836Y298809D02*
X998586D01*
G01X1000836Y291009D02*
X998586D01*
G01X1000836Y294909D02*
X998586D01*
G01X1000836Y287109D02*
X998586D01*
G01X1000836Y283209D02*
X998586D01*
G01X1000836Y302709D02*
X998586D01*
G01X1000836Y310509D02*
X998586D01*
G01X1000836Y306609D02*
X998586D01*
G01X1004215Y296860D02*
X1006665D01*
G01X1004215Y289060D02*
X1006665D01*
G01X1004215Y281260D02*
X1006665D01*
G01X1014355Y337809D02*
X1012105D01*
G01X1014355Y333909D02*
Y331509D01*
G01X1010975Y331960D02*
Y329560D01*
G01X1004215Y285160D02*
X1006665D01*
G01X1004215Y292959D02*
X1006665D01*
G01X1004215Y304660D02*
X1006665D01*
G01X1004215Y308560D02*
X1006665D01*
G01X1004215Y300760D02*
X1006665D01*
G01X980556Y306609D02*
X978306D01*
G01X983936Y308560D02*
X981686D01*
G01X983936Y304660D02*
X981686D01*
G01X977176D02*
X974926D01*
G01X977176Y308560D02*
X974926D01*
G01X997456Y300760D02*
X995206D01*
G01X994076Y302709D02*
X991826D01*
G01X987316D02*
X985066D01*
G01X980556D02*
X978306D01*
G01X997456Y308560D02*
X995206D01*
G01X997456Y304660D02*
X995206D01*
G01X987316Y294909D02*
X985066D01*
G01X977176Y296860D02*
X974926D01*
G01X990696D02*
X988446D01*
G01X987316Y298809D02*
X985066D01*
G01X980556D02*
X978306D01*
G01X980556Y294909D02*
X978306D01*
G01X983936Y296860D02*
X981686D01*
G01X997456Y281260D02*
X995206D01*
G01X997456Y285160D02*
X995206D01*
G01X997456Y289060D02*
X995206D01*
G01X997456Y292959D02*
X995206D01*
G01X994076Y291009D02*
X991826D01*
G01X994076Y287109D02*
X991826D01*
G01X990696Y285160D02*
X988446D01*
G01X990696Y289060D02*
X988446D01*
G01X980556Y291009D02*
X978306D01*
G01X977176Y285160D02*
X974926D01*
G01X977176Y289060D02*
X974926D01*
G01X994076Y298809D02*
X991826D01*
G01X994076Y294909D02*
X991826D01*
G01X997456Y296860D02*
X995206D01*
G01X987316Y291009D02*
X985066D01*
G01X994076Y306609D02*
X991826D01*
G01X990696Y304660D02*
X988446D01*
G01X990696Y308560D02*
X988446D01*
G01X987316Y306609D02*
X985066D01*
G01X987316Y287109D02*
X985066D01*
G01X980556D02*
X978306D01*
G01X983936Y289060D02*
X981686D01*
G01X1007595Y327609D02*
X1004215Y328060D01*
G01X983936Y324160D02*
X981686D01*
G01X990696Y320260D02*
X988446D01*
G01X987316Y322209D02*
X985066D01*
G01X987316Y318309D02*
X985066D01*
G01X990696Y324160D02*
X988446D01*
G01X990696Y328060D02*
X988446D01*
G01X983936D02*
X981686D01*
G01X987316Y326110D02*
X985066D01*
G01X977176Y320260D02*
X974926D01*
G01X983936D02*
X981686D01*
G01X980556Y322209D02*
X978306D01*
G01X980556Y318309D02*
X978306D01*
G01X983936Y316360D02*
X981686D01*
G01X977176D02*
X974926D01*
G01X980556Y314409D02*
X978306D01*
G01X987316D02*
X985066D01*
G01X994076Y388509D02*
X991826D01*
G01X1000836Y376809D02*
X998586D01*
G01X1007595D02*
X1005345D01*
G01X1000836Y388509D02*
X1001965Y386560D01*
G01X1007595Y388509D02*
X1005345D01*
G01X1034635D02*
X1032385D01*
G01X1034635Y376809D02*
X1032385D01*
G01X1025625Y388509D02*
X1027875D01*
G01X1025625Y376809D02*
X1027875D01*
G01X1021115D02*
X1018865D01*
G01X1014355D02*
X1012105D01*
G01X1021115Y388509D02*
X1018865D01*
G01X1014355D02*
X1012105D01*
G01X1000836Y349509D02*
X998586D01*
G01X1010975Y359260D02*
X1008725D01*
G01X1004215D02*
X1001965D01*
G01X1007595Y349509D02*
X1005345D01*
G01X1014355Y341709D02*
X1012105D01*
G01X1031255Y359260D02*
X1029005D01*
G01X1034635Y349509D02*
X1032385D01*
G01X1031255Y347560D02*
X1029005D01*
G01X1025625Y345609D02*
X1027875D01*
G01X1017735Y343660D02*
X1015485D01*
G01X1022245Y347560D02*
X1024495D01*
G01X1022245Y359260D02*
X1024495D01*
G01X1017735D02*
X1015485D01*
G01X1021115Y345609D02*
X1018865D01*
G01X987316Y372909D02*
X985066D01*
G01X991826Y388509D02*
X990696Y390460D01*
G01X991826Y388509D02*
X990696Y386560D01*
G01X977176D02*
X974926D01*
G01X987316Y392410D02*
X990696Y390460D01*
G01X994076Y376809D02*
X991826D01*
G01X983936Y378760D02*
X981686D01*
G01X980556Y376809D02*
X978306D01*
G01X977176Y378760D02*
X974926D01*
G01X977176Y374860D02*
X974926D01*
G01X987316Y380709D02*
X985066D01*
G01X983936Y386560D02*
X985066Y384609D01*
G01X994076Y388509D02*
X995206Y390460D01*
G01X973796Y392410D02*
Y396309D01*
G01X997456Y359260D02*
X995206D01*
G01X990696D02*
X988446D01*
G01X990696Y347560D02*
X988446D01*
G01X994076Y345609D02*
X991826D01*
G01X990696Y351460D02*
X988446D01*
G01X990696Y355360D02*
X988446D01*
G01X983936Y347560D02*
X981686D01*
G01X997456Y343660D02*
X995206D01*
G01X980556Y345609D02*
X978306D01*
G01X977176Y343660D02*
X974926D01*
G01X983936Y355360D02*
X981686D01*
G01X987316Y349509D02*
X985066D01*
G01X977176Y355360D02*
X974926D01*
G01X977176Y347560D02*
X974926D01*
G01X980556Y365109D02*
X978306D01*
G01X977176Y367060D02*
X974926D01*
G01X977176Y370959D02*
X974926D01*
G01X987316Y361209D02*
X985066D01*
G01X983936Y363160D02*
X981686D01*
G01X977176D02*
X974926D01*
G01X1022245Y343660D02*
X1024495D01*
G01X1021115Y341709D02*
X1018865D01*
G01X997456Y382660D02*
X995206D01*
G01X1031255Y394359D02*
X1029005Y390460D01*
G01X1017735Y382660D02*
X1015485D01*
G01X1022245D02*
X1024495D01*
G01X1017735Y394359D02*
X1018500Y393040D01*
X1018865Y392410D01*
G01X1010975Y394359D02*
X1012105Y392410D01*
G01X1024495Y394359D02*
X1025625Y392410D01*
G01X1027875Y400209D02*
Y402800D01*
G01X1007595Y400209D02*
Y402800D01*
G01X1000836Y365109D02*
X998586D01*
G01X1000836Y353409D02*
X998586D01*
G01X1025625Y365109D02*
X1027875D01*
G01X1025625Y353409D02*
X1027875D01*
G01X1021115D02*
X1018865D01*
G01X1014355D02*
X1012105D01*
G01X1017735Y370959D02*
X1015485D01*
G01X1022245D02*
X1024495D01*
G01X1021115Y365109D02*
X1018865D01*
G01X1014355D02*
X1012105D01*
G01X1007595Y353409D02*
X1005345D01*
G01X1007595Y365109D02*
X1005345D01*
G01X1004215Y370959D02*
X1001965D01*
G01X1010975D02*
X1008725D01*
G01X1031255D02*
X1029005D01*
G01X1034635Y365109D02*
X1032385D01*
G01X1004215Y394359D02*
X1005345Y392410D01*
G01X1010975Y382660D02*
X1008725D01*
G01X1004215D02*
X1001965D01*
G01X1031255D02*
X1029005D01*
G01X988446D02*
X990696D01*
G01X994076Y353409D02*
X991826D01*
G01X997456Y370959D02*
X995206D01*
G01X994076Y365109D02*
X991826D01*
G01X990696Y367060D02*
X988446D01*
G01X997456Y394359D02*
X998586Y392410D01*
G01X995206Y382660D02*
X990696D01*
G01X1057676Y84424D02*
Y87392D01*
G01X1091143Y81598D02*
Y82442D01*
X1089918Y83667D01*
Y86169D01*
X1091141Y87392D01*
G01Y35942D02*
Y35959D01*
G01X1071072Y202547D02*
Y199583D01*
G01X1074452Y216196D02*
X1072202D01*
G01X1067692Y208397D02*
X1065242D01*
G01X1067692Y204496D02*
X1065242D01*
G01X1068822Y214247D02*
X1071072D01*
G01X1067692Y212296D02*
X1065242D01*
G01X1077832Y218147D02*
X1075582D01*
G01X1084591D02*
X1082341D01*
G01X1081212Y216196D02*
X1078962D01*
G01X1084591Y214247D02*
X1082341D01*
G01X1074452Y208397D02*
X1075583Y206451D01*
X1075582Y206446D01*
G01X1084591Y202547D02*
Y198931D01*
G01X1087971Y212296D02*
X1085721D01*
G01Y216196D02*
X1087971D01*
G01X1091351Y214247D02*
X1089101D01*
G01X1081212Y208397D02*
X1081211D01*
X1079016Y212200D01*
X1078961Y212296D01*
G01X1094731Y208397D02*
X1094736Y208396D01*
X1095862Y206450D01*
X1095861Y206446D01*
G01X1087971Y208397D02*
X1089101Y210346D01*
G01X1087971Y204496D02*
Y205029D01*
X1087900Y205100D01*
Y208326D01*
X1087971Y208397D01*
G01X1091351Y202547D02*
Y199841D01*
G01X1094731Y216196D02*
X1092481D01*
G01X1041395Y209109D02*
X1039145D01*
G01X1054914D02*
X1057314D01*
G01X1048154D02*
X1045904D01*
G01X1051534Y203260D02*
X1049284D01*
G01X1035765Y214960D02*
X1038015D01*
G01X1044774D02*
X1042524D01*
G01X1038015Y203260D02*
X1035765Y207159D01*
G01X1048154Y197409D02*
X1045954D01*
X1045904Y197359D01*
G01X1041395Y197409D02*
X1042516Y195070D01*
X1042506Y195041D01*
G01X1044774Y203260D02*
X1042524D01*
G01X1051534Y214960D02*
X1049284D01*
G01X1054914Y201309D02*
Y200014D01*
X1054000Y199100D01*
G01D02*
X1053740Y199360D01*
X1051534D01*
G01X1072202Y251296D02*
X1074452D01*
G01X1087971D02*
X1085721D01*
G01X1081212D02*
X1078962D01*
G01X1094764Y275472D02*
X1098028D01*
X1100200Y273300D01*
G01X1082432Y264620D02*
X1082359D01*
Y267341D01*
X1081700Y268000D01*
G01X1091351Y253247D02*
X1089101D01*
G01X1094731Y255196D02*
X1092481D01*
G01X1094731Y243496D02*
X1092481D01*
G01X1087971Y231797D02*
X1085721D01*
G01X1084591Y245447D02*
X1082341D01*
G01X1084591Y249347D02*
X1082341D01*
G01X1081212Y247396D02*
X1078962D01*
G01X1077832Y249347D02*
X1075582D01*
G01X1077832Y245447D02*
X1075582D01*
G01X1087971Y243496D02*
X1085721D01*
G01X1091351Y241547D02*
X1089101D01*
G01X1074452Y231797D02*
X1072202D01*
G01X1074452Y223996D02*
X1072202D01*
G01X1071072Y233746D02*
X1068822D01*
G01X1067692Y235696D02*
X1065242D01*
G01X1067692Y223996D02*
X1065242D01*
G01X1071072Y237647D02*
X1068822D01*
G01X1071072Y249347D02*
X1068822D01*
G01X1067692Y247396D02*
X1065242D01*
G01X1071072Y241547D02*
X1068822D01*
G01X1074452Y243496D02*
X1072202D01*
G01X1084591Y229847D02*
X1082341D01*
G01X1081212Y227896D02*
X1078962D01*
G01Y220096D02*
X1081212D01*
G01Y223996D02*
X1078962D01*
G01X1084591Y237647D02*
X1082341D01*
G01X1077832D02*
X1075582D01*
G01X1087971Y223996D02*
X1085721D01*
G01X1077832Y229847D02*
X1075582D01*
G01X1091351Y237647D02*
X1089101D01*
G01X1094731Y223996D02*
X1092481D01*
G01X1094731Y231797D02*
X1092481D01*
G01X1091351Y233746D02*
X1089101D01*
G01X1038015Y238360D02*
X1035765D01*
G01X1044774D02*
X1042524D01*
G01X1041395Y220809D02*
X1039145D01*
G01X1048154D02*
X1045904D01*
G01X1054914D02*
X1057314D01*
G01X1044774Y250060D02*
X1042524D01*
G01X1051534D02*
X1049284D01*
G01X1048154Y248109D02*
X1045904D01*
G01X1038015Y250060D02*
X1035765D01*
G01X1054914Y248109D02*
X1057314D01*
G01X1041395D02*
X1039145D01*
G01X1067692Y239596D02*
X1065242D01*
G01Y243496D02*
X1067692D01*
G01X1068822Y245447D02*
X1071072D01*
G01X1054914Y252009D02*
Y254500D01*
G01X1048154Y252009D02*
Y254259D01*
G01X1041395Y252009D02*
Y254259D01*
G01X1034635Y252009D02*
Y254259D01*
G01X1044774Y253960D02*
Y256400D01*
G01X1051534Y253960D02*
Y256500D01*
G01X1038015Y253960D02*
Y256500D01*
G01X1077833Y255400D02*
X1077832Y255399D01*
G01X1074461Y257145D02*
X1074452Y257136D01*
G01X1077832Y255399D02*
Y253247D01*
G01X1074452Y257136D02*
Y255196D01*
G01X1094731Y251296D02*
X1092481D01*
G01X1094731Y247396D02*
X1092481D01*
G01X1087971D02*
X1085721D01*
G01X1091351Y245447D02*
X1089101D01*
G01X1091351Y249347D02*
X1089101D01*
G01X1038015Y226660D02*
X1042524D01*
G01X1054914Y232509D02*
X1057314D01*
G01X1041395D02*
X1039145D01*
G01X1035765Y226660D02*
X1038015D01*
G01X1054914Y240309D02*
X1057314D01*
G01X1051534Y226660D02*
X1049284D01*
G01X1048154Y232509D02*
X1045904D01*
G01X1042524Y226660D02*
X1044774D01*
G01X1077000Y272000D02*
Y269200D01*
X1078200Y268000D01*
G01X1079859Y265000D02*
X1078200Y266659D01*
Y268000D01*
G01X1074452Y395597D02*
X1073323Y397548D01*
G01X1074452Y372197D02*
X1076702D01*
G01X1094731D02*
X1096981D01*
G01X1087971D02*
X1090221D01*
G01X1071072Y374146D02*
X1073322D01*
G01X1071072Y401447D02*
X1073321D01*
X1073323Y401449D01*
G01X1091351Y393647D02*
X1093601D01*
G01X1091351Y385847D02*
X1093601D01*
G01X1084591Y389747D02*
X1086841D01*
G01X1084591Y385847D02*
X1086841D01*
G01X1077832D02*
X1080082D01*
G01X1081212Y391696D02*
X1083462D01*
G01X1077832Y393647D02*
X1080082D01*
G01X1087971Y391696D02*
X1090221D01*
G01X1094731Y376096D02*
X1096981D01*
G01X1091351Y378047D02*
X1093601D01*
G01X1087971Y379996D02*
X1090221D01*
G01Y395595D02*
X1088450Y398666D01*
X1087971Y399496D01*
G01X1094731Y403396D02*
X1093601Y401447D01*
G01X1081212Y399496D02*
X1078962D01*
G01X1073323Y397548D02*
X1074452Y399496D01*
G01X1073323Y397548D02*
X1073321Y397546D01*
X1071072D01*
G01Y385847D02*
X1073322D01*
G01X1081212Y379996D02*
X1083462D01*
G01X1077832Y378047D02*
X1080082D01*
G01X1084591Y381947D02*
X1086841D01*
G01X1074452Y376096D02*
X1076702D01*
G01X1071072Y354647D02*
X1073322D01*
G01X1071072Y362447D02*
X1073322D01*
G01X1074452Y368296D02*
X1076702D01*
G01X1087971Y364396D02*
X1090221D01*
G01X1091351Y358547D02*
X1093601D01*
G01X1087971Y352696D02*
X1090221D01*
G01X1074452Y356596D02*
X1076702D01*
G01X1074452Y352696D02*
X1076702D01*
G01X1081212D02*
X1083462D01*
G01X1074452Y360496D02*
X1076702D01*
G01X1084591Y354647D02*
X1086841D01*
G01X1077832D02*
X1080082D01*
G01X1084591Y362447D02*
X1086841D01*
G01X1094731Y368296D02*
X1096981D01*
G01X1091351Y366347D02*
X1093601D01*
G01X1054914Y376809D02*
X1052664D01*
G01X1041395D02*
X1039145D01*
G01X1048154D02*
X1045904D01*
G01X1058294Y374860D02*
X1060694D01*
G01X1054914Y388509D02*
X1052664D01*
G01X1048154D02*
X1045904D01*
G01X1041395D02*
X1039145D01*
G01X1058294Y351460D02*
X1060694D01*
G01X1054914Y349509D02*
Y347000D01*
G01X1051534Y351460D02*
X1049284D01*
G01X1041395Y353409D02*
X1039145D01*
G01X1038015Y359260D02*
X1035765D01*
G01X1038015Y351460D02*
X1035765D01*
G01X1048154Y353409D02*
X1045904D01*
G01X1044774Y359260D02*
X1042524D01*
G01X1044774Y351460D02*
X1042524D01*
G01X1093601Y393647D02*
X1094731Y395597D01*
G01X1073323Y401449D02*
X1074452Y403396D01*
G01X1034635Y345609D02*
Y343209D01*
G01X1051534Y347560D02*
Y345160D01*
G01X1044774Y347560D02*
Y345160D01*
G01X1048154Y349509D02*
Y347109D01*
G01X1041395Y349509D02*
Y347109D01*
G01X1038015Y347560D02*
Y345160D01*
G01X1054914Y400209D02*
X1056176Y402471D01*
G01X1044774Y394359D02*
X1042524Y390460D01*
G01X1038015Y394359D02*
X1040265D01*
G01X1041395Y400209D02*
Y402800D01*
G01X1038015Y370959D02*
X1035765D01*
G01X1048154Y365109D02*
X1045904D01*
G01X1054914Y357309D02*
X1052664D01*
G01X1051534Y370959D02*
X1049284D01*
G01X1054914Y365109D02*
X1052664D01*
G01X1044774Y370959D02*
X1042524D01*
G01X1041395Y365109D02*
X1039145D01*
G01X1051534Y382660D02*
X1049284D01*
G01X1044774D02*
X1042524D01*
G01X1038015D02*
X1035765D01*
G01X1051534Y394359D02*
X1052664Y392410D01*
G01X1056176Y402471D02*
X1058294Y400353D01*
Y398260D01*
G01X1077832Y405347D02*
Y407800D01*
G01X1091351Y405347D02*
X1093601D01*
G01X1091141Y574742D02*
Y574759D01*
G01X1124606Y9114D02*
X1119400Y9300D01*
G01X1114300Y16900D02*
X1119440Y17114D01*
G01X1161417Y46914D02*
X1156200Y47000D01*
G01X1124606Y46914D02*
X1119400Y47100D01*
G01X1114300Y54700D02*
X1119440Y54914D01*
G01X1097834Y36519D02*
Y35949D01*
X1098022Y35761D01*
G01X1148810Y212296D02*
X1151060D01*
G01X1121771Y216196D02*
X1119521D01*
G01X1121771Y208397D02*
X1119575Y212200D01*
X1119520Y212296D01*
G01X1128530Y204496D02*
X1129500Y206171D01*
X1129531Y206224D01*
X1129660Y206447D01*
G01X1138670Y218147D02*
X1136420D01*
G01X1145430Y210346D02*
X1147504D01*
X1147950Y209900D01*
G01X1138670Y214247D02*
X1136420D01*
G01X1138670Y210346D02*
X1136420D01*
G01X1126280Y216196D02*
X1128530D01*
G01X1126280Y212296D02*
X1128530D01*
G01X1131910Y214247D02*
X1129660D01*
G01X1125150Y202547D02*
Y200050D01*
X1125300Y199900D01*
G01X1122900Y214247D02*
X1125150D01*
G01X1122900Y218147D02*
X1125150D01*
G01X1155570Y212296D02*
X1157820D01*
G01X1101491Y208397D02*
X1100600Y209941D01*
X1100471Y210164D01*
X1099296Y212200D01*
X1099241Y212296D01*
G01Y216196D02*
X1101491D01*
G01X1095861Y218147D02*
X1098111D01*
G01X1108251Y212296D02*
X1106001D01*
G01X1108251Y216196D02*
X1106001D01*
G01X1104871Y218147D02*
X1102621D01*
G01X1104871Y214247D02*
X1102621D01*
G01X1111631D02*
X1109381D01*
G01X1118391Y218147D02*
X1116141D01*
G01X1115011Y208397D02*
X1115037Y208390D01*
X1115600Y207418D01*
X1116148Y206471D01*
X1116141Y206446D01*
G01X1115011Y216196D02*
X1112761D01*
G01X1151060Y212296D02*
X1152190Y211166D01*
Y210346D01*
G01X1129660Y206447D02*
X1128530Y208397D01*
G01X1121771Y251296D02*
X1119521D01*
G01Y270796D02*
X1121771D01*
G01Y255196D02*
X1119521D01*
G01X1121771Y270796D02*
X1123722Y272747D01*
X1125150D01*
G01X1133040Y251296D02*
X1135290D01*
G01X1142050D02*
X1144300D01*
G01X1126280D02*
X1128530D01*
G01X1155570Y278596D02*
X1157820D01*
G01X1155570Y270796D02*
X1157820D01*
G01X1148810Y259096D02*
X1151060D01*
G01X1142050Y270796D02*
X1144300D01*
G01X1135290Y274696D02*
X1137540D01*
G01X1135290Y278596D02*
X1137540D01*
G01X1142050Y255196D02*
X1144300D01*
G01X1138670Y257147D02*
X1136420D01*
G01X1144300Y278596D02*
X1142050D01*
G01X1152190Y253247D02*
X1154440D01*
G01X1148810Y274696D02*
X1151060D01*
G01X1148810Y266896D02*
X1151060D01*
G01X1134160Y268847D02*
X1131910D01*
G01X1133040Y259096D02*
X1135290D01*
G01X1122900Y257147D02*
X1125150D01*
G01X1131910Y261047D02*
X1129660D01*
G01X1126280Y259096D02*
X1128530D01*
G01X1130780Y274696D02*
X1128530D01*
G01X1130780Y278596D02*
X1128530D01*
G01X1121771Y227896D02*
X1119521D01*
G01X1121771Y223996D02*
X1119521D01*
G01X1121771Y220096D02*
X1119521D01*
G01X1121771Y247396D02*
X1119521D01*
G01X1133040Y243496D02*
X1135290D01*
G01X1148810Y223996D02*
X1151060D01*
G01X1152190Y229847D02*
X1154440D01*
G01X1138670D02*
X1136420D01*
G01X1145430Y233746D02*
X1147680D01*
G01X1142050Y235696D02*
X1144300D01*
G01X1145430Y222047D02*
X1147680D01*
G01X1145430Y225947D02*
X1147680D01*
G01X1138670Y237647D02*
X1136420D01*
G01X1138670Y225947D02*
X1136420D01*
G01X1138670Y222047D02*
X1136420D01*
G01X1138670Y233746D02*
X1136420D01*
G01X1138670Y241547D02*
X1136420D01*
G01X1152190D02*
X1154440D01*
G01X1155570Y239596D02*
X1157820D01*
G01X1122900Y237647D02*
X1125150D01*
G01X1126280Y223996D02*
X1128530D01*
G01X1126280Y231797D02*
X1128530D01*
G01X1131910Y233746D02*
X1129660D01*
G01X1131910Y237647D02*
X1129660D01*
G01X1122900Y229847D02*
X1125150D01*
G01X1131910Y241547D02*
X1129660D01*
G01X1122900Y245447D02*
X1125150D01*
G01X1126280Y243496D02*
X1128530D01*
G01X1155570Y220096D02*
X1157820D01*
G01X1155570Y223996D02*
X1157820D01*
G01X1155570Y231797D02*
X1157820D01*
G01X1142050Y247396D02*
X1144300D01*
G01X1138670Y245447D02*
X1136420D01*
G01X1142050Y243496D02*
X1144300D01*
G01X1152190Y245447D02*
X1154440D01*
G01X1148810Y247396D02*
X1151060D01*
G01X1133040Y235696D02*
X1135290D01*
G01X1133040Y223996D02*
X1135290D01*
G01X1115011Y251296D02*
X1112761D01*
G01X1101491D02*
X1099241D01*
G01X1108251D02*
X1106001D01*
G01X1110648Y276899D02*
Y277252D01*
X1108544Y279356D01*
X1108058D01*
X1106856Y280558D01*
Y281341D01*
G01X1111631Y261047D02*
X1109381D01*
G01X1101491Y255196D02*
X1099241D01*
G01X1118391Y264947D02*
X1116141D01*
G01X1108251Y266896D02*
X1107561Y267586D01*
Y269038D01*
G01X1108251Y262996D02*
X1106001D01*
G01X1111631Y268847D02*
Y271300D01*
G01X1101491Y259096D02*
X1099241D01*
G01X1098111Y257147D02*
X1095861D01*
G01X1104871Y261047D02*
X1102621D01*
G01X1108251Y259096D02*
X1106001D01*
G01X1115011D02*
X1112761D01*
G01X1104871Y257147D02*
X1102621D01*
G01X1118391D02*
X1116141D01*
G01X1118391Y272747D02*
Y274997D01*
G01X1115011Y243496D02*
X1112761D01*
G01X1118391Y245447D02*
X1116141D01*
G01X1101491Y223996D02*
X1099241D01*
G01X1101491Y247396D02*
X1099241D01*
G01X1098111Y245447D02*
X1095861D01*
G01X1111631Y241547D02*
X1109381D01*
G01X1108251Y243496D02*
X1106001D01*
G01X1104871Y245447D02*
X1102621D01*
G01X1101491Y220096D02*
X1099241D01*
G01X1101491Y227896D02*
X1099241D01*
G01X1098111Y229847D02*
X1095861D01*
G01X1108251Y223996D02*
X1106001D01*
G01X1104871Y229847D02*
X1102621D01*
G01X1108251Y231797D02*
X1106001D01*
G01X1104871Y237647D02*
X1102621D01*
G01X1098111D02*
X1095861D01*
G01X1115011Y223996D02*
X1112761D01*
G01X1118391Y229847D02*
X1116141D01*
G01X1118391Y237647D02*
X1116141D01*
G01X1111631D02*
X1109381D01*
G01X1111631Y233746D02*
X1109381D01*
G01X1115011Y231797D02*
X1112761D01*
G01X1121771Y278596D02*
X1119521D01*
G01X1125150Y276646D02*
X1127400D01*
G01X1142050Y223996D02*
X1144300D01*
G01X1152190Y225947D02*
X1154440D01*
G01X1145430Y245447D02*
X1147680D01*
G01X1098111Y253247D02*
X1095861D01*
G01X1116141Y261047D02*
X1118391D01*
G01X1112761Y262996D02*
X1115011D01*
G01X1098111Y249347D02*
X1095861D01*
G01X1115011Y270796D02*
Y276686D01*
X1110356Y281341D01*
G01X1115011Y266896D02*
X1113920Y267987D01*
Y269705D01*
X1115011Y270796D01*
G01X1126280Y262996D02*
X1128530D01*
G01X1122900Y268847D02*
X1125150D01*
G01D02*
X1127099Y270796D01*
X1128530D01*
G01X1122900Y264947D02*
X1125150D01*
G01X1131910D02*
X1129660D01*
G01X1126280Y266896D02*
X1128530D01*
G01X1142050Y262996D02*
X1144300D01*
G01X1138670Y264947D02*
X1140920D01*
G01X1138670Y268847D02*
X1140920D01*
G01X1137540Y270796D02*
X1135290D01*
G01X1145430Y268847D02*
X1147680D01*
G01X1135290Y266896D02*
X1137540D01*
G01X1152190Y264947D02*
X1154440D01*
G01X1121771Y321496D02*
X1119521D01*
G01X1121771Y337096D02*
X1124021D01*
G01X1121771Y340996D02*
X1124021D01*
G01X1155570Y313696D02*
X1157820D01*
G01X1130780D02*
X1128530D01*
G01X1142050Y340996D02*
X1144300D01*
G01X1138670Y339047D02*
X1140920D01*
G01X1138670Y331247D02*
X1140920D01*
G01X1142050Y337096D02*
X1144300D01*
G01X1145430Y327347D02*
X1147680D01*
G01X1152190Y331247D02*
X1154440D01*
G01X1152190Y335147D02*
X1154440D01*
G01X1152190Y323446D02*
X1154440D01*
G01X1152190Y315647D02*
X1154440D01*
G01X1125150Y327347D02*
X1127400D01*
G01X1125150Y319547D02*
X1127400D01*
G01X1125150Y315647D02*
X1127400D01*
G01X1152190Y319547D02*
X1154440D01*
G01X1155570Y325396D02*
X1157820D01*
G01X1135290Y317596D02*
X1137540D01*
G01X1145430Y319547D02*
X1147680D01*
G01X1148810Y333196D02*
X1151060D01*
G01X1155570Y317596D02*
X1157820D01*
G01X1155570Y333196D02*
X1157820D01*
G01X1155570Y337096D02*
X1157820D01*
G01X1155570Y329296D02*
X1157820D01*
G01X1121771Y286396D02*
X1119521D01*
G01X1155570Y294196D02*
X1157820D01*
G01X1142050Y286396D02*
X1144300D01*
G01X1138670Y292247D02*
X1140920D01*
G01X1142050Y294196D02*
X1144300D01*
G01X1135290Y282496D02*
X1137540D01*
G01X1148810Y290296D02*
X1151060D01*
G01X1148810Y282496D02*
X1151060D01*
G01X1148810Y298096D02*
X1151060D01*
G01X1131910Y292247D02*
X1134160D01*
G01X1131910Y300047D02*
X1134160D01*
G01X1155570Y290296D02*
X1157820D01*
G01X1142050Y309797D02*
X1144300D01*
G01X1135290D02*
X1137540D01*
G01X1145430Y303947D02*
X1147680D01*
G01X1130780Y290296D02*
X1128530D01*
G01X1125150Y288347D02*
X1127400D01*
G01X1130780Y301996D02*
X1128530D01*
G01X1125150Y307847D02*
X1127400D01*
G01X1125150Y303947D02*
X1127400D01*
G01X1130780Y309797D02*
X1128530D01*
G01X1138670Y300047D02*
X1140920D01*
G01X1152190Y307847D02*
X1154440D01*
G01X1121771Y333196D02*
X1124021D01*
G01X1145430Y339047D02*
X1147680D01*
G01X1155570Y321496D02*
X1157820D01*
G01X1125150Y323446D02*
X1127400D01*
G01X1152190Y327347D02*
X1154440D01*
G01X1121771Y301996D02*
X1119521D01*
G01X1121771Y298096D02*
X1119521D01*
G01X1121771Y294196D02*
X1119521D01*
G01X1121771Y290296D02*
X1119521D01*
G01X1121771Y282496D02*
X1119521D01*
G01X1125150Y296147D02*
X1127400D01*
G01X1125150Y284447D02*
X1127400D01*
G01X1125150Y280547D02*
X1127400D01*
G01X1130780Y294196D02*
X1128530D01*
G01X1130780Y298096D02*
X1128530D01*
G01X1125150Y300047D02*
X1127400D01*
G01X1130780Y305896D02*
X1128530D01*
G01X1131910Y296147D02*
X1134160D01*
G01X1131910Y288347D02*
X1134160D01*
G01X1131910Y280547D02*
X1134160D01*
G01X1135290Y290296D02*
X1137540D01*
G01X1118391Y339047D02*
X1120641D01*
G01X1111631D02*
Y342947D01*
G01X1152190Y311747D02*
X1154440D01*
G01X1152190Y303947D02*
X1154440D01*
G01X1155570Y301996D02*
X1157820D01*
G01X1152190Y300047D02*
X1154440D01*
G01X1142050Y333196D02*
Y334017D01*
X1140920Y335147D01*
G01X1142050Y333196D02*
X1144300D01*
G01X1148810Y313696D02*
X1151060D01*
G01X1142050D02*
X1144300D01*
G01X1145430Y331247D02*
X1147680D01*
G01X1148810Y329296D02*
X1151060D01*
G01X1142050Y321496D02*
X1144300D01*
G01X1142050Y325396D02*
X1144300D01*
G01X1138670Y319547D02*
X1140920D01*
G01X1131910Y339047D02*
X1134160D01*
G01X1131910Y335147D02*
X1134160D01*
G01X1135290Y333196D02*
X1137540D01*
G01X1135290Y340996D02*
X1137540D01*
G01X1135290Y337096D02*
X1137540D01*
G01X1148810Y317596D02*
X1151060D01*
G01X1145430Y315647D02*
X1147680D01*
G01X1127400Y339047D02*
X1125150D01*
G01Y335147D02*
X1127400D01*
G01X1125150Y331247D02*
X1127400D01*
G01X1130780Y337096D02*
X1128530D01*
G01X1130780Y340996D02*
X1128530D01*
G01X1138670Y327347D02*
X1140920D01*
G01X1142050Y329296D02*
X1144300D01*
G01X1135290D02*
X1137540D01*
G01X1145430Y323446D02*
X1147680D01*
G01X1148810Y321496D02*
X1151060D01*
G01X1148810Y325396D02*
X1151060D01*
G01X1144300Y333196D02*
X1145430Y334326D01*
Y335147D01*
G01X1144300Y333196D02*
Y332377D01*
X1145430Y331247D01*
G01Y335147D02*
X1147680D01*
G01X1145430Y311747D02*
X1147680D01*
G01X1138670D02*
X1140920D01*
G01X1152190Y296147D02*
X1154440D01*
G01X1155570Y298096D02*
X1157820D01*
G01X1142050Y305896D02*
X1144300D01*
G01X1138670Y307847D02*
X1140920D01*
G01X1145430Y296147D02*
X1147680D01*
G01X1145430Y300047D02*
X1147680D01*
G01X1148810Y294196D02*
X1151060D01*
G01X1131910Y307847D02*
X1134160D01*
G01X1140920Y335147D02*
X1138670D01*
G01X1121771Y372197D02*
X1124021D01*
G01X1121771Y391696D02*
X1124021D01*
G01X1121771Y379996D02*
X1124021D01*
G01X1130780D02*
X1128530D01*
G01X1125150Y381947D02*
X1127400D01*
G01X1130780Y391696D02*
X1128530D01*
G01X1125150Y389747D02*
X1127400D01*
G01X1125150Y385847D02*
X1127400D01*
G01X1131910Y378047D02*
X1134160D01*
G01X1142050Y391696D02*
X1144300D01*
G01X1138670Y385847D02*
X1140920D01*
G01X1145430D02*
X1147680D01*
G01X1135290Y376096D02*
X1137540D01*
G01X1148810Y395597D02*
X1151060D01*
G01X1148810Y379996D02*
X1151060D01*
G01X1138670Y389747D02*
X1140920D01*
G01X1145430Y393647D02*
X1147680D01*
G01X1148810Y391696D02*
X1151060D01*
G01X1152190Y381947D02*
X1154440D01*
G01X1152190Y378047D02*
X1154440D01*
G01X1135290Y395597D02*
X1137540D01*
G01X1131910Y385847D02*
X1134160D01*
G01X1131910Y393647D02*
X1134160D01*
G01X1130780Y395596D02*
X1130400Y396255D01*
X1129009Y398666D01*
X1128530Y399496D01*
G01X1135290D02*
X1137540D01*
G01X1121771Y348796D02*
X1124021D01*
G01X1121771Y364396D02*
X1124021D01*
G01X1121771Y352696D02*
X1124021D01*
G01X1148810D02*
X1151060D01*
G01X1152190Y354647D02*
X1154440D01*
G01X1152190Y346847D02*
X1154440D01*
G01X1140920Y350747D02*
X1138670D01*
G01Y346847D02*
X1140920D01*
G01X1145430Y342947D02*
X1147680D01*
G01X1131910Y346847D02*
X1134160D01*
G01X1131910Y366347D02*
X1134160D01*
G01X1152190Y342947D02*
X1154440D01*
G01X1148810Y344896D02*
X1151060D01*
G01X1147680Y350747D02*
X1145430D01*
G01Y346847D02*
X1147680D01*
G01X1142050Y344896D02*
X1144300D01*
G01X1142050Y348796D02*
X1144300D01*
G01X1145430Y354647D02*
X1147680D01*
G01X1125150Y342947D02*
X1127400D01*
G01X1130780Y344896D02*
X1128530D01*
G01X1130780Y352696D02*
X1128530D01*
G01X1125150Y362447D02*
X1127400D01*
G01X1125150Y358547D02*
X1127400D01*
G01X1125150Y354647D02*
X1127400D01*
G01X1135290Y368296D02*
X1137540D01*
G01X1142050Y364396D02*
X1144300D01*
G01X1145430Y362447D02*
X1147680D01*
G01X1138670Y370247D02*
X1140920D01*
G01X1138670Y366347D02*
X1140920D01*
G01X1148810Y364396D02*
X1151060D01*
G01X1138670Y362447D02*
X1140920D01*
G01X1138670Y358547D02*
X1140920D01*
G01X1142050Y360496D02*
X1144300D01*
G01X1147680Y358547D02*
X1145430D01*
G01X1148810Y360496D02*
X1151060D01*
G01X1148810Y356596D02*
X1151060D01*
G01X1115011Y372197D02*
X1117261D01*
G01X1101491D02*
X1103741D01*
G01X1115011Y395597D02*
X1113881Y393647D01*
G01X1111631Y385847D02*
X1113881D01*
G01X1104871D02*
X1107121D01*
G01X1104871Y389747D02*
X1107121D01*
G01X1101491Y391696D02*
X1103741D01*
G01X1098111Y393647D02*
X1100361D01*
G01X1098111Y385847D02*
X1100361D01*
G01X1108251Y391696D02*
X1110501D01*
G01X1115011Y376096D02*
X1117261D01*
G01X1111631Y378047D02*
X1113881D01*
G01X1101491Y379996D02*
X1103741D01*
G01X1098111Y378047D02*
X1100361D01*
G01X1104871Y381947D02*
X1107121D01*
G01X1108251Y379996D02*
X1110501D01*
G01X1118391Y378047D02*
X1120641D01*
G01X1118391Y385847D02*
X1120641D01*
G01Y393647D02*
X1118391D01*
G01X1110501Y395595D02*
X1108730Y398666D01*
X1108251Y399496D01*
G01X1115011Y403396D02*
X1113881Y401447D01*
G01Y397546D02*
X1115011Y399496D01*
G01X1118391Y366347D02*
X1120641D01*
G01X1111631Y350747D02*
X1113881D01*
G01X1115011Y348796D02*
X1117261D01*
G01X1104871Y358547D02*
X1107121D01*
G01X1104871Y354647D02*
X1107121D01*
G01X1101491Y364396D02*
X1103741D01*
G01X1108251D02*
X1110501D01*
G01X1104871Y346847D02*
X1107121D01*
G01X1108251Y352696D02*
X1110501D01*
G01X1101491D02*
X1103741D01*
G01X1101491Y348796D02*
X1103741D01*
G01X1098111Y350747D02*
X1100361D01*
G01X1111631Y358547D02*
X1113881D01*
G01X1104871Y362447D02*
X1107121D01*
G01X1115011Y368296D02*
X1117261D01*
G01X1111631Y366347D02*
X1113881D01*
G01X1098111D02*
X1100361D01*
G01X1118391Y350747D02*
X1120641D01*
G01X1118391Y358547D02*
X1120641D01*
G01X1113881Y393647D02*
X1111631D01*
G01X1155570Y379996D02*
X1157820D01*
G01X1148810Y383896D02*
X1151060D01*
G01X1145430Y389747D02*
X1147680D01*
G01X1142050Y376096D02*
X1144300D01*
G01X1142050Y368296D02*
X1144300D01*
G01X1152190Y362447D02*
X1154440D01*
G01X1142050Y352696D02*
X1144300D01*
G01X1155570Y356596D02*
X1157820D01*
G01X1152190Y350747D02*
X1154440D01*
G01X1104871D02*
X1107121D01*
G01D02*
X1108251Y349617D01*
Y348796D01*
G01X1111631Y342947D02*
X1113881D01*
G01X1115011Y344896D02*
Y345717D01*
X1113881Y346847D01*
G01D02*
X1111631D01*
G01X1135290Y352696D02*
X1137540D01*
G01X1135290Y344896D02*
X1137540D01*
G01Y348796D02*
X1135290D01*
G01X1131910Y358547D02*
X1134160D01*
G01X1131910Y350747D02*
X1134160D01*
G01X1131910Y354647D02*
X1134160D01*
G01X1131910Y342947D02*
X1134160D01*
G01X1130780Y356596D02*
X1128530D01*
G01X1111631Y405347D02*
X1113881D01*
G01X1193063Y17114D02*
X1187923Y16900D01*
G01X1198228Y9114D02*
X1195310Y9219D01*
X1194630Y9243D01*
X1193023Y9300D01*
G01X1174803Y46914D02*
X1168110D01*
G01X1198228D02*
X1193012Y47000D01*
G01X1248263Y98408D02*
X1223760D01*
X1215072Y107096D01*
Y131282D01*
X1216969Y133179D01*
X1222451D01*
X1223451Y134179D01*
Y141574D01*
X1230822Y148945D01*
X1234385D01*
X1236894Y146436D01*
X1238678D01*
X1239238Y146996D01*
X1242121D01*
X1246970Y142147D01*
Y137547D01*
G01X1192749Y210346D02*
X1194999D01*
G01X1199509Y214247D02*
Y213426D01*
X1198379Y212296D01*
G01X1199509Y218147D02*
X1201759D01*
G01X1188239Y206447D02*
X1185989D01*
G01Y210346D02*
X1188239D01*
G01X1185989Y214247D02*
X1188239D01*
G01X1197492Y201356D02*
X1196129Y202719D01*
Y204496D01*
G01X1202889Y208397D02*
X1203786Y207500D01*
X1204001D01*
X1204819Y206682D01*
X1205759D01*
G01X1196129Y204496D02*
X1198080Y206447D01*
X1199509D01*
G01X1182609Y204496D02*
X1184859D01*
G01X1158950Y210346D02*
X1161200D01*
G01X1158950Y218147D02*
X1161200D01*
G01X1167960D02*
X1165710D01*
G01X1175849Y216196D02*
X1178099D01*
G01X1172469Y218147D02*
X1174719D01*
G01X1158950Y206447D02*
X1158951Y206446D01*
X1161200D01*
G01X1167960Y206447D02*
X1165710D01*
G01X1171339Y208397D02*
X1169089D01*
G01X1174719Y206447D02*
X1172469D01*
G01X1175849Y208397D02*
X1178099D01*
G01X1179229Y206447D02*
X1181479D01*
G01X1194999Y210346D02*
X1196129Y211476D01*
Y212296D01*
G01X1198379D02*
X1196129D01*
G01X1201759Y218147D02*
X1202889Y217017D01*
Y216196D01*
G01X1189369Y208397D02*
X1191619D01*
G01X1206269Y218147D02*
X1208519D01*
G01X1169089Y216196D02*
X1171339D01*
G01X1179229Y218147D02*
X1181479D01*
G01X1179229Y268847D02*
X1181479D01*
G01X1185989Y249347D02*
X1184859Y250477D01*
Y251296D01*
G01X1185989Y222047D02*
X1188239D01*
G01X1199509Y229847D02*
X1201759D01*
G01X1199509Y225947D02*
X1194999D01*
G01X1209649Y251296D02*
X1212199D01*
G01X1209649Y262996D02*
G03X1209068Y264397I-1982J-1D01*
G01X1208519Y264947D01*
G01X1196129Y266896D02*
X1194999Y268026D01*
Y268847D01*
G01X1196129Y266896D02*
X1194999Y265766D01*
Y264947D01*
G01X1196129Y255196D02*
X1198379D01*
G01X1206269Y276646D02*
Y275826D01*
X1205139Y274696D01*
G01X1185989Y257147D02*
X1188239D01*
G01X1189369Y274696D02*
X1191619D01*
G01X1196129Y278596D02*
X1198379D01*
G01X1194999Y272747D02*
X1192749D01*
G01X1199509Y261047D02*
X1201759D01*
G01X1209649Y274696D02*
X1212199D01*
G01X1206269Y272747D02*
X1208519D01*
G01X1182609Y259096D02*
X1184859D01*
G01X1209649Y235696D02*
X1208519Y234566D01*
Y233746D01*
G01X1202889Y247396D02*
X1201759Y248526D01*
Y249347D01*
G01X1189369Y247396D02*
X1188239Y248526D01*
Y249347D01*
G01X1185989Y237647D02*
X1188239D01*
G01X1185989Y225947D02*
X1188239D01*
G01X1189369Y239596D02*
X1191619D01*
G01X1194999Y233746D02*
X1192749D01*
G01X1199509D02*
X1201759D01*
G01X1196129Y243496D02*
X1198379D01*
G01X1196129Y239596D02*
X1198379D01*
G01X1196129Y235696D02*
X1198379D01*
G01X1199509Y241547D02*
X1201759D01*
G01X1206269Y222047D02*
X1214147D01*
X1215700Y223600D01*
G01X1209649Y243496D02*
X1212199D01*
G01X1182609Y235696D02*
X1184859D01*
G01X1182609Y247396D02*
X1184859D01*
G01X1182609Y239596D02*
X1184859D01*
G01X1220017Y220323D02*
X1219790Y220096D01*
X1209649D01*
G01X1169089Y274696D02*
X1171339D01*
G01X1172469Y253247D02*
X1174719D01*
G01X1169089Y259096D02*
X1171339D01*
G01X1162330Y270796D02*
X1164580D01*
G01X1175849Y274696D02*
X1178099D01*
G01X1167960Y253247D02*
X1165710D01*
G01X1169089Y266896D02*
X1171339D01*
G01X1162330Y278596D02*
X1164580D01*
G01X1162330Y227896D02*
X1164580D01*
G01X1162330Y235696D02*
X1164580D01*
G01X1167960Y229847D02*
X1165710D01*
G01X1162330Y223996D02*
X1164580D01*
G01X1172469Y237647D02*
X1174719D01*
G01X1169089Y235696D02*
X1171339D01*
G01X1175849Y220096D02*
X1178099D01*
G01X1169089D02*
X1171339D01*
G01X1175849Y227896D02*
X1178099D01*
G01X1175849Y235696D02*
X1178099D01*
G01X1179229Y261047D02*
X1181479D01*
G01X1179229Y276646D02*
X1181479D01*
G01X1158950Y241547D02*
X1161200D01*
G01X1162330Y239596D02*
X1164580D01*
G01X1175849Y247396D02*
X1178099D01*
G01X1175849Y243496D02*
X1178099D01*
G01X1169089Y247396D02*
X1171339D01*
G01X1169089Y231797D02*
X1171339D01*
G01X1162330Y247396D02*
X1164580D01*
G01X1158950Y249347D02*
X1161200D01*
G01X1179229Y222047D02*
X1181479D01*
G01X1198379Y255196D02*
Y256017D01*
X1199509Y257147D01*
G01X1205139Y274696D02*
X1202889D01*
G01X1208519Y264947D02*
X1206269D01*
G01X1181479Y268847D02*
Y268026D01*
X1182609Y266896D01*
G01X1194999Y268847D02*
X1192749D01*
G01X1194999Y264947D02*
X1192749D01*
G01X1208519Y233746D02*
X1206269D01*
G01X1212199Y251296D02*
Y252646D01*
X1209649Y255196D01*
G01X1184859Y251296D02*
X1182609D01*
G01X1194999Y225947D02*
X1192749D01*
G01X1201759Y249347D02*
X1199509D01*
G01X1201759Y229847D02*
X1206269D01*
G01X1188239Y249347D02*
X1185989D01*
G01X1188239Y222047D02*
X1192749D01*
G01X1196129Y251296D02*
X1198379D01*
G01X1182609Y255196D02*
X1184859D01*
G01X1189369Y270796D02*
X1191619D01*
G01X1194999Y276646D02*
X1192749D01*
G01X1196129Y270796D02*
X1198379D01*
G01X1196129Y262996D02*
X1198379D01*
G01X1189369Y223996D02*
X1191619D01*
G01X1194999Y237647D02*
X1192749D01*
G01X1199509Y245447D02*
X1201759D01*
G01X1199509Y237647D02*
X1201759D01*
G01X1196129Y227896D02*
X1198379D01*
G01X1202889Y231797D02*
X1205139D01*
G01X1182609Y223996D02*
X1184859D01*
G01X1175849Y270796D02*
X1178099D01*
G01X1175849Y278596D02*
X1178099D01*
G01X1179229Y264947D02*
X1181479D01*
G01X1175849Y223996D02*
X1178099D01*
G01X1167960Y222047D02*
X1165710D01*
G01X1162330Y220096D02*
X1164580D01*
G01X1158950Y222047D02*
X1161200D01*
G01X1179229Y249347D02*
X1181479D01*
G01X1179229Y241547D02*
X1181479D01*
G01X1179229Y237647D02*
X1181479D01*
G01X1192749Y296147D02*
X1194999D01*
G01Y319547D02*
X1192749D01*
G01X1194999Y315647D02*
X1192749D01*
G01X1199509Y323446D02*
X1201759D01*
G01X1206269Y319547D02*
X1208823D01*
X1208826Y319544D01*
G01X1212200Y333196D02*
X1209649D01*
G01X1206269Y342947D02*
Y342879D01*
X1207492Y341656D01*
Y340556D01*
X1208519Y339529D01*
Y339047D01*
G01X1209649Y333196D02*
X1208220D01*
X1206269Y335147D01*
G01X1182609Y329296D02*
X1184859D01*
G01X1182609Y321496D02*
X1184859D01*
G01X1189369Y294196D02*
X1191619D01*
G01X1189369Y298096D02*
X1191619D01*
G01X1185989Y292247D02*
X1188239D01*
G01X1185989Y284447D02*
X1188239D01*
G01X1185989Y288347D02*
X1188239D01*
G01X1202889Y309797D02*
X1205500D01*
G01X1199509Y284447D02*
X1201759D01*
G01X1199509Y288347D02*
X1201759D01*
G01X1194999Y303947D02*
X1192749D01*
G01X1194999Y307847D02*
X1192749D01*
G01X1194999Y288347D02*
X1192749D01*
G01X1194999Y292247D02*
X1192749D01*
G01X1194999Y280547D02*
X1192749D01*
G01X1194999Y300047D02*
X1192749D01*
G01X1202889Y298096D02*
X1205439D01*
G01X1196129Y286396D02*
X1198379D01*
G01X1196129Y309797D02*
X1198379D01*
G01X1202889Y305896D02*
X1205439D01*
G01X1206269Y280547D02*
X1208819D01*
G01X1182609Y309797D02*
X1184859D01*
G01X1182609Y294196D02*
X1184859D01*
G01X1182609Y290296D02*
X1184859D01*
G01X1182609Y301996D02*
X1184859D01*
G01X1185989Y319547D02*
X1188239D01*
G01X1189369Y321496D02*
X1191619D01*
G01X1179229Y311747D02*
X1181479D01*
G01X1158950Y335147D02*
X1161200D01*
G01X1169089Y325396D02*
X1171339D01*
G01X1179229Y319547D02*
X1181479D01*
G01X1179229Y327347D02*
X1181479D01*
G01X1179229Y335147D02*
X1181479D01*
G01X1172469Y315647D02*
X1174719D01*
G01X1175849Y317596D02*
X1178099D01*
G01X1169089D02*
X1171339D01*
G01X1162330Y321496D02*
X1164580D01*
G01X1162330Y317596D02*
X1164580D01*
G01X1158950Y323446D02*
X1161200D01*
G01X1158950Y319547D02*
X1161200D01*
G01X1162330Y325396D02*
X1164580D01*
G01X1162330Y333196D02*
X1164580D01*
G01X1158950Y327347D02*
X1161200D01*
G01X1158950Y331247D02*
X1161200D01*
G01X1167960Y327347D02*
X1165710D01*
G01X1158950Y315647D02*
X1161200D01*
G01X1167960Y323446D02*
X1165710D01*
G01X1167960Y315647D02*
X1165710D01*
G01X1167960Y319547D02*
X1165710D01*
G01X1162330Y329296D02*
X1164580D01*
G01X1158950Y339047D02*
X1161200D01*
G01X1179229Y307847D02*
X1181479D01*
G01X1179229Y303947D02*
X1181479D01*
G01X1179229Y300047D02*
X1181479D01*
G01X1175849Y298096D02*
X1178099D01*
G01X1162330Y286396D02*
X1164580D01*
G01X1175849Y294196D02*
X1178099D01*
G01X1162330D02*
X1164580D01*
G01X1172469Y280547D02*
X1174719D01*
G01X1162330Y290296D02*
X1164580D01*
G01X1175849Y286396D02*
X1178099D01*
G01X1172469Y284447D02*
X1174719D01*
G01X1158950D02*
X1161200D01*
G01X1158950Y307847D02*
X1161200D01*
G01X1169089Y301996D02*
X1171339D01*
G01X1162330D02*
X1164580D01*
G01X1172469Y300047D02*
X1174719D01*
G01X1179229Y292247D02*
X1181479D01*
G01X1179229Y288347D02*
X1181479D01*
G01X1194999Y296147D02*
X1199509D01*
G01X1196129Y337096D02*
X1198379D01*
G01X1196129Y329296D02*
X1198379D01*
G01X1182609Y325396D02*
X1184859D01*
G01X1182609Y333196D02*
X1184859D01*
G01X1196129Y282496D02*
X1198379D01*
G01X1169089Y321496D02*
X1171339D01*
G01X1172469Y339047D02*
X1174719D01*
G01X1167960Y331247D02*
X1165710D01*
G01X1162330Y340996D02*
X1164580D01*
G01X1172469Y311747D02*
X1174719D01*
G01X1167960D02*
X1165710D01*
G01X1162330Y313696D02*
X1164580D01*
G01X1169089D02*
X1171339D01*
G01X1175849D02*
X1178099D01*
G01X1175849Y305896D02*
X1178099D01*
G01X1174719Y307847D02*
X1172469D01*
G01X1175849Y301996D02*
X1178099D01*
G01X1175849Y309797D02*
X1178099D01*
G01X1167960Y303947D02*
X1165710D01*
G01X1172469D02*
X1174719D01*
G01X1169089Y309797D02*
X1171339D01*
G01X1167960Y307847D02*
X1165710D01*
G01X1162330Y305896D02*
X1164580D01*
G01X1162330Y309797D02*
X1164580D01*
G01X1171339Y305896D02*
X1169089D01*
G01X1175849Y290296D02*
X1178099D01*
G01X1161200Y296147D02*
X1158950D01*
G01X1167960Y288347D02*
X1165710D01*
G01X1167960Y292247D02*
X1165710D01*
G01X1167960Y296147D02*
X1165710D01*
G01X1164580Y298096D02*
X1162330D01*
G01X1167960Y300047D02*
X1165710D01*
G01X1169089Y290296D02*
X1171339D01*
G01X1169089Y286396D02*
X1171339D01*
G01X1172469Y288347D02*
X1174719D01*
G01X1172469Y292247D02*
X1174719D01*
G01X1172469Y296147D02*
X1174719D01*
G01X1169089Y294196D02*
X1171339D01*
G01X1169089Y298096D02*
X1171339D01*
G01X1192749Y366347D02*
X1194999D01*
G01X1192749Y358547D02*
Y359366D01*
X1191619Y360496D01*
G01X1206269Y370247D02*
X1209219D01*
G01X1209649Y356597D02*
X1212199D01*
G01X1209649Y352696D02*
X1212199D01*
G01X1209649Y344896D02*
X1212199D01*
G01X1182609Y356596D02*
X1184859D01*
G01X1189369Y376096D02*
X1188239Y377226D01*
Y378047D01*
G01X1194999Y385847D02*
X1192749D01*
G01X1202889Y387796D02*
Y388617D01*
X1201759Y389747D01*
G01X1196129Y395597D02*
X1197258Y397546D01*
G01X1185989Y393647D02*
X1188239D01*
G01X1199509Y378047D02*
X1201759D01*
G01X1206269Y381947D02*
X1208769D01*
X1208819Y381897D01*
G01X1206269Y393647D02*
X1208819D01*
G01X1182609Y383896D02*
X1184859D01*
G01X1192749Y401447D02*
X1194250Y402948D01*
Y404364D01*
X1195355Y405469D01*
Y405673D01*
X1195455Y405773D01*
X1195555D01*
G01X1206269Y374146D02*
X1209769D01*
G01X1179229Y389747D02*
X1181479D01*
G01X1165710D02*
X1167960D01*
G01X1172469Y393647D02*
X1174719D01*
G01X1162330Y379996D02*
X1164580D01*
G01X1158950Y378047D02*
X1161200D01*
G01X1172469Y381947D02*
X1174719D01*
G01X1172469Y342947D02*
X1174719D01*
G01X1167960D02*
X1165710D01*
G01X1194999Y366347D02*
Y367166D01*
X1196129Y368296D01*
G01X1188239Y366347D02*
Y367166D01*
X1189369Y368296D01*
G01X1178099Y403396D02*
X1179229Y402266D01*
Y401447D01*
G01X1185989Y381947D02*
X1188239D01*
G01X1206269Y385847D02*
X1208819D01*
G01X1189369Y372197D02*
X1191619D01*
G01X1189369Y364396D02*
X1191619D01*
G01X1185989Y370247D02*
X1188239D01*
G01X1189369Y352696D02*
X1191619D01*
G01X1158950Y374146D02*
X1161200D01*
G01X1162330Y399496D02*
X1164580D01*
G01X1179229Y385847D02*
X1181479D01*
G01X1172469Y397546D02*
X1174719D01*
G01X1175849Y391696D02*
X1178099D01*
G01X1167960Y366347D02*
X1165710D01*
G01X1169089Y368296D02*
X1171339D01*
G01X1167960Y358547D02*
X1165710D01*
G01X1169089Y344896D02*
X1171339D01*
G01X1172469Y350747D02*
X1174719D01*
G01X1185989Y405347D02*
Y407800D01*
G01X1179229Y405347D02*
X1181479D01*
G01X1254024Y128013D02*
X1254400Y127637D01*
Y125400D01*
G01X1230906Y109155D02*
Y107028D01*
X1234834Y103100D01*
X1237400D01*
G01X1250900Y125400D02*
X1246837D01*
X1244354Y122917D01*
X1242856D01*
X1241406Y121467D01*
Y119155D01*
G01X1250900Y125400D02*
Y127481D01*
X1251344Y127925D01*
G01X1278000Y138000D02*
X1279000D01*
X1285450Y144450D01*
X1295700D01*
G01X1309870Y499254D02*
X1307624Y501500D01*
X1304900D01*
X1300907Y505493D01*
X1284407D01*
X1280300Y509600D01*
Y515100D01*
X1278410Y516990D01*
X1275540D01*
G01X1272060Y517090D02*
X1274010D01*
X1274117Y516983D01*
X1275533D01*
X1275540Y516990D01*
G01X1272060Y517090D02*
Y518750D01*
X1273060Y519750D01*
X1278419D01*
X1278573Y519596D01*
G01X1338000Y46000D02*
X1341000D01*
X1341100Y46100D01*
X1341400D01*
G01X1336500Y83500D02*
X1334000D01*
X1331800Y85700D01*
X1328560D01*
X1326600Y83740D01*
Y80900D01*
G01X1330500Y77800D02*
X1329550D01*
X1328550Y78800D01*
Y80150D01*
X1327800Y80900D01*
X1326600D01*
G01X1336500Y83500D02*
Y81100D01*
G01X1322000Y95000D02*
Y91500D01*
G01Y88000D02*
X1325500D01*
G01X1323000Y83000D02*
Y85170D01*
X1322000Y86170D01*
Y88000D01*
G01X1325500Y91500D02*
Y95000D01*
G01X1328500Y95100D02*
Y92500D01*
G01X1322628Y100134D02*
X1321944Y99450D01*
X1319200D01*
G01X1344500Y110100D02*
X1345866Y111466D01*
X1348550D01*
G01X1322000Y95000D02*
X1319000D01*
G01X1328500Y95100D02*
X1325600D01*
X1325500Y95000D01*
G01X1296468Y437500D02*
X1297618Y438650D01*
Y439925D01*
G01X1300315Y427902D02*
X1299665Y428390D01*
X1297618Y429925D01*
G01X1343350Y522066D02*
X1339331D01*
X1338069Y520804D01*
G01X1343350Y516160D02*
X1340860D01*
X1340500Y515800D01*
X1339600D01*
G01X1327250Y501000D02*
X1324030D01*
X1323450Y500420D01*
G01X1326900Y504750D02*
X1323900D01*
G01D02*
Y502894D01*
X1323192Y502186D01*
Y500678D01*
X1323450Y500420D01*
G01X1332600Y506300D02*
Y505750D01*
X1331600Y504750D01*
X1330000D01*
G01D02*
Y503760D01*
X1330750Y503010D01*
Y501000D01*
G01X1341600Y505250D02*
X1344900D01*
G01X1330000Y508250D02*
X1326900D01*
G01X1332500Y509100D02*
X1331650Y508250D01*
X1330000D01*
G01X1345642Y511900D02*
X1344670D01*
X1339661Y506891D01*
Y506595D01*
X1339076Y506010D01*
X1339060D01*
X1338300Y505250D01*
G01X1343350Y518129D02*
X1340671D01*
X1339900Y518900D01*
G01X1388294Y-5675D02*
X1387806Y-5187D01*
Y-3320D01*
X1387497Y-3011D01*
G01X1384371Y-3020D02*
X1387488D01*
X1387497Y-3011D01*
G01X1386727Y4966D02*
X1389523D01*
G01X1370855Y2573D02*
Y4205D01*
X1372989Y6339D01*
Y8876D01*
G01X1382934Y-17458D02*
X1385581D01*
X1385608Y-17485D01*
G01X1380008Y-3805D02*
X1378813Y-5000D01*
X1378364D01*
X1377294Y-6070D01*
X1375048D01*
G01X1367311Y2573D02*
Y5254D01*
X1366789Y5776D01*
G01X1366589Y8376D02*
Y5976D01*
X1366789Y5776D01*
G01X1375359Y25954D02*
X1378200D01*
X1379200Y26954D01*
Y27000D01*
G01X1372626Y2573D02*
X1374261D01*
X1376094Y4406D01*
G01X1375359Y20639D02*
X1377321D01*
X1378053Y19907D01*
G01X1375048Y-11385D02*
X1377563D01*
X1378974Y-12796D01*
G01X1369083Y2573D02*
Y4569D01*
X1369389Y4875D01*
Y5776D01*
G01X1381642Y25898D02*
X1380190Y24446D01*
X1377292D01*
X1377029Y24183D01*
X1375359D01*
G01X1375048Y-7841D02*
X1378501D01*
X1378907Y-7435D01*
X1380261D01*
X1382151Y-5545D01*
G01X1384371Y480D02*
X1383310D01*
X1382426Y-404D01*
X1380696D01*
X1380678Y-422D01*
G01X1384200Y31700D02*
X1382418D01*
X1380950Y30232D01*
G01X1375359Y27726D02*
X1377095D01*
X1378869Y29500D01*
X1380218D01*
X1380950Y30232D01*
G01X1375048Y-4298D02*
X1376602D01*
X1380478Y-422D01*
X1380678D01*
G01X1378004Y22411D02*
X1375359D01*
G01X1375048Y-9613D02*
X1378839D01*
X1379025Y-9799D01*
G01X1370100Y79500D02*
Y82500D01*
G01X1366100Y79500D02*
Y82500D01*
G01X1388627Y35032D02*
X1388459Y35200D01*
X1384200D01*
G01X1378000Y54500D02*
X1380500D01*
G01X1344000Y80500D02*
Y83000D01*
G01X1374500Y73500D02*
Y75000D01*
X1375500Y76000D01*
G01X1378000Y73500D02*
X1375500Y76000D01*
G01X1371166Y34597D02*
Y36551D01*
X1372400Y37785D01*
G01X1364489Y37693D02*
Y37513D01*
X1365851Y36151D01*
Y34597D01*
G01X1384300Y43900D02*
X1382817D01*
X1381817Y44900D01*
Y46484D01*
G01X1370820Y43895D02*
X1366123D01*
X1363400Y41172D01*
G01D02*
Y40200D01*
G01X1376912Y87578D02*
Y90682D01*
X1375412Y92182D01*
G01X1367622Y34597D02*
Y37278D01*
X1367100Y37800D01*
G01X1377009Y39753D02*
Y37741D01*
X1373865Y34597D01*
X1372937D01*
G01X1376912Y79978D02*
X1382771Y74119D01*
Y67611D01*
X1380675Y65515D01*
X1377504D01*
G01X1374177Y65482D02*
X1377471D01*
X1377504Y65515D01*
G01X1374177Y65482D02*
X1372614D01*
X1372232Y65100D01*
X1369400D01*
G01X1369394Y34597D02*
Y37494D01*
X1369700Y37800D01*
G01X1360141Y73141D02*
X1361382Y74382D01*
Y75282D01*
X1363500Y77400D01*
G01X1374500Y58500D02*
X1372238D01*
X1371738Y59000D01*
X1371198D01*
X1370849Y59349D01*
G01X1371910Y48800D02*
Y53590D01*
X1369716Y55784D01*
G01X1374500Y50500D02*
Y49800D01*
X1373500Y48800D01*
X1371910D01*
G01X1351500Y80500D02*
Y83000D01*
G01X1384771Y79997D02*
Y66715D01*
X1380071Y62015D01*
X1377504D01*
G01X1369037Y62862D02*
X1370599Y61300D01*
X1372499D01*
X1373181Y61982D01*
X1374177D01*
G01D02*
X1377471D01*
X1377504Y62015D01*
G01X1353500Y89140D02*
X1350500D01*
G01X1353500Y96959D02*
Y92340D01*
G01D02*
X1352160D01*
X1351860Y92640D01*
X1350500D01*
G01X1359657Y96096D02*
Y93493D01*
X1360700Y92450D01*
G01X1347000Y93500D02*
Y94391D01*
X1348615Y96006D01*
Y96239D01*
G01X1357000Y89140D02*
Y92340D01*
G01Y96213D02*
Y92340D01*
G01X1383171Y57549D02*
X1382122Y56500D01*
X1375500D01*
X1374500Y55500D01*
Y54500D01*
G01X1378464Y91979D02*
X1383536D01*
X1384771Y90744D01*
Y87597D01*
G01X1370850Y111466D02*
X1364634D01*
G01D02*
X1359700Y116400D01*
G01X1348550Y105560D02*
X1346060D01*
X1345000Y104500D01*
G01X1348550Y107529D02*
X1345500D01*
G01X1352810Y101300D02*
Y97649D01*
X1353500Y96959D01*
G01X1356747Y101300D02*
Y99529D01*
X1359657Y96619D01*
Y96096D01*
G01X1350842Y101300D02*
Y99472D01*
X1348615Y97245D01*
Y96239D01*
G01X1354779Y101300D02*
Y99471D01*
X1357000Y97250D01*
Y96213D01*
G01X1415450Y350550D02*
X1426609Y339391D01*
Y299609D01*
X1419500Y292500D01*
X1371815D01*
X1365246Y285931D01*
G01X1392200Y394845D02*
X1394635D01*
X1394760Y394720D01*
G01X1392200Y394845D02*
Y393500D01*
X1393200Y392500D01*
Y391745D01*
G01X1394760Y394720D02*
X1398280Y391200D01*
Y388701D01*
G01X1389450Y372250D02*
X1388924Y372776D01*
X1386100D01*
G01X1369929Y393465D02*
Y396146D01*
X1369407Y396668D01*
G01X1375244Y393465D02*
X1376172D01*
X1377275Y394568D01*
X1378207D01*
G01X1380872Y378098D02*
X1379463Y379507D01*
X1377666D01*
G01X1371701Y393465D02*
Y396362D01*
X1372007Y396668D01*
G01X1380900Y383164D02*
X1380787Y383051D01*
X1377666D01*
G01Y386594D02*
X1379194D01*
X1380000Y387400D01*
X1380613D01*
X1380713Y387500D01*
X1388600D01*
X1388900Y387800D01*
G01D02*
X1389801Y388701D01*
X1394780D01*
G01X1377666Y381279D02*
X1380393D01*
X1380402Y381270D01*
X1382500D01*
G01D02*
X1383330D01*
X1384250Y380350D01*
G01X1377618Y454925D02*
X1380100Y452500D01*
G01X1377618Y449925D02*
X1380100Y447500D01*
G01X1354500Y527000D02*
X1359434Y522066D01*
G01D02*
X1365650D01*
G01X1400445Y510159D02*
Y511074D01*
X1405847Y516476D01*
X1431474D01*
X1440622Y525624D01*
Y527961D01*
X1439200Y529383D01*
Y531100D01*
G01X1396871Y509300D02*
X1399586D01*
X1400445Y510159D01*
G01X1391291Y528436D02*
Y525647D01*
X1394079Y522859D01*
X1396956D01*
X1398274Y521541D01*
Y512330D01*
X1400445Y510159D01*
G01X1358000Y501800D02*
Y503612D01*
X1356400Y505212D01*
Y507900D01*
G01D02*
X1355800Y508500D01*
G01X1344900Y501750D02*
Y501600D01*
X1346250Y500250D01*
X1346950D01*
X1348200Y499000D01*
G01X1344900Y505250D02*
X1347081Y507431D01*
Y507919D01*
G01X1348200Y502200D02*
Y502900D01*
X1345850Y505250D01*
X1344900D01*
G01X1347081Y507919D02*
X1347221Y508059D01*
Y509762D01*
X1347610Y510151D01*
Y511900D01*
G01X1351547D02*
Y510349D01*
X1353700Y508196D01*
Y506600D01*
X1354254Y506046D01*
Y505212D01*
X1354309Y505157D01*
G01D02*
X1354254Y505102D01*
Y503446D01*
X1354500Y503200D01*
Y501800D01*
G01X1349579Y511900D02*
Y508000D01*
X1349000Y507421D01*
Y505800D01*
G01X1351700Y499000D02*
Y502200D01*
G01X1349000Y505800D02*
Y505100D01*
X1350000Y504100D01*
X1351100D01*
X1351700Y503500D01*
Y502200D01*
G01X1400222Y554185D02*
Y556077D01*
X1401777Y557632D01*
G01X1375166Y581453D02*
Y583066D01*
X1376428Y584328D01*
X1376800D01*
G01X1368605Y584491D02*
X1369150Y583946D01*
Y583848D01*
X1369851Y583147D01*
Y581453D01*
G01X1371622D02*
Y584134D01*
X1371100Y584656D01*
G01X1379359Y572810D02*
X1383421D01*
X1385316Y574705D01*
G01X1379053Y581864D02*
X1378642Y581453D01*
X1376937D01*
G01X1398226Y539962D02*
X1396888D01*
X1395948Y540902D01*
X1394664D01*
G01X1402623Y540018D02*
X1400994D01*
X1400938Y539962D01*
X1398226D01*
G01X1394664Y540902D02*
X1392402D01*
X1390500Y539000D01*
G01X1382623Y565804D02*
X1380932Y567495D01*
X1379359D01*
G01X1373394Y581453D02*
Y584350D01*
X1373700Y584656D01*
G01X1379359Y571039D02*
X1381932D01*
X1382250Y571357D01*
X1385211D01*
X1387986Y574132D01*
Y574960D01*
G01X1405460Y528455D02*
X1401960D01*
G01X1394664Y544402D02*
X1395718D01*
X1396658Y543462D01*
X1398226D01*
G01X1390462Y541800D02*
X1391564Y542902D01*
X1393164D01*
X1394664Y544402D01*
G01X1398226Y543462D02*
X1399630D01*
X1401499Y541593D01*
G01X1379359Y574582D02*
X1381682D01*
X1382500Y575400D01*
G01X1397235Y551044D02*
X1397060Y551219D01*
Y556972D01*
X1400216Y560128D01*
G01X1379359Y569267D02*
X1381923D01*
X1382283Y568907D01*
X1383075D01*
G01X1376800Y615756D02*
X1376556D01*
G01X1375166Y612653D02*
Y614366D01*
X1376556Y615756D01*
G01X1387050Y615350D02*
Y614050D01*
X1385800Y612800D01*
Y612500D01*
G01X1368700Y616700D02*
Y615300D01*
X1369851Y614149D01*
Y612653D01*
G01X1371622D02*
Y615234D01*
X1371100Y615756D01*
G01D02*
Y617100D01*
X1371700Y617700D01*
Y619200D01*
G01X1379359Y604010D02*
X1382810D01*
X1384489Y605689D01*
X1384744D01*
G01X1376937Y612653D02*
X1378387D01*
X1379546Y613812D01*
Y614476D01*
X1380890Y615820D01*
G01X1379359Y598695D02*
X1381212D01*
X1382509Y597398D01*
Y597000D01*
X1383004Y596505D01*
G01X1373394Y612653D02*
Y614796D01*
X1373400Y614802D01*
Y615723D01*
X1373838Y616161D01*
G01X1379359Y602239D02*
X1383927D01*
X1384288Y602600D01*
X1384900D01*
X1385000Y602700D01*
G01X1379359Y605782D02*
X1381382D01*
X1381900Y606300D01*
X1382200D01*
G01X1379359Y600467D02*
X1383783D01*
X1384225Y600025D01*
G01X1460965Y30669D02*
Y30906D01*
G01X1452648Y103788D02*
X1452626D01*
Y103155D01*
X1449824Y100353D01*
X1446179D01*
G01X1445232Y173080D02*
X1448999D01*
X1451365Y170714D01*
Y170318D01*
G01X1448603Y273603D02*
X1450177Y275177D01*
G01X1445454Y270454D02*
X1447028Y272028D01*
G01X1454902Y279902D02*
X1456476Y281476D01*
G01X1451753Y276753D02*
X1453327Y278327D01*
G01X1457131Y252416D02*
Y253287D01*
X1455592Y254826D01*
X1455600D01*
G01X1445339Y255160D02*
Y261848D01*
X1442432Y264755D01*
Y267174D01*
X1442303Y267303D01*
G01X1454902Y276753D02*
X1456476Y278327D01*
G01X1451753Y279902D02*
X1453327Y281476D01*
G01X1442303Y267303D02*
X1443878Y268878D01*
G01X1456476Y303524D02*
X1454902Y305098D01*
G01X1447028Y312972D02*
X1448603Y311397D01*
G01X1458051Y283051D02*
X1459626Y284626D01*
G01X1464351Y289351D02*
X1465925Y290925D01*
G01X1458051Y301949D02*
X1459626Y300374D01*
G01X1465925Y294075D02*
X1464351Y295649D01*
G01X1448603Y311397D02*
X1450177Y309823D01*
G01X1454902Y305098D02*
X1453327Y306673D01*
G01X1461202Y286202D02*
X1462776Y287776D01*
G01Y290925D02*
Y294075D01*
G01X1461202Y289351D02*
X1462776Y290925D01*
G01X1464351Y286202D02*
X1465925Y287776D01*
G01X1461202Y298798D02*
X1462776Y297224D01*
G01X1464351Y298798D02*
X1465925Y297224D01*
G01X1454902Y308247D02*
X1456476Y306673D01*
G01X1451753Y305098D02*
X1453327Y303524D01*
G01X1443878Y316122D02*
X1445528Y317772D01*
G01X1462776Y294075D02*
X1461202Y295649D01*
G01X1430117Y283989D02*
Y281983D01*
X1431356Y280744D01*
X1433362D01*
G01X1446700Y387900D02*
X1441900D01*
X1441800Y388000D01*
G01X1453900Y398100D02*
X1456267D01*
X1459033Y395334D01*
G01X1453800Y368018D02*
X1460918D01*
X1463400Y370500D01*
X1467501D01*
X1473255Y376254D01*
G01X1441800Y366400D02*
Y367650D01*
X1443100Y368950D01*
G01X1453000Y377750D02*
X1443090D01*
X1441800Y379040D01*
Y388000D01*
G01X1456750Y381850D02*
Y379349D01*
X1455151Y377750D01*
X1453000D01*
G01X1441800Y388000D02*
Y396794D01*
X1443106Y398100D01*
X1453900D01*
G01X1445510Y350327D02*
X1422611D01*
X1419738Y353200D01*
X1415500D01*
G01X1446800Y362900D02*
X1441800D01*
G01X1451000Y373000D02*
Y370600D01*
X1450350Y369950D01*
Y363900D01*
X1449350Y362900D01*
X1446800D01*
G01X1451000Y373000D02*
X1449050D01*
X1448050Y374000D01*
Y374950D01*
G01X1461700Y399000D02*
X1462200Y398500D01*
X1463421D01*
X1464273Y397648D01*
G01X1458450Y361950D02*
X1458826Y362326D01*
X1463074D01*
X1463200Y362200D01*
G01X1451560Y418179D02*
X1450479D01*
X1448800Y416500D01*
G01X1439000Y419350D02*
Y423000D01*
G01X1451560Y418179D02*
X1456731D01*
X1459559Y421007D01*
Y422959D01*
X1464600Y428000D01*
G01X1445100Y431500D02*
X1445300Y431300D01*
Y427618D01*
G01X1448800Y416500D02*
X1448450Y416150D01*
X1436521D01*
X1435451Y417220D01*
Y423079D01*
X1435479Y423107D01*
G01D02*
Y429873D01*
X1437106Y431500D01*
X1445100D01*
G01X1420200Y520500D02*
X1420600Y520900D01*
Y523400D01*
X1421200Y524000D01*
X1422000D01*
G01X1456100Y503000D02*
X1455100D01*
X1453700Y501600D01*
G01X1456100Y506000D02*
Y503000D01*
G01Y509000D02*
X1449405D01*
X1446702Y511703D01*
Y525886D01*
X1441488Y531100D01*
X1439200D01*
G01X1474900Y622900D02*
X1472358D01*
X1471269Y623989D01*
X1461589D01*
G01D02*
X1461000Y623400D01*
G01X1489311Y30669D02*
Y30906D01*
G01X1479863Y30669D02*
Y30906D01*
G01X1470414Y30669D02*
Y30906D01*
G01X1498800Y-12676D02*
Y1700D01*
X1511200Y14100D01*
X1533700D01*
X1541300Y21700D01*
X1547000D01*
X1549156Y23856D01*
X1549334D01*
G01X1520100Y-6500D02*
X1522600D01*
G01X1525000D02*
X1522600D01*
G01X1515294Y91306D02*
X1514588Y90600D01*
X1511900D01*
X1510882Y91618D01*
X1507076D01*
G01X1491164Y82923D02*
Y79093D01*
X1487424Y75353D01*
X1483779D01*
G01X1482832Y148080D02*
X1486980D01*
X1488350Y149450D01*
G01X1507076Y115240D02*
X1510930D01*
X1511635Y114535D01*
G01X1507076Y109334D02*
X1511584D01*
X1511650Y109400D01*
G01X1507076Y103429D02*
X1511621D01*
X1511650Y103400D01*
G01X1507076Y97523D02*
X1510499D01*
X1511651Y98675D01*
G01X1507076Y121145D02*
X1511584D01*
X1511634Y121195D01*
G01X1507076Y127051D02*
X1503351D01*
X1500820Y124520D01*
X1499618D01*
G01X1490900Y146600D02*
Y153672D01*
X1489847Y154725D01*
Y157027D01*
X1490627Y157807D01*
Y165475D01*
X1496713Y171561D01*
Y174853D01*
G01X1498985Y146565D02*
Y149193D01*
X1498609Y149569D01*
Y150642D01*
X1496038Y153213D01*
Y154229D01*
G01X1529699Y215920D02*
X1525380D01*
X1523400Y217900D01*
G01D02*
X1518350D01*
X1518000Y218250D01*
G01X1491196Y218527D02*
X1492548Y217175D01*
Y215132D01*
G01X1511000Y218250D02*
X1509250Y216500D01*
X1503794D01*
X1497241Y209947D01*
X1482413D01*
X1480664Y211696D01*
X1477080D01*
X1475401Y210017D01*
G01D02*
Y209417D01*
X1476389Y208429D01*
Y207078D01*
X1478192Y205275D01*
X1487275D01*
X1488717Y206717D01*
X1502783D01*
X1508815Y200685D01*
Y198685D01*
X1511280Y196220D01*
X1516690D01*
X1519243Y193667D01*
Y191627D01*
G01X1489048Y215132D02*
Y217650D01*
X1488048Y218650D01*
X1487716D01*
G01X1486397Y273603D02*
X1484823Y275177D01*
G01X1489546Y270454D02*
X1487972Y272028D01*
G01X1483247Y276753D02*
X1481673Y278327D01*
G01X1530200Y257200D02*
Y256600D01*
X1526900Y253300D01*
G01X1492697Y267303D02*
X1491122Y268878D01*
G01X1480098Y276753D02*
X1478524Y278327D01*
G01X1483247Y279902D02*
X1481673Y281476D01*
G01X1472500Y341074D02*
Y343750D01*
G01X1526000Y341000D02*
Y343750D01*
G01X1520972Y293257D02*
X1514722D01*
G01X1475374Y284626D02*
X1476949Y283051D01*
G01X1483247Y308247D02*
X1481673Y306673D01*
G01X1480098Y305098D02*
X1478524Y303524D01*
G01X1476949Y301949D02*
X1475374Y300374D01*
G01X1486397Y311397D02*
X1484823Y309823D01*
G01X1489546Y314546D02*
X1487972Y312972D01*
G01X1524250Y314300D02*
X1528250D01*
G01X1470649Y289351D02*
X1469075Y290925D01*
G01Y294075D02*
X1470649Y295649D01*
G01X1476949Y283051D02*
X1478524Y281476D01*
G01X1517600Y320940D02*
X1517897Y321237D01*
X1519716D01*
X1521013Y322534D01*
X1521513D01*
G01X1510987Y318669D02*
X1515329D01*
X1517600Y320940D01*
G01X1514050Y327490D02*
X1513850D01*
X1512670Y328670D01*
X1509930D01*
X1509879Y328619D01*
X1509843D01*
X1509287Y328063D01*
Y328027D01*
X1506929Y325669D01*
X1505869D01*
G01X1531750Y314300D02*
Y308579D01*
X1528000Y304829D01*
Y302800D01*
X1526137Y300937D01*
X1520972D01*
G01X1487858Y340412D02*
X1488238D01*
X1490247Y338403D01*
Y334373D01*
X1491817Y332803D01*
X1499894D01*
X1506231Y339140D01*
X1508700D01*
X1509840Y338000D01*
X1516811D01*
X1518602Y336209D01*
X1527077D01*
X1527078Y336210D01*
X1529532D01*
X1538050Y327692D01*
X1540677D01*
X1541637Y326732D01*
X1542868D01*
X1544200Y325400D01*
Y323100D01*
X1543700Y322600D01*
G01X1509233Y295817D02*
Y297089D01*
X1510476Y298332D01*
Y299316D01*
G01X1509233Y295817D02*
Y292410D01*
X1510276Y291367D01*
X1513854D01*
X1514305Y290916D01*
X1527815D01*
X1530000Y293101D01*
Y304000D01*
X1532600Y306600D01*
X1534700D01*
X1538450Y310350D01*
Y314300D01*
G01X1483247Y305098D02*
X1481673Y303524D01*
G01X1491122Y316122D02*
Y316120D01*
X1492696Y314546D01*
G01X1484620Y339152D02*
Y341720D01*
X1486650Y343750D01*
X1487000D01*
G01X1480098Y308247D02*
X1478524Y306673D01*
G01X1470649Y286202D02*
X1469075Y287776D01*
G01X1473798Y286202D02*
X1472224Y287776D01*
G01X1473798Y289351D02*
X1472224Y290925D01*
G01D02*
Y294075D01*
G01X1470649Y298798D02*
X1469075Y297224D01*
G01X1473798Y298798D02*
X1472224Y297224D01*
G01Y294075D02*
X1473798Y295649D01*
G01X1520000Y343750D02*
Y341766D01*
X1520766Y341000D01*
G01X1505000Y343750D02*
Y340990D01*
G01X1480000Y395098D02*
X1482000D01*
G01D02*
X1481634Y393130D01*
G01X1483000Y347250D02*
Y351634D01*
X1483172Y351806D01*
G01X1501175Y378420D02*
X1503125Y377514D01*
G01X1512875Y378420D02*
X1514825Y377514D01*
G01X1524575Y378420D02*
X1526525Y377514D01*
G01X1499941Y374823D02*
X1503878D01*
G01X1496004D02*
X1499941D01*
G01X1507815D02*
X1503878D01*
G01X1511752D02*
X1507815D01*
G01X1494035Y373189D02*
X1496004Y374823D01*
G01X1515689D02*
X1511752D01*
G01X1523563D02*
X1527500D01*
G01X1519626D02*
X1523563D01*
G01X1519626D02*
X1515689D01*
G01X1519626Y371555D02*
Y374823D01*
G01X1494035Y369921D02*
Y373189D01*
G01X1492067Y374823D02*
X1494035Y373189D01*
G01X1489475Y378420D02*
X1491425Y377514D01*
G01X1484622Y375979D02*
X1484621D01*
X1481437Y376988D01*
G01X1488130Y374823D02*
X1484622Y375979D01*
G01X1492067Y374823D02*
X1488130D01*
G01X1522625Y402080D02*
X1524575Y401174D01*
G01D02*
Y398700D01*
G01X1512875D02*
X1514825Y397794D01*
G01D02*
X1517516Y396287D01*
X1518725Y395320D01*
G01X1507025D02*
X1507600Y395053D01*
X1508975Y394414D01*
G01X1503125Y397794D02*
X1501175Y398700D01*
G01X1495325Y395320D02*
X1497275Y394414D01*
G01X1495325Y388560D02*
X1497275Y387654D01*
G01X1489475Y385180D02*
X1491425Y384274D01*
G01X1495325Y381800D02*
X1497275Y380894D01*
G01X1501175Y391940D02*
X1503125Y391034D01*
G01X1501175Y385180D02*
X1503125Y384274D01*
G01X1507025Y381800D02*
X1507600Y381533D01*
X1508975Y380894D01*
G01X1507025Y388560D02*
X1507600Y388293D01*
X1508975Y387654D01*
G01X1512875Y391940D02*
X1514825Y391034D01*
G01X1518725Y381800D02*
X1520675Y380894D01*
G01X1518725Y388560D02*
X1520675Y387654D01*
G01X1512875Y385180D02*
X1514825Y384274D01*
G01X1524575Y391940D02*
X1526525Y391034D01*
G01Y384274D02*
X1524575Y385180D01*
G01X1514825Y377514D02*
X1515689Y374823D01*
G01X1526525Y377514D02*
X1527500Y374823D01*
G01X1491425Y377514D02*
X1492067Y374823D01*
G01X1503125Y377514D02*
X1503878Y374823D01*
G01X1489475Y391940D02*
X1491425Y391034D01*
G01X1481634Y401004D02*
X1483950Y401650D01*
G01X1480000Y399035D02*
Y399721D01*
X1481283Y401004D01*
X1481634D01*
G01X1476732Y399035D02*
X1480000D01*
G01X1507025Y402080D02*
X1507600Y401813D01*
X1508975Y401174D01*
G01X1495325Y402080D02*
X1497275Y401174D01*
G01X1487879Y368287D02*
Y365981D01*
X1488394Y365466D01*
G01X1519626Y368287D02*
Y365817D01*
G01X1475098Y377868D02*
X1474869D01*
X1473255Y376254D01*
G01D02*
X1474841Y374668D01*
X1475098D01*
G01X1482000Y387224D02*
X1481634Y389193D01*
G01Y385256D02*
X1482000Y387224D01*
G01X1476732D02*
X1480000D01*
G01X1482000D02*
X1480000D01*
G01X1481634Y381319D02*
X1482000Y383287D01*
G01X1484679Y368287D02*
Y366500D01*
X1483679Y365500D01*
X1483500D01*
G01X1484193Y371161D02*
X1484679Y368287D01*
G01X1481105Y371161D02*
X1481479Y368287D01*
G01D02*
X1479637Y365693D01*
X1478500Y365500D01*
G01X1478298Y371487D02*
X1474500Y367689D01*
Y365500D01*
G01X1475098Y381068D02*
X1473118D01*
X1472680Y380630D01*
G01X1475098Y397067D02*
X1474665Y397500D01*
X1472550D01*
G01X1490000Y343750D02*
X1487000D01*
G01X1507025Y408840D02*
X1508320Y407545D01*
Y406115D01*
X1508975Y405460D01*
G01X1512875D02*
X1510925Y404554D01*
G01D02*
X1508975Y405460D01*
G01X1501175Y418980D02*
Y416587D01*
X1501236D01*
Y416596D01*
X1501219D01*
G01X1495325Y415600D02*
X1497275Y414694D01*
G01X1501219Y416596D02*
X1499225Y415600D01*
G01X1522625Y460446D02*
X1520675Y459540D01*
G01X1526525Y460446D02*
X1524575Y459540D01*
G01X1520225Y449825D02*
X1521800Y448250D01*
G01D02*
X1523375Y446675D01*
G01X1516775Y459540D02*
X1518725Y460446D01*
G01X1512875Y459540D02*
X1514825Y460446D01*
G01X1518725Y456160D02*
X1520675Y457066D01*
G01X1491425Y462920D02*
X1493375Y463826D01*
G01X1499225Y462920D02*
X1501175Y463826D01*
G01X1495325Y442640D02*
X1497275Y443546D01*
G01X1495325Y453686D02*
X1493375Y452780D01*
G01X1495325Y446926D02*
X1493375Y446020D01*
G01X1495325Y449400D02*
X1497275Y450306D01*
G01X1495325Y456160D02*
X1497275Y457066D01*
G01X1485575Y452780D02*
X1487525Y453686D01*
G01X1499225Y456160D02*
X1501175Y457066D01*
G01Y459540D02*
X1503125Y460446D01*
G01X1501175Y452780D02*
X1503081Y453666D01*
X1503125Y453786D01*
G01X1505075Y459540D02*
X1505300Y459645D01*
X1507025Y460446D01*
G01X1508975Y459540D02*
X1510925Y460446D01*
G01X1495325Y435880D02*
X1497275Y436786D01*
G01X1495325Y440166D02*
X1493375Y439260D01*
G01X1499225Y435880D02*
X1501175Y436786D01*
G01Y439260D02*
X1503125Y440166D01*
G01X1493375Y412220D02*
X1493849Y412000D01*
X1495325Y411314D01*
G01D02*
Y408840D01*
G01X1485575Y405460D02*
X1487525Y404554D01*
G01X1493375Y405460D02*
X1491425Y404554D01*
G01D02*
X1489475Y405460D01*
G01X1516775D02*
X1518700Y406500D01*
G01X1520225Y412025D02*
Y410340D01*
X1518725Y408840D01*
G01X1518700Y406500D02*
X1518705Y407000D01*
X1518725Y408840D01*
G01X1513925Y415175D02*
X1515500Y416750D01*
G01X1528475Y405460D02*
X1526525Y404554D01*
G01D02*
X1524575Y405460D01*
G01X1487525Y404554D02*
X1489475Y405460D01*
G01X1485575Y418980D02*
X1485677Y418932D01*
X1487525Y418074D01*
G01X1493375Y418980D02*
X1493266Y418929D01*
X1491425Y418074D01*
G01X1487525D02*
X1489369Y418931D01*
X1489475Y418980D01*
G01X1481634Y428563D02*
X1483818Y430597D01*
G01X1478366Y428563D02*
X1481634D01*
G01X1517075Y418325D02*
X1518650Y419900D01*
G01X1526525Y421475D02*
X1524950Y419900D01*
G01D02*
X1523375Y421475D01*
G01X1495325Y433406D02*
X1493375Y432500D01*
G01X1489475D02*
X1491425Y433406D01*
G01X1501175Y432500D02*
X1503125Y433406D01*
G01X1493375Y425740D02*
X1493891Y425500D01*
X1495325Y424834D01*
G01D02*
Y422360D01*
G01Y429120D02*
X1496659Y428500D01*
X1497275Y428214D01*
G01X1501175Y425740D02*
X1501600Y425542D01*
X1501691Y425500D01*
X1503125Y424834D01*
G01X1491425Y418074D02*
X1489581Y418931D01*
X1489475Y418980D01*
G01X1497275Y414694D02*
X1499225Y415600D01*
G01X1501175Y405460D02*
X1503125Y404554D01*
G01X1481634Y432500D02*
X1482500Y434600D01*
G01X1478366Y432500D02*
X1481634D01*
G01X1483400Y438100D02*
X1482126Y436900D01*
X1481634Y436437D01*
G01X1482500Y434600D02*
X1481634Y436437D01*
G01X1485575Y432500D02*
X1482500Y434600D01*
G01X1481634Y456122D02*
Y455860D01*
X1483115Y454379D01*
G01X1480000Y450217D02*
X1481634Y452185D01*
G01X1476732Y450217D02*
X1480000D01*
G01X1481634Y452185D02*
X1483200Y450455D01*
G01D02*
X1481634Y448248D01*
G01X1483115Y454379D02*
X1481634Y452185D01*
G01Y463996D02*
X1482000Y462028D01*
G01D02*
X1481634Y460059D01*
G01Y444311D02*
X1482603Y442418D01*
G01X1478366Y440374D02*
X1481634D01*
G01X1482603Y442418D02*
X1481634Y440374D01*
G01Y424626D02*
X1481797Y425500D01*
X1481834Y425700D01*
X1481890Y426000D01*
X1482000Y426595D01*
G01X1481634Y420689D02*
X1481971Y422500D01*
X1482000Y422658D01*
G01X1478366Y420689D02*
X1481634D01*
G01Y412815D02*
X1481840Y413922D01*
X1482000Y414783D01*
G01X1476732D02*
X1480000D01*
G01X1482000D02*
X1480000D01*
G01X1481634Y408878D02*
X1481898Y410298D01*
X1482000Y410846D01*
G01X1476732D02*
X1480000D01*
G01X1482000D02*
X1480000D01*
G01X1481634Y404941D02*
X1482000Y406909D01*
G01X1478366Y404941D02*
X1481634D01*
G01Y416752D02*
X1482000Y418720D01*
G01X1475098Y420689D02*
X1472800D01*
G01X1475098Y428563D02*
X1472900D01*
X1472400Y428063D01*
G01X1475098Y432500D02*
X1473231D01*
X1473000Y432731D01*
X1472530D01*
G01X1475098Y404941D02*
X1473850D01*
X1472000Y406791D01*
Y406900D01*
X1471900D01*
G01X1475098Y440374D02*
X1473402D01*
X1472449Y439421D01*
G01X1523375Y424625D02*
X1522220Y425780D01*
G01X1520225Y421475D02*
X1521800Y423050D01*
G01X1505073Y452780D02*
X1506030Y453790D01*
G01X1505442Y443900D02*
X1504385D01*
X1503125Y442640D01*
G01X1526525Y449825D02*
X1528010Y451310D01*
G01X1528190D02*
X1526525Y452975D01*
G01X1485575Y446020D02*
X1485300Y445745D01*
Y443484D01*
G01X1526525Y408840D02*
X1528475Y407934D01*
G01X1517075Y446675D02*
X1515500Y448250D01*
G01X1520225Y418325D02*
X1518650Y416750D01*
G01X1522625Y408840D02*
X1524575Y407624D01*
G01X1514825Y408840D02*
X1514696Y408869D01*
X1512983Y407782D01*
X1512954Y407653D01*
G01X1522625Y404554D02*
X1520675Y405460D01*
G01X1522625Y456160D02*
X1524575Y457066D01*
G01X1503125Y456160D02*
X1504600Y456845D01*
X1505075Y457066D01*
G01X1510925Y408840D02*
X1509315Y410450D01*
X1509200D01*
G01D02*
X1507625Y412025D01*
G01X1505075Y446020D02*
X1505714Y448145D01*
G01X1523375Y418325D02*
X1521800Y419900D01*
G01X1513925Y412025D02*
X1512350Y410450D01*
G01X1526525Y415175D02*
X1528100Y413700D01*
G01X1517075Y415175D02*
X1515500Y413600D01*
G01X1509200Y448250D02*
X1510775Y446675D01*
G01X1517075Y449825D02*
X1518650Y448250D01*
G01D02*
X1520225Y446675D01*
G01X1507025Y456160D02*
X1507600Y456427D01*
X1508975Y457066D01*
G01X1528475D02*
X1526525Y456160D01*
G01X1503125Y435880D02*
X1505392Y437133D01*
G01D02*
X1505075Y439260D01*
G01X1503125Y415600D02*
X1505000Y416240D01*
G01X1484679Y496713D02*
X1484573Y496819D01*
Y498235D01*
X1485300Y498962D01*
G01X1525531Y495079D02*
X1527500Y496713D01*
G01X1525531Y491811D02*
Y495079D01*
G01X1527500Y496713D02*
X1526500Y497713D01*
Y498671D01*
G01X1488130Y493445D02*
Y496462D01*
X1487879Y496713D01*
G01D02*
Y498279D01*
X1488500Y498900D01*
G01X1507815Y493445D02*
X1508233Y493863D01*
Y496295D01*
X1507815Y496713D01*
G01Y490177D02*
Y493445D01*
G01Y496713D02*
X1509000Y497898D01*
Y498750D01*
G01X1511752Y496713D02*
X1511333Y496294D01*
Y493864D01*
X1511752Y493445D01*
G01Y498780D02*
Y496713D01*
G01Y490177D02*
X1514825Y487486D01*
G01D02*
X1512875Y486580D01*
G01X1524575Y466300D02*
X1526512Y467200D01*
X1526525Y467206D01*
G01Y473966D02*
X1524575Y473060D01*
G01X1526525Y476440D02*
X1528475Y477346D01*
G01X1526525Y469680D02*
X1528475Y470586D01*
G01X1524575Y486580D02*
X1526525Y487486D01*
G01D02*
X1527074Y489000D01*
X1527500Y490177D01*
G01X1523563D02*
X1524838Y489019D01*
X1524859Y489000D01*
X1526525Y487486D01*
G01X1519626Y490177D02*
X1522625Y487486D01*
G01D02*
X1520675Y486580D01*
G01X1522625Y473966D02*
X1520675Y473060D01*
G01Y466300D02*
X1522612Y467200D01*
X1522625Y467206D01*
G01X1516775Y466300D02*
X1518712Y467200D01*
X1518725Y467206D01*
G01X1516775Y473060D02*
X1518725Y473966D01*
G01Y480726D02*
X1516775Y479820D01*
G01X1515689Y490177D02*
X1518725Y487486D01*
G01D02*
X1516775Y486580D01*
G01X1514825Y469680D02*
X1516775Y470586D01*
G01X1512875Y473060D02*
X1514825Y473966D01*
G01Y480726D02*
X1512875Y479820D01*
G01X1514825Y483200D02*
X1516775Y484106D01*
G01X1487525Y483200D02*
X1487200D01*
X1485575Y481575D01*
Y479820D01*
G01X1489475Y484106D02*
X1487525Y483200D01*
G01X1488130Y490177D02*
X1487865Y489000D01*
X1487525Y487486D01*
G01D02*
X1485575Y486580D01*
G01X1490098Y491811D02*
Y489702D01*
X1490100Y489700D01*
G01X1496004Y490177D02*
X1495577Y489750D01*
X1492494D01*
X1492067Y490177D01*
G01X1490098Y495079D02*
Y491811D01*
G01X1490100Y489700D02*
X1490577Y490177D01*
X1492067D01*
G01X1487525Y469680D02*
X1489475Y470586D01*
G01Y473060D02*
X1490339Y473461D01*
X1491425Y473966D01*
G01X1485575Y473060D02*
X1487525Y473966D01*
G01X1481634Y475807D02*
X1482828D01*
X1485575Y473060D01*
G01X1503878Y490177D02*
X1504600Y489560D01*
X1505255Y489000D01*
X1505500Y488790D01*
X1507025Y487486D01*
G01X1501175Y486580D02*
X1505075D01*
G01X1499941Y490177D02*
X1503878D01*
G01X1507025Y487486D02*
X1505300Y486685D01*
X1505075Y486580D01*
G01X1501175Y466300D02*
X1503112Y467200D01*
X1503125Y467206D01*
G01X1499225Y469680D02*
X1501175Y470586D01*
G01X1503125Y469680D02*
X1504600Y470365D01*
X1505075Y470586D01*
G01X1508975Y473060D02*
X1510925Y473966D01*
G01X1507025Y469680D02*
X1507600Y469947D01*
X1508975Y470586D01*
G01X1510925Y480726D02*
X1508975Y479820D01*
G01X1507025Y476440D02*
X1507600Y476707D01*
X1508975Y477346D01*
G01X1499225Y480726D02*
X1497275Y479820D01*
G01X1475098Y493532D02*
X1473800Y494830D01*
Y495800D01*
G01X1481479Y496713D02*
X1481410Y496782D01*
Y498010D01*
X1482300Y498900D01*
G01X1478279Y496713D02*
Y497421D01*
X1476800Y498900D01*
G01X1481105Y493839D02*
Y493887D01*
X1478279Y496713D01*
G01X1484193Y493839D02*
X1481105D01*
G01X1481634Y467933D02*
X1482000Y469902D01*
G01D02*
X1481634Y471870D01*
G01Y479744D02*
X1481793Y480600D01*
X1482000Y481713D01*
G01X1478366Y483681D02*
X1481634D01*
G01X1475098Y483932D02*
X1478115D01*
X1478366Y483681D01*
G01X1475098Y487132D02*
Y483932D01*
G01Y487132D02*
Y490332D01*
G01X1482000Y481713D02*
X1481980Y481820D01*
X1481742Y483100D01*
X1481634Y483681D01*
G01X1518725Y469680D02*
X1520675Y470586D01*
G01X1522625Y469680D02*
X1524575Y470586D01*
G01X1503226Y623027D02*
X1499511D01*
X1497680Y621196D01*
Y619084D01*
X1501325Y615439D01*
X1502268D01*
G01X1503226Y623027D02*
Y620236D01*
X1503008Y620018D01*
G01X1469982Y605622D02*
X1472332D01*
G01X1516513Y616398D02*
Y619800D01*
X1516400D01*
G01X1480975Y615130D02*
Y620100D01*
G01X1472332Y607393D02*
X1469698D01*
X1469301Y607790D01*
G01D02*
X1468841Y608250D01*
X1466500D01*
G01X1507870Y608661D02*
X1504861D01*
X1504700Y608500D01*
G01X1500445Y619956D02*
Y619258D01*
X1501860Y617843D01*
X1504257D01*
X1506768Y615332D01*
Y614731D01*
X1507523Y613976D01*
X1507870D01*
G01X1467839Y618964D02*
Y617744D01*
X1472332Y613251D01*
Y612708D01*
G01X1521828Y616398D02*
Y618004D01*
X1523100Y619276D01*
G01X1504700Y611100D02*
X1505061Y610739D01*
X1505569D01*
X1505875Y610433D01*
X1507870D01*
G01X1518284Y616398D02*
Y618584D01*
X1518900Y619200D01*
Y619800D01*
G01X1486290Y615130D02*
Y616626D01*
X1487932Y618268D01*
G01X1472332Y609165D02*
X1470774D01*
X1469200Y610739D01*
G01X1483279Y619100D02*
Y618921D01*
X1482746Y618388D01*
Y615130D01*
G01X1514741Y616398D02*
Y618759D01*
X1513800Y619700D01*
Y619800D01*
X1513700Y619900D01*
G01X1478400Y622900D02*
Y619400D01*
X1478500Y619300D01*
G01D02*
Y618500D01*
X1479203Y617797D01*
Y615130D01*
G01X1520056Y616398D02*
Y618257D01*
X1521094Y619295D01*
Y621175D01*
G01X1484518Y615130D02*
Y616818D01*
X1485173Y617473D01*
Y620592D01*
G01X1576800Y-6800D02*
X1579349D01*
X1579447Y-6702D01*
G01X1560700Y13000D02*
X1560909Y13209D01*
Y17268D01*
G01X1554609Y30668D02*
Y37180D01*
X1554573Y37216D01*
G01X1564059Y30668D02*
Y37180D01*
X1564023Y37216D01*
G01X1551309Y12792D02*
X1551459Y12942D01*
Y17268D01*
G01X1579809D02*
Y13293D01*
X1579773Y13257D01*
G01X1573509Y30668D02*
Y37180D01*
X1573473Y37216D01*
G01X1582959Y30668D02*
Y37180D01*
X1582923Y37216D01*
G01X1570359Y17268D02*
Y13059D01*
X1570200Y12900D01*
G01X1528384Y28040D02*
X1529899Y29555D01*
X1537580D01*
X1540071Y27064D01*
X1544159D01*
X1545159Y28064D01*
Y30668D01*
G01X1547800Y-6200D02*
X1545582D01*
X1544882Y-6900D01*
G01X1585500Y101000D02*
X1583208D01*
X1582500Y100292D01*
Y98000D01*
G01X1580920Y112185D02*
X1578815D01*
X1578000Y113000D01*
G01X1536801Y96539D02*
X1541139D01*
X1541900Y97300D01*
G01X1574536Y159073D02*
X1576110D01*
X1577700Y157483D01*
Y155353D01*
G01D02*
X1578015D01*
X1582250Y151118D01*
Y149600D01*
G01X1590949Y97850D02*
X1588150D01*
X1588000Y98000D01*
X1585500D01*
G01X1576731Y131910D02*
Y134131D01*
X1578138Y135538D01*
X1581500D01*
G01X1576731Y131910D02*
X1571691D01*
X1570392Y133209D01*
Y134959D01*
G01X1587222Y112169D02*
X1588915D01*
X1589622Y112876D01*
G01X1586210Y104240D02*
X1586950Y103500D01*
Y102308D01*
X1588000Y101258D01*
Y100500D01*
G01X1562079Y163580D02*
X1562920D01*
X1567427Y159073D01*
X1571036D01*
G01X1583874Y217746D02*
Y211770D01*
X1582874Y210770D01*
X1581700D01*
G01X1576958Y253988D02*
X1576943Y253973D01*
G01D02*
X1572807D01*
X1572684Y253850D01*
X1571068D01*
X1570114Y254804D01*
X1558703D01*
X1550852Y246953D01*
Y246702D01*
G01X1546399Y252647D02*
Y251444D01*
X1547874Y249969D01*
X1550769D01*
X1551900Y251100D01*
Y257262D01*
X1553438Y258800D01*
X1554400D01*
G01X1543399Y251250D02*
X1545002D01*
X1546399Y252647D01*
G01X1543399Y251250D02*
X1542050D01*
X1541550Y250750D01*
X1540000D01*
G01X1543399Y251250D02*
X1547375Y247274D01*
Y245850D01*
G01X1549899Y255747D02*
Y252647D01*
G01X1544200Y246200D02*
Y243900D01*
X1547479Y240621D01*
X1549600D01*
X1550852Y241873D01*
Y243202D01*
G01X1537000Y250750D02*
Y249213D01*
X1538000Y248213D01*
X1542187D01*
X1544200Y246200D01*
G01X1544472Y293257D02*
X1539843D01*
X1537880Y295220D01*
Y299661D01*
X1539156Y300937D01*
X1544472D01*
G01X1554800Y290600D02*
X1553419Y291981D01*
X1549713D01*
X1548437Y293257D01*
X1544472D01*
G01X1544500Y290500D02*
Y293229D01*
X1544472Y293257D01*
G01X1547651Y336246D02*
X1546444D01*
X1545367Y337323D01*
X1543957D01*
G01X1557250Y315410D02*
Y312500D01*
G01X1528250Y311900D02*
Y314300D01*
G01X1530033Y340799D02*
X1532000Y342766D01*
Y343750D01*
G01X1528250Y314300D02*
Y317400D01*
G01X1565947Y295474D02*
Y296480D01*
X1566947Y297480D01*
X1573460D01*
X1574940Y296000D01*
X1577500D01*
G01X1583559Y321059D02*
Y323524D01*
X1583641Y323606D01*
Y328394D01*
X1583559Y328476D01*
Y328691D01*
X1582900Y329350D01*
X1580283D01*
X1580150Y329483D01*
G01X1578630Y293430D02*
X1578500D01*
X1577500Y294430D01*
Y296000D01*
G01X1580150Y329483D02*
Y332000D01*
X1581150Y333000D01*
X1581941D01*
G01X1540957Y337323D02*
X1543957D01*
G01X1544904Y334008D02*
Y334096D01*
X1543957Y335043D01*
Y337323D01*
G01X1539400Y320200D02*
Y321156D01*
X1538090Y322466D01*
X1536728D01*
G01X1551404Y309376D02*
X1551980Y309952D01*
Y310730D01*
X1553750Y312500D01*
G01X1541300Y313350D02*
Y309701D01*
X1542384Y308617D01*
X1544472D01*
G01D02*
X1550024D01*
X1550783Y309376D01*
X1551404D01*
G01X1533228Y325000D02*
Y322466D01*
G01X1528513Y327652D02*
X1530417D01*
X1533069Y325000D01*
X1533228D01*
G01X1541300Y316850D02*
X1538450D01*
X1537500Y317800D01*
X1535250D01*
G01X1531750Y314300D02*
Y317400D01*
G01X1535250Y317800D02*
X1533820D01*
X1533420Y317400D01*
X1531750D01*
G01X1538450Y314300D02*
X1535250D01*
G01X1587059Y321059D02*
Y318359D01*
X1585570Y316870D01*
Y316610D01*
G01X1550500Y343750D02*
Y335500D01*
X1551250Y334750D01*
X1553500D01*
G01D02*
Y333603D01*
X1554932Y332171D01*
G01D02*
X1556500Y333739D01*
Y334750D01*
G01X1585479Y316610D02*
X1585570D01*
G01X1587059Y326000D02*
Y321059D01*
G01X1585570Y316610D02*
Y316533D01*
X1585233D01*
X1584446Y315746D01*
X1581485D01*
X1579406Y317825D01*
Y320284D01*
X1577500Y322190D01*
Y324250D01*
G01X1532375Y405460D02*
X1530425Y403510D01*
Y402080D01*
G01X1553825Y381800D02*
X1554739Y381375D01*
X1555775Y380894D01*
G01X1553825Y388560D02*
X1554739Y388135D01*
X1555775Y387654D01*
G01X1547975Y385180D02*
X1549925Y384274D01*
G01X1547975Y391940D02*
X1549925Y391034D01*
G01X1559675Y385180D02*
X1561625Y384274D01*
G01X1559675Y391940D02*
X1561625Y391034D01*
G01X1547975Y378420D02*
X1549925Y377514D01*
G01X1536275Y378420D02*
X1538225Y377514D01*
G01X1547185Y374823D02*
X1551122D01*
G01X1555059D02*
X1551122D01*
G01X1543248D02*
X1547185D01*
G01X1558996D02*
X1555059D01*
G01X1539311D02*
X1543248D01*
G01X1535374D02*
X1539311D01*
G01X1558996Y371555D02*
Y374823D01*
G01X1562933D02*
X1558996D01*
G01X1559675Y378420D02*
X1561625Y377514D01*
G01X1562933Y374823D02*
X1566870D01*
G01X1533406Y373189D02*
X1535374Y374823D01*
G01X1533406Y373189D02*
Y369921D01*
G01X1531437Y374823D02*
X1533406Y373189D01*
G01X1527500Y374823D02*
X1531437D01*
G01X1561625Y377514D02*
X1562933Y374823D01*
G01X1549925Y377514D02*
X1551122Y374823D01*
G01X1553825Y402080D02*
X1554739Y401655D01*
X1555775Y401174D01*
G01X1559675Y398700D02*
X1560033Y398533D01*
X1561625Y397794D01*
G01X1549925D02*
X1547975Y398700D01*
G01X1553825Y395320D02*
X1554739Y394895D01*
X1555775Y394414D01*
G01X1558996Y368287D02*
Y365817D01*
G01X1542125Y395320D02*
X1544075Y394414D01*
G01X1538225Y397794D02*
X1536275Y398700D01*
G01Y391940D02*
X1538225Y391034D01*
G01X1542125Y388560D02*
X1543415Y387961D01*
X1544075Y387654D01*
G01X1542125Y381800D02*
X1543415Y381201D01*
X1544075Y380894D01*
G01X1536275Y385180D02*
X1538225Y384274D01*
G01Y377514D02*
X1539311Y374823D01*
G01X1530425Y395320D02*
X1532375Y394414D01*
G01X1530425Y388560D02*
X1532375Y387654D01*
G01X1530425Y381800D02*
X1532375Y380894D01*
G01X1569425Y402080D02*
Y404554D01*
G01X1573521Y368287D02*
Y370787D01*
X1573895Y371161D01*
G01X1573366Y393130D02*
Y397067D01*
G01X1576634D02*
X1573366D01*
G01X1565525Y395320D02*
X1566100Y395053D01*
X1567475Y394414D01*
G01X1579902Y381068D02*
X1580002Y381168D01*
X1580162D01*
X1582124Y381164D01*
G01X1565525Y388560D02*
X1566100Y388293D01*
X1567475Y387654D01*
G01X1579902Y371468D02*
X1580792D01*
X1582660Y369600D01*
X1582500D01*
G01X1576721Y368287D02*
Y363231D01*
X1576380Y362890D01*
G01X1567121Y368287D02*
Y365817D01*
G01X1579902Y374668D02*
X1580003Y374567D01*
X1582350D01*
G01X1579902Y377868D02*
X1580130Y377640D01*
X1582230D01*
X1582420Y377830D01*
G01X1573521Y365500D02*
Y368287D01*
G01X1573366Y397067D02*
Y401004D01*
G01X1570807Y371161D02*
X1570321Y370675D01*
Y368287D01*
G01X1573366Y381319D02*
X1571732Y379350D01*
G01X1566870Y374823D02*
X1567036Y374739D01*
X1568919D01*
X1569919Y375069D01*
X1570378Y375979D01*
G01X1570321Y368287D02*
Y362485D01*
X1570672Y362134D01*
G01X1579902Y393130D02*
X1576634D01*
G01D02*
X1573366D01*
G01Y389193D02*
X1573000Y391161D01*
G01X1573366Y385256D02*
Y389193D01*
G01Y401004D02*
X1571608Y401154D01*
X1571366D01*
G01X1582000Y396250D02*
X1581183Y397067D01*
X1579902D01*
G01X1571366Y401154D02*
X1573366Y404941D01*
G01X1573000Y391161D02*
X1573009Y391212D01*
X1573366Y393130D01*
G01X1567475Y380894D02*
X1565525Y381800D01*
G01X1579902Y393130D02*
X1581838Y391194D01*
X1583698D01*
G01X1590981Y386320D02*
X1590971Y386310D01*
X1588590D01*
X1588490Y386410D01*
G01D02*
X1588505D01*
G01X1583698Y391194D02*
X1583702Y391198D01*
X1588490Y386410D01*
G01X1560500Y347250D02*
Y350000D01*
G01X1543528Y349946D02*
X1544500D01*
X1545500Y348946D01*
Y347250D01*
G01X1543528Y349946D02*
X1542500Y348918D01*
Y347250D01*
G01X1570350Y344350D02*
Y342000D01*
X1570574Y341776D01*
G01X1529274Y353882D02*
X1532000Y351156D01*
Y347250D01*
G01X1573366Y432500D02*
X1569425Y431594D01*
G01X1567475Y432500D02*
X1565525Y431594D01*
G01X1567475Y459540D02*
Y457066D01*
G01X1569425Y462920D02*
X1570216Y463306D01*
X1571390Y464480D01*
G01X1551875Y414694D02*
X1553825Y415600D01*
G01X1542275Y412025D02*
X1540700Y410450D01*
G01X1539125Y440375D02*
X1540700Y441950D01*
G01D02*
X1542275Y440375D01*
G01X1563575Y432500D02*
X1561625Y431594D01*
G01X1563575Y428214D02*
X1561625Y429120D01*
G01X1543850Y435650D02*
X1542275Y437225D01*
G01X1538225Y462920D02*
X1540175Y463826D01*
G01X1542275Y449825D02*
X1540700Y451400D01*
G01D02*
X1539125Y449825D01*
G01X1538225Y456160D02*
X1540175Y457066D01*
G01X1542125Y456160D02*
X1543415Y456759D01*
X1544075Y457066D01*
G01X1529675Y449825D02*
X1531250Y451400D01*
G01X1532375Y459540D02*
X1534325Y460446D01*
G01D02*
Y456160D01*
G01X1532375Y405460D02*
X1534325Y404554D01*
G01X1547975Y405460D02*
X1546025Y404554D01*
G01X1536275Y405460D02*
X1538225Y404554D01*
G01X1540175Y405460D02*
X1540208Y405445D01*
X1542125Y404554D01*
G01D02*
X1543415Y405153D01*
X1544075Y405460D01*
G01X1538225Y404554D02*
X1540175Y405460D01*
G01X1534325Y404554D02*
X1534400Y404589D01*
X1536275Y405460D01*
G01X1532825Y421475D02*
X1534400Y419900D01*
G01X1553825Y462920D02*
X1555775Y463826D01*
G01D02*
X1557725Y462920D01*
G01X1549925D02*
X1551192Y463508D01*
X1551875Y463826D01*
G01X1546025Y462920D02*
X1547975Y463826D01*
G01X1553825Y435880D02*
X1555775Y436786D01*
G01X1561625Y435880D02*
X1559675Y436786D01*
G01D02*
X1557725Y435880D01*
G01X1553825Y442640D02*
X1555775Y443546D01*
G01X1561625Y442640D02*
X1559675Y443546D01*
G01D02*
X1557725Y442640D01*
G01X1555775Y452780D02*
X1556000Y452885D01*
X1557725Y453686D01*
G01X1549925Y456160D02*
X1551875Y457066D01*
G01X1553825Y456160D02*
X1555775Y457066D01*
G01X1559675Y459540D02*
X1561625Y460446D01*
G01X1557725Y449400D02*
Y446926D01*
G01D02*
X1556000Y446125D01*
X1555775Y446020D01*
G01X1547975D02*
X1547990Y446062D01*
X1549883Y446941D01*
X1549925Y446926D01*
G01X1546025Y456160D02*
X1547975Y457066D01*
G01X1547977Y452780D02*
X1549962Y453702D01*
X1549950D01*
X1549938Y453714D01*
G01X1561625Y456160D02*
X1563575Y457066D01*
G01Y439260D02*
X1565525Y440166D01*
G01X1555775Y436786D02*
X1557725Y435880D01*
G01X1555775Y443546D02*
X1557725Y442640D01*
G01X1561625Y431594D02*
Y429120D01*
G01X1551875Y428214D02*
Y429680D01*
G01X1555775Y425740D02*
X1551875D01*
G01X1549925Y429120D02*
X1550980Y429680D01*
X1551875D01*
G01Y428214D02*
Y425740D01*
G01X1549925Y422360D02*
X1551500Y421629D01*
X1551672Y421158D01*
G01X1551875Y418980D02*
Y420955D01*
X1551672Y421158D01*
G01X1559675Y425740D02*
X1560191Y425500D01*
X1561625Y424834D01*
G01D02*
Y422360D01*
G01X1546025Y404554D02*
X1545000Y405030D01*
X1544075Y405460D01*
G01X1559675Y414694D02*
X1561625Y415600D01*
G01X1557725D02*
X1559675Y414694D01*
G01D02*
Y412220D01*
G01X1561625Y408840D02*
X1563575Y407934D01*
G01D02*
Y405460D01*
G01X1549925Y408840D02*
X1551875Y407934D01*
G01D02*
X1553825Y408840D01*
G01X1528475Y459540D02*
X1530425Y460446D01*
G01X1529675Y421475D02*
X1531250Y419900D01*
G01X1565525Y449400D02*
X1566100Y449667D01*
X1567475Y450306D01*
G01X1579902Y456122D02*
X1582122D01*
X1582200Y456200D01*
G01X1579902Y460059D02*
X1576634D01*
G01X1578268Y454154D02*
X1575000D01*
G01X1573366Y412815D02*
Y408878D01*
G01X1569425Y418074D02*
X1573366Y416752D01*
G01X1569425Y411314D02*
X1573366Y412815D01*
G01X1575000Y438406D02*
X1578268D01*
G01X1573366Y420689D02*
Y424626D01*
G01X1567475Y457066D02*
X1569425Y456160D01*
G01X1567475Y457066D02*
X1566100Y456427D01*
X1565525Y456160D01*
G01X1575000Y438406D02*
X1573366Y440374D01*
G01Y420689D02*
X1571375Y421454D01*
G01X1573366Y432500D02*
Y436437D01*
G01Y416752D02*
X1571375Y414694D01*
G01X1579902Y412815D02*
X1576634D01*
G01D02*
X1573366D01*
G01Y408878D02*
Y404941D01*
G01Y428563D02*
Y432500D01*
G01Y424626D02*
Y428563D01*
G01Y448248D02*
Y452185D01*
G01Y444311D02*
Y448248D01*
G01Y440374D02*
Y444311D01*
G01Y436437D02*
X1575000Y438406D01*
G01X1576634Y460059D02*
X1573366D01*
G01Y456122D02*
X1575000Y454154D01*
G01X1573366Y452185D02*
X1575000Y454154D01*
G01X1567475Y459540D02*
X1569425Y460446D01*
G01Y456160D02*
X1571375Y457066D01*
G01X1573366Y420689D02*
Y416752D01*
G01X1583208Y412815D02*
X1579902D01*
G01X1571390Y464480D02*
X1571874Y463996D01*
X1573366D01*
G01X1571375Y414694D02*
X1573366Y412815D01*
G01X1569425Y404554D02*
X1567475Y405460D01*
G01X1569425Y431594D02*
X1567475Y432500D01*
G01X1565525Y431594D02*
X1563575Y432500D01*
G01X1569425Y460446D02*
X1573366Y460059D01*
G01X1571375Y457066D02*
X1573366Y456122D01*
G01X1551875Y429680D02*
Y432500D01*
G01X1551672Y421158D02*
X1551990D01*
G01X1528010Y451310D02*
X1528190D01*
G01X1549925Y449400D02*
X1551875Y450306D01*
G01X1545425Y449825D02*
X1543850Y451400D01*
G01X1545425Y452975D02*
X1543850Y454550D01*
G01Y451400D02*
X1545425Y452975D01*
G01X1551875Y439260D02*
X1553825Y440166D01*
G01X1551875Y446020D02*
X1553825Y446926D01*
G01X1542125Y408840D02*
X1542390Y408979D01*
X1543415Y409515D01*
X1544150Y409900D01*
G01X1547977Y412220D02*
X1549926Y411312D01*
G01X1543850Y445100D02*
X1545425Y443525D01*
G01X1539125Y415175D02*
X1540700Y413600D01*
G01X1538225Y408840D02*
X1538260Y408745D01*
X1540080Y407899D01*
X1540175Y407934D01*
G01X1534325Y408840D02*
X1536275Y407934D01*
G01X1532375D02*
X1530425Y408840D01*
G01X1546025D02*
X1547180Y408190D01*
G01X1547140Y410390D02*
X1545505Y412025D01*
X1545425D01*
G01X1578268Y410846D02*
X1578727Y411305D01*
X1582039D01*
X1582423Y410921D01*
X1583993D01*
X1585102Y412030D01*
Y412301D01*
X1585106Y412305D01*
Y412761D01*
X1585148Y412803D01*
Y412898D01*
X1586276Y414026D01*
X1591751D01*
X1593841Y416116D01*
X1597634D01*
X1597750Y416000D01*
G01X1529675Y452975D02*
X1528147Y454546D01*
G01X1535975Y452975D02*
X1536300Y455200D01*
G01X1553825Y449400D02*
Y453686D01*
G01D02*
X1551875Y452780D01*
G01X1537550Y445100D02*
X1539125Y443525D01*
G01X1542275Y446675D02*
X1540700Y448250D01*
G01Y445100D02*
X1542275Y443525D01*
G01X1528100Y413700D02*
X1529675Y415175D01*
G01X1547755Y423570D02*
X1546470Y424230D01*
X1545425Y424625D01*
G01X1543950Y438700D02*
Y438800D01*
G01X1530425Y456160D02*
X1528475Y457066D01*
G01X1539125Y452975D02*
X1540653Y454503D01*
Y454588D01*
G01D02*
X1542266Y452975D01*
X1542275D01*
G01X1532825D02*
X1532349Y455200D01*
G01X1547975Y418980D02*
X1548092Y418907D01*
X1548740Y418500D01*
X1548890Y417590D01*
X1548220Y416910D01*
X1547000Y416750D01*
G01X1549925Y442640D02*
X1549941Y442684D01*
X1551831Y443562D01*
X1551875Y443546D01*
G01X1555059Y490177D02*
Y488720D01*
X1553825Y487486D01*
G01X1558996Y490177D02*
X1555059D01*
G01X1553825Y487486D02*
X1551875Y486580D01*
G01X1551122Y490177D02*
X1552304Y489000D01*
X1553300Y488009D01*
X1553825Y487486D01*
G01X1549154Y491811D02*
X1551122Y490177D01*
G01X1549154Y495079D02*
Y491811D01*
G01X1562933Y490177D02*
X1558996D01*
G01X1562933Y493445D02*
X1563300Y493812D01*
Y496346D01*
X1562933Y496713D01*
G01D02*
X1564600Y498380D01*
Y500414D01*
G01X1562933Y490177D02*
Y493445D01*
G01X1564902Y491811D02*
Y490902D01*
X1564177Y490177D01*
X1562933D01*
G01X1564902Y495079D02*
Y491811D01*
G01X1547185Y493445D02*
X1547566Y493826D01*
Y496332D01*
X1547185Y496713D01*
G01D02*
X1548300Y497828D01*
Y499000D01*
G01X1546025Y480726D02*
X1544075Y479820D01*
G01X1563575D02*
X1564844Y480410D01*
X1565192Y480571D01*
X1565525Y480726D01*
G01X1547185Y490177D02*
X1548383Y489000D01*
X1549925Y487486D01*
G01X1543248Y490177D02*
X1547185D01*
G01X1549925Y487486D02*
X1547975Y486580D01*
G01X1553825Y483200D02*
X1555775Y484106D01*
G01X1553825Y476440D02*
X1555775Y477346D01*
G01Y473060D02*
X1556000Y473165D01*
X1557725Y473966D01*
G01X1553825Y469680D02*
X1555775Y470586D01*
G01X1551875Y466300D02*
X1553812Y467200D01*
X1553825Y467206D01*
G01X1551875Y473060D02*
X1553825Y473966D01*
G01X1546025Y469680D02*
X1547975Y470586D01*
G01Y473060D02*
X1549925Y473966D01*
G01X1555775Y479820D02*
X1556000Y479925D01*
X1557725Y480726D01*
G01X1551875Y479820D02*
X1553825Y480726D01*
G01X1544075Y466300D02*
X1546012Y467200D01*
X1546025Y467206D01*
G01X1536275Y473060D02*
X1538225Y473966D01*
G01X1542125Y476440D02*
X1544075Y477346D01*
G01X1534325Y469680D02*
X1536275Y470586D01*
G01X1538225Y476440D02*
X1540175Y477346D01*
G01Y473060D02*
X1542125Y473966D01*
G01Y469680D02*
X1544075Y470586D01*
G01X1534325Y483200D02*
X1536275Y484106D01*
G01X1531437Y490177D02*
X1532701Y489000D01*
X1534325Y487486D01*
G01X1539311Y490177D02*
X1535374D01*
G01X1534325Y487486D02*
X1534915Y489000D01*
X1535374Y490177D01*
G01X1532375Y486580D02*
X1534325Y487486D01*
G01X1535374Y493445D02*
X1535000Y493819D01*
Y496339D01*
X1535374Y496713D01*
G01D02*
Y496785D01*
X1534180Y497979D01*
Y498580D01*
G01X1528475Y473060D02*
X1530425Y473966D01*
G01Y469680D02*
X1532375Y470586D01*
G01X1527500Y493445D02*
Y490177D01*
G01X1567475Y473060D02*
X1569425Y473966D01*
G01Y469680D02*
X1571375Y470586D01*
G01X1570321Y496713D02*
X1570486Y496878D01*
Y498294D01*
X1569045Y499735D01*
X1567817D01*
G01X1571732Y485650D02*
X1571692Y485884D01*
X1570062Y487039D01*
G01X1572327Y490970D02*
X1569680D01*
X1568839Y491811D01*
G01X1579902Y490332D02*
Y490791D01*
X1580192Y491086D01*
Y493242D01*
X1579902Y493532D01*
G01X1576702Y493513D02*
X1577150Y493961D01*
Y496284D01*
X1576721Y496713D01*
G01D02*
X1576644Y496790D01*
X1573598D01*
X1573521Y496713D01*
G01X1579902Y493532D02*
X1582644Y495077D01*
G01X1573895Y493839D02*
X1570807D01*
G01X1568839Y491811D02*
Y494261D01*
X1568600Y494500D01*
G01X1579902Y487132D02*
X1583478Y490708D01*
X1587033D01*
X1587433Y490308D01*
G01X1579902Y483932D02*
X1583233D01*
X1587433Y488132D01*
Y490308D01*
G01X1570062Y487039D02*
X1569603Y486580D01*
X1567475D01*
G01X1567817Y499735D02*
Y497409D01*
X1567121Y496713D01*
G01X1568600Y494500D02*
X1570146D01*
X1570807Y493839D01*
G01X1582644Y495077D02*
X1581008Y496713D01*
X1576721D01*
G01X1565525Y469680D02*
X1566100Y469947D01*
X1567475Y470586D01*
G01X1571375D02*
X1572947Y468491D01*
X1573366Y467933D01*
G01X1587433Y490308D02*
Y490425D01*
G01X1549925Y469680D02*
X1551875Y470586D01*
G01X1547975Y466300D02*
X1549912Y467200D01*
X1549925Y467206D01*
G01X1568600Y507530D02*
Y503500D01*
X1568400Y503300D01*
G01X1563800Y574300D02*
Y579022D01*
G01D02*
X1568212Y583434D01*
Y587331D01*
G01X1587610Y582396D02*
Y579550D01*
G01X1534967Y616500D02*
X1537820D01*
X1538679Y615641D01*
G01X1538337Y601097D02*
Y600887D01*
X1538060Y600610D01*
Y598459D01*
G01X1537711Y613397D02*
Y611789D01*
X1539000Y610500D01*
G01X1573500Y613500D02*
X1577000D01*
G01X1582347Y612754D02*
X1581601Y613500D01*
X1577000D01*
G01X1541211Y604235D02*
Y601435D01*
X1541384Y601262D01*
G01X1543544Y604034D02*
X1543343Y604235D01*
X1541211D01*
G01X1541384Y601262D02*
X1541560Y601086D01*
Y598459D01*
G01X1542500Y595419D02*
X1539000D01*
G01X1534968Y597268D02*
X1536817Y595419D01*
X1539000D01*
G01X1577000Y610560D02*
X1579399D01*
X1579680Y610279D01*
G01X1573520Y610590D02*
X1576970D01*
X1577000Y610560D01*
G01X1617609Y17268D02*
Y14609D01*
X1615000Y12000D01*
G01X1627059Y17268D02*
Y12141D01*
X1627500Y11700D01*
G01X1620759Y30668D02*
Y34841D01*
X1620050Y35550D01*
G01X1630209Y30668D02*
Y37609D01*
X1630121D01*
G01X1608159Y17268D02*
Y13338D01*
X1608123Y13302D01*
G01X1611309Y30668D02*
Y36441D01*
X1610450Y37300D01*
G01X1601859Y30668D02*
Y36259D01*
X1602800Y37200D01*
Y37382D01*
X1602840D01*
G01X1598709Y17268D02*
Y10509D01*
X1597700Y9500D01*
Y9000D01*
G01X1639659Y30668D02*
Y38064D01*
X1639623Y38100D01*
G01X1645959Y17268D02*
Y13841D01*
X1646400Y13400D01*
G01X1634200Y9700D02*
X1636509Y12009D01*
Y17268D01*
G01X1649109Y30668D02*
Y38164D01*
X1649073Y38200D01*
G01X1592409Y30668D02*
Y37491D01*
X1592200Y37700D01*
G01X1589259Y17268D02*
Y10241D01*
G01X1592453Y8502D02*
Y5502D01*
G01X1625500Y86750D02*
X1628250D01*
X1628500Y86500D01*
G01X1621949Y83888D02*
X1622349Y84288D01*
X1625451D01*
G01X1608500Y72688D02*
X1606562D01*
X1605000Y74250D01*
Y76250D01*
G01X1625451Y84288D02*
X1625849Y84686D01*
Y86401D01*
X1625500Y86750D01*
G01X1589500Y87000D02*
Y84822D01*
X1589900Y84422D01*
G01X1632000Y64500D02*
X1634800D01*
X1637700Y67400D01*
G01X1632000Y64500D02*
Y69910D01*
X1629410Y72500D01*
X1627500D01*
G01X1615316Y104467D02*
Y101017D01*
X1610821Y96522D01*
Y82519D01*
X1611630Y81710D01*
Y79134D01*
G01X1602350Y72090D02*
Y78130D01*
X1603970Y79750D01*
X1605000D01*
G01X1611630Y79134D02*
X1609173D01*
X1608557Y79750D01*
X1605000D01*
G01X1599500Y84500D02*
Y83550D01*
X1598500Y82550D01*
X1594150D01*
X1592500Y84200D01*
Y87000D01*
G01X1605250Y90500D02*
Y88750D01*
X1606472Y87528D01*
Y86833D01*
X1606579Y86726D01*
G01X1598849Y87288D02*
X1599500Y86637D01*
Y84500D01*
G01X1612000Y70984D02*
Y71000D01*
X1611630Y71370D01*
Y74134D01*
G01X1621949Y87388D02*
Y90188D01*
X1621599Y90538D01*
G01X1624200Y96700D02*
Y93825D01*
X1621599Y91224D01*
Y90538D01*
G01X1618449Y87388D02*
Y90188D01*
X1618099Y90538D01*
G01X1620827Y95153D02*
Y94006D01*
X1618099Y91278D01*
Y90538D01*
G01X1620733Y74847D02*
X1617614D01*
X1614847Y77614D01*
Y80511D01*
X1612221Y83137D01*
Y95442D01*
X1612245Y95466D01*
G01X1624000Y72500D02*
Y67485D01*
X1622999Y66484D01*
X1621375D01*
G01D02*
X1620275D01*
X1619093Y67666D01*
Y71101D01*
X1620733Y72741D01*
Y74847D01*
G01X1651536Y121790D02*
X1649961Y120215D01*
G01X1651536Y121790D02*
X1649961Y123365D01*
G01X1637363Y113916D02*
Y113844D01*
X1638902Y112305D01*
G01X1637363Y117066D02*
Y113916D01*
G01Y120215D02*
X1637364D01*
X1638938Y118641D01*
G01X1637363Y123365D02*
Y120215D01*
G01X1638902Y112305D02*
X1637363Y110766D01*
G01Y151711D02*
X1638938Y153286D01*
G01D02*
X1637363Y154861D01*
G01X1618465Y151711D02*
X1616976Y153200D01*
X1616900D01*
G01X1621615Y120215D02*
Y120214D01*
X1623189Y118640D01*
G01D02*
X1624764Y120215D01*
G01X1602717Y102240D02*
Y104467D01*
G01X1615316Y117066D02*
X1613741Y115491D01*
G01X1615316Y126514D02*
X1616891Y124939D01*
G01X1609016Y120215D02*
X1607441Y118640D01*
G01X1627914Y117066D02*
X1627915D01*
X1629489Y118640D01*
G01X1618465Y107617D02*
X1620040Y106042D01*
G01X1621615Y110766D02*
Y107617D01*
G01X1620040Y106042D02*
X1621615Y107617D01*
G01X1629489Y131239D02*
X1631064Y132814D01*
G01X1627914Y129664D02*
X1629489Y131239D01*
G01D02*
X1627914Y132814D01*
G01X1631064Y129664D02*
X1629489Y131239D01*
G01X1627914Y145412D02*
X1629489Y143837D01*
G01D02*
X1631064Y142262D01*
G01X1627914D02*
X1629489Y143837D01*
G01X1631064Y145412D02*
X1629489Y143837D01*
G01X1627914Y139113D02*
X1629489Y137538D01*
G01D02*
X1631064Y135963D01*
G01Y139113D02*
X1629489Y137538D01*
G01X1627914Y135963D02*
X1629489Y137538D01*
G01X1635788Y131239D02*
X1637363Y129664D01*
G01X1635788Y131239D02*
X1637363Y132814D01*
G01X1634213Y129664D02*
X1635788Y131239D01*
G01D02*
X1634213Y132814D01*
G01X1635788Y143837D02*
X1637363Y142262D01*
G01X1635788Y143837D02*
X1637363Y145412D01*
G01X1634213Y142262D02*
X1635788Y143837D01*
G01D02*
X1634213Y145412D01*
G01X1635788Y137538D02*
X1637363Y139113D01*
G01X1635788Y137538D02*
X1637363Y135963D01*
G01X1634213Y139113D02*
X1635788Y137538D01*
G01D02*
X1634213Y135963D01*
G01X1631064Y151711D02*
X1629489Y150136D01*
G01X1640512Y139113D02*
X1638937Y137538D01*
G01D02*
X1640512Y135963D01*
G01Y145412D02*
X1638937Y143837D01*
G01D02*
X1640512Y142262D01*
G01Y129664D02*
X1638937Y131239D01*
G01D02*
X1640512Y132814D01*
G01X1648430Y150163D02*
Y150180D01*
X1649961Y151711D01*
G01X1638938Y118641D02*
X1637363Y117066D01*
G01Y107617D02*
X1638938Y109192D01*
G01X1637363Y104467D02*
Y107617D01*
G01X1631064Y113916D02*
X1629489Y115491D01*
G01X1618465Y113916D02*
X1616890Y112341D01*
G01X1618465Y132814D02*
X1618466D01*
X1620040Y134388D01*
G01D02*
X1618465Y135963D01*
G01Y126514D02*
X1618892Y126087D01*
Y123792D01*
X1618465Y123365D01*
G01X1620040Y128089D02*
X1618465Y126514D01*
G01X1631064Y154861D02*
X1629489Y153286D01*
G01D02*
X1627914Y154861D01*
G01X1615316Y107617D02*
X1613741Y106042D01*
G01X1624200Y96700D02*
Y97801D01*
X1624764Y98365D01*
Y104467D01*
G01X1624200Y96700D02*
X1624188D01*
G01X1621700Y99200D02*
X1620827Y98327D01*
Y95153D01*
G01X1649961Y129664D02*
X1651536Y128089D01*
G01X1621615Y123365D02*
X1618465Y120215D01*
G01X1634213Y154861D02*
X1635788Y153286D01*
G01X1649961Y132814D02*
X1651536Y134388D01*
G01X1649961Y132814D02*
X1651536Y131239D01*
G01X1649961Y126514D02*
X1651536Y124939D01*
G01X1649961Y139113D02*
X1651536Y140687D01*
G01Y143837D02*
X1649961Y145412D01*
G01D02*
X1648173Y143624D01*
Y142265D01*
G01D02*
Y139113D01*
G01X1649961Y142262D02*
X1649958Y142265D01*
X1648173D01*
G01Y139113D02*
Y132816D01*
G01X1649961Y139113D02*
X1648173D01*
G01Y132816D02*
Y128302D01*
X1649961Y126514D01*
G01Y132814D02*
X1648175D01*
X1648173Y132816D01*
G01X1627914Y120215D02*
X1626364Y121765D01*
G01X1634213Y120215D02*
X1635788Y118640D01*
G01D02*
X1634214Y117066D01*
X1634213D01*
G01X1631064Y120215D02*
X1632639Y118640D01*
G01D02*
X1631065Y117066D01*
X1631064D01*
G01X1643662Y120215D02*
X1645237Y118640D01*
G01D02*
X1646812Y120215D01*
G01X1642087Y153286D02*
X1640512Y154861D01*
G01X1643662D02*
X1642087Y153286D01*
G01X1634213Y151711D02*
X1632638Y153286D01*
G01X1618465Y148562D02*
X1620040Y146987D01*
G01D02*
X1618465Y145412D01*
G01Y142262D02*
X1620040Y140687D01*
G01D02*
X1618466Y139113D01*
X1618465D01*
G01X1631064Y123365D02*
X1632639Y124940D01*
G01X1640512Y120215D02*
X1640595D01*
X1642150Y118660D01*
G01X1643662Y120215D02*
Y120172D01*
X1642150Y118660D01*
G01X1626339Y124940D02*
X1624764Y123365D01*
G01X1627914D02*
X1626339Y124940D01*
G01X1609016Y123365D02*
X1607441Y121790D01*
G01X1650300Y195251D02*
Y194737D01*
X1650852Y194185D01*
Y192729D01*
G01X1639811Y191803D02*
X1636811D01*
G01X1648400Y214100D02*
X1650250Y215950D01*
Y217650D01*
G01X1645000Y217850D02*
Y217500D01*
X1646500Y216000D01*
X1646508D01*
X1647650Y214858D01*
Y214850D01*
X1648400Y214100D01*
G01X1639378Y207633D02*
X1641867D01*
X1642700Y206800D01*
Y203400D01*
X1643585Y202515D01*
X1646378D01*
G01X1652485Y207858D02*
Y205749D01*
X1649251Y202515D01*
X1646378D01*
G01X1648400Y214100D02*
Y213992D01*
X1644576Y210168D01*
X1640159D01*
X1639378Y209387D01*
Y207633D01*
G01X1627914Y170609D02*
Y167459D01*
G01Y170609D02*
X1627998Y170693D01*
Y172854D01*
G01X1621615Y161160D02*
X1620040Y162735D01*
G01X1604401Y213500D02*
X1605487D01*
X1610955Y218968D01*
X1613632D01*
X1615600Y217000D01*
X1620800D01*
G01X1636811Y191803D02*
X1636725D01*
X1636839Y191917D01*
Y193333D01*
X1635720Y194452D01*
Y194573D01*
X1635112Y195181D01*
G01X1640000Y217000D02*
Y219600D01*
X1641750Y221350D01*
X1645000D01*
G01X1645700Y214050D02*
X1644750Y215000D01*
X1641000D01*
X1640000Y216000D01*
Y217000D01*
G01X1599200Y202000D02*
X1604216D01*
X1608099Y198117D01*
Y197125D01*
G01D02*
X1608224Y197000D01*
X1610750D01*
G01X1637870Y197577D02*
Y199629D01*
X1636199Y201300D01*
X1634350D01*
G01X1616286Y176515D02*
Y180694D01*
X1615440Y181540D01*
G01X1592450Y175960D02*
Y174776D01*
X1595042Y172184D01*
G01X1591174Y227582D02*
Y225017D01*
G01X1608489Y252095D02*
X1608084Y252500D01*
X1605650D01*
G01X1608280Y249234D02*
X1607915Y249599D01*
X1606500D01*
X1606401Y249500D01*
X1605650D01*
G01X1645400Y224850D02*
X1645717Y224533D01*
Y223117D01*
X1645000Y222400D01*
Y221350D01*
G01X1627177Y260267D02*
X1627483Y259961D01*
X1632112D01*
G01X1649500Y323941D02*
X1652991D01*
G01X1592110Y322002D02*
X1591500Y322612D01*
Y325750D01*
G01X1652991Y321341D02*
X1646000D01*
G01X1641000Y325000D02*
Y323748D01*
X1643407Y321341D01*
X1646000D01*
G01D02*
Y314801D01*
X1647360Y313441D01*
X1649500D01*
G01X1620000Y349250D02*
Y352730D01*
X1619889Y352841D01*
G01X1601060Y401010D02*
X1600070Y402000D01*
X1598250D01*
G01X1622100Y400600D02*
X1623500D01*
X1624200Y401300D01*
Y403500D01*
G01X1601250Y416000D02*
X1603119D01*
X1603650Y415469D01*
G01X1634500Y418500D02*
X1634745Y418255D01*
X1643301D01*
G01X1603650Y415469D02*
X1604181Y416000D01*
X1606250D01*
G01X1652050Y413500D02*
X1649600D01*
X1648345Y414755D01*
X1643301D01*
G01X1651750Y445000D02*
Y446850D01*
X1649800Y448800D01*
G01X1623750Y432000D02*
Y435500D01*
G01X1609250D02*
Y432500D01*
G01D02*
X1612250D01*
G01X1623750Y432000D02*
X1622140D01*
X1621120Y433020D01*
Y433288D01*
X1621044Y433364D01*
G01X1618250Y426000D02*
X1620091D01*
X1621182Y427091D01*
G01X1621347Y415297D02*
X1618953D01*
X1618750Y415500D01*
G01X1608949Y422971D02*
X1611418D01*
G01X1618250Y435500D02*
Y432500D01*
G01X1606250Y412000D02*
Y410441D01*
X1606500Y410191D01*
Y408750D01*
G01X1646480Y443880D02*
X1647600Y445000D01*
X1651750D01*
G01X1612100Y446000D02*
X1609250D01*
G01X1611638Y454809D02*
X1609169D01*
G01X1603719Y412000D02*
X1606250D01*
G01X1621182Y427091D02*
X1619273Y429000D01*
X1618250D01*
G01X1621044Y433364D02*
X1620180Y432500D01*
X1618250D01*
G01X1627250Y446500D02*
X1629719D01*
X1630219Y446000D01*
G01X1627250Y443500D02*
X1629139D01*
X1630219Y444580D01*
Y446000D01*
G01X1603719Y412000D02*
X1601300D01*
G01X1633200Y445800D02*
X1630419D01*
X1630219Y446000D01*
G01X1632200Y441900D02*
Y443200D01*
X1633200Y444200D01*
Y445800D01*
G01X1618250Y439500D02*
X1620000D01*
X1621000Y440500D01*
G01X1618250Y442500D02*
Y439500D01*
G01X1623800D02*
X1622000D01*
X1621000Y440500D01*
G01X1618800Y453400D02*
X1619900Y454500D01*
X1622963D01*
X1623800Y453663D01*
G01X1627800Y467600D02*
X1627614D01*
X1623814Y471400D01*
G01X1634611Y479293D02*
X1631285D01*
X1626992Y475000D01*
X1620500D01*
G01X1629530Y496374D02*
X1630863Y495041D01*
X1634611D01*
G01X1619861Y521918D02*
Y518918D01*
G01X1634611Y483230D02*
X1625470D01*
X1624300Y484400D01*
Y489113D01*
X1628000Y492813D01*
Y495146D01*
X1627580Y495566D01*
Y495983D01*
X1627571Y495992D01*
Y507845D01*
X1628061Y508335D01*
Y508366D01*
X1629533Y509838D01*
Y514368D01*
X1628401Y515500D01*
X1621199D01*
X1619861Y516838D01*
Y518918D01*
G01X1634611Y483230D02*
X1640220D01*
X1643366Y486376D01*
Y489561D01*
X1642880Y490047D01*
G01X1631538Y534000D02*
X1628038D01*
G01X1631538D02*
X1632907D01*
X1633907Y533000D01*
Y530441D01*
X1634908Y529440D01*
X1637460D01*
X1637500Y529400D01*
G01X1658559Y30668D02*
Y37890D01*
G01X1664859Y17268D02*
Y13323D01*
X1664823Y13287D01*
G01X1674309Y17268D02*
Y11582D01*
X1672427Y9700D01*
G01X1711863Y13276D02*
X1712109Y13522D01*
Y17268D01*
G01X1702421Y13231D02*
X1702400Y13252D01*
Y14200D01*
X1702659Y14459D01*
Y17268D01*
G01X1696359Y30668D02*
Y37824D01*
X1696795Y38260D01*
G01X1691541Y13226D02*
X1691857D01*
X1692764Y14133D01*
Y14867D01*
X1693209Y15312D01*
Y17268D01*
G01X1683759D02*
Y14615D01*
X1684902Y13472D01*
G01X1686909Y30668D02*
Y36409D01*
X1687500Y37000D01*
G01X1677459Y30668D02*
Y36459D01*
X1678000Y37000D01*
G01X1705809Y30668D02*
Y36309D01*
X1706500Y37000D01*
G01X1668009Y30668D02*
Y37000D01*
G01X1654800Y13518D02*
Y14100D01*
X1655409Y14709D01*
Y17268D01*
G01X1705000Y56000D02*
Y54911D01*
X1706336Y53575D01*
X1711808D01*
X1713550Y55317D01*
Y56000D01*
G01X1682160Y68600D02*
X1670712D01*
X1669350Y69962D01*
G01X1705250Y48400D02*
X1707000D01*
X1709600Y45800D01*
G01X1704900Y69768D02*
Y72968D01*
G01D02*
X1701034D01*
X1700710Y73292D01*
G01X1702513Y79885D02*
X1699941Y82457D01*
Y84668D01*
G01X1700300Y94703D02*
X1700000Y95003D01*
Y102000D01*
G01X1689155Y77991D02*
Y78545D01*
X1685200Y82500D01*
X1683500D01*
G01X1682500Y90000D02*
Y86500D01*
X1683500Y85500D01*
Y82500D01*
G01X1692300Y56900D02*
X1694956D01*
X1699781Y52075D01*
X1712430D01*
X1716900Y56545D01*
Y59400D01*
X1718000Y60500D01*
X1719750D01*
G01X1708400Y72968D02*
Y76536D01*
X1707268Y77668D01*
G01X1711700Y58500D02*
X1711000Y57800D01*
Y55525D01*
G01X1708000Y56000D02*
X1710525D01*
X1711000Y55525D01*
G01X1667916Y54616D02*
X1667000Y53700D01*
Y51500D01*
G01X1700080Y46400D02*
X1701900D01*
X1703400Y44900D01*
X1705250D01*
G01X1663000Y81600D02*
Y83600D01*
X1663700Y84300D01*
G01X1705250Y44900D02*
X1707100D01*
X1708400Y43600D01*
X1711100D01*
X1712600Y45100D01*
Y46100D01*
G01X1707268Y77668D02*
X1705059D01*
G01X1708400Y63200D02*
Y72968D01*
G01X1653111Y120215D02*
X1651536Y121790D01*
G01X1665709Y142262D02*
X1665708D01*
X1664134Y140688D01*
G01X1665709Y148562D02*
X1665710D01*
X1667284Y150136D01*
G01X1665709Y129664D02*
X1667284Y128089D01*
G01X1665709Y123365D02*
X1667284Y121790D01*
G01X1656260Y151711D02*
X1657835Y150136D01*
G01X1665709Y135963D02*
X1665710D01*
X1667284Y137537D01*
G01X1709000Y127200D02*
X1707750Y128450D01*
X1706100D01*
G01X1671000Y103000D02*
X1669859D01*
X1668859Y104000D01*
Y104467D01*
G01X1653111Y135963D02*
X1654678Y137530D01*
G01X1656260Y139113D02*
Y139112D01*
X1654678Y137530D01*
G01X1656260Y145412D02*
X1654685Y146987D01*
G01X1687520Y142025D02*
X1690207D01*
X1691207Y141025D01*
Y139891D01*
G01X1656260Y154861D02*
X1657835Y156436D01*
G01X1662560Y154861D02*
X1661956D01*
X1661693Y154598D01*
X1660277D01*
X1660014Y154861D01*
X1659410D01*
G01X1662560D02*
Y154862D01*
X1664134Y156436D01*
G01X1703242Y198749D02*
Y196569D01*
X1709622Y190189D01*
X1714528D01*
G01X1687950Y186150D02*
X1690582Y183518D01*
X1692312D01*
G01X1668859Y170609D02*
Y171962D01*
X1668213Y172608D01*
G01X1710650Y166200D02*
X1709500D01*
X1708250Y164950D01*
G01X1667349Y192788D02*
X1664349D01*
G01X1664321Y195244D02*
X1666349D01*
X1667349Y194244D01*
Y192788D01*
G01X1659949D02*
Y193431D01*
X1658082Y195298D01*
G01X1653949Y192788D02*
X1656949D01*
G01X1658082Y195298D02*
X1656949Y194165D01*
Y192788D01*
G01X1655978Y207827D02*
X1655505Y208300D01*
Y212022D01*
X1654819Y212708D01*
G01X1703350Y177850D02*
Y186150D01*
X1702500Y187000D01*
G01X1674066Y196666D02*
Y193934D01*
X1675212Y192788D01*
X1676849D01*
G01X1656500Y318559D02*
X1653173D01*
X1652991Y318741D01*
G01X1668000Y416200D02*
X1662660D01*
X1659840Y419020D01*
Y421320D01*
G01X1662550Y413500D02*
X1663500D01*
X1666900Y410100D01*
X1668550D01*
X1670518Y412068D01*
Y419488D01*
X1668706Y421300D01*
G01X1652160Y421320D02*
Y424500D01*
X1653160Y425500D01*
X1662850D01*
X1667050Y421300D01*
X1668706D01*
G01X1652050Y413500D02*
X1652160Y413610D01*
Y421320D01*
G01X1668706Y421300D02*
X1670300Y422894D01*
Y434911D01*
X1675120Y439731D01*
G01X1661000Y462550D02*
X1662571D01*
X1665093Y465072D01*
X1665762D01*
X1666997Y466307D01*
Y466594D01*
X1667674Y467271D01*
G01X1661000Y462550D02*
X1657500D01*
G01X1668843Y465060D02*
X1668770D01*
Y464034D01*
X1666350Y461614D01*
Y450993D01*
X1662250Y446893D01*
Y445000D01*
G01X1652160Y437500D02*
Y444590D01*
X1651750Y445000D01*
G01X1724200Y506600D02*
X1722000Y504400D01*
X1712990D01*
X1710594Y506796D01*
Y508850D01*
G01Y516950D02*
Y519900D01*
G01X1687606Y500938D02*
X1687294Y501250D01*
X1679250D01*
G01X1681650Y510673D02*
X1681323Y511000D01*
X1679250D01*
G01X1690000Y514750D02*
X1688750D01*
X1682784Y520716D01*
Y523549D01*
X1681115Y525218D01*
G01X1716490Y506970D02*
X1715930Y506410D01*
X1713530D01*
X1712562Y507378D01*
Y508850D01*
G01X1740459Y17268D02*
Y20659D01*
X1741000Y21200D01*
G01X1743500Y39300D02*
X1743900Y38900D01*
Y33300D01*
X1743609Y33009D01*
Y30668D01*
G01X1749941Y21163D02*
X1749909D01*
Y17268D01*
G01X1724758Y38600D02*
Y30717D01*
X1724709Y30668D01*
G01X1721559Y17268D02*
Y13500D01*
G01X1768807Y17268D02*
Y21512D01*
G01X1753059Y30668D02*
Y35300D01*
G01X1733910Y38233D02*
Y35933D01*
X1734159Y35684D01*
Y30668D01*
G01X1731009Y17268D02*
Y13554D01*
X1730768Y13313D01*
G01X1715259Y35602D02*
Y30668D01*
G01X1768807Y21512D02*
X1769927D01*
X1771957Y23542D01*
Y30668D01*
G01X1741544Y9151D02*
Y6634D01*
X1738143Y3233D01*
X1719663D01*
G01X1752908Y9481D02*
X1752750Y9323D01*
Y4500D01*
G01X1748750D02*
X1752750D01*
G01X1714850Y74278D02*
X1715822D01*
X1717350Y72750D01*
X1718500D01*
G01X1771459Y52695D02*
X1769764Y51000D01*
X1763118D01*
G01X1754703Y84053D02*
X1752901Y85855D01*
Y91701D01*
X1754070Y92870D01*
X1755580D01*
G01X1769000Y83500D02*
X1766100D01*
X1765900Y83700D01*
G01X1765500Y76250D02*
X1767324D01*
X1768450Y77376D01*
G01X1719450Y86600D02*
X1718200D01*
X1716900Y87900D01*
G01X1758780Y92870D02*
X1755580D01*
G01X1720600Y70200D02*
X1719800D01*
X1718500Y71500D01*
Y72750D01*
G01X1714700Y58500D02*
Y57150D01*
X1713550Y56000D01*
G01X1766240Y70500D02*
X1765053Y71687D01*
X1757190D01*
X1753300Y75577D01*
Y79899D01*
X1754301Y80900D01*
X1757714D01*
X1760364Y83550D01*
Y85136D01*
G01X1741594Y55606D02*
X1739306D01*
X1734700Y51000D01*
X1729500D01*
G01X1746328Y59011D02*
X1742611D01*
X1741594Y57994D01*
Y55606D01*
G01X1719750Y60500D02*
Y63500D01*
G01X1713900Y87900D02*
Y87724D01*
X1714502Y87122D01*
Y85298D01*
X1716550Y83250D01*
X1718500D01*
G01X1759000Y63000D02*
Y62500D01*
X1758000Y61500D01*
Y58000D01*
G01X1759000Y63000D02*
Y64758D01*
X1760016Y65774D01*
G01X1776900Y86550D02*
Y84600D01*
X1775800Y83500D01*
X1772500D01*
G01X1776900Y86550D02*
X1775314D01*
X1771646Y90218D01*
G01X1761350Y158650D02*
X1758650D01*
G01X1714530Y516950D02*
Y519900D01*
G01X1730814Y571564D02*
Y568814D01*
G01X1749971Y571695D02*
X1748305D01*
X1746000Y574000D01*
G01X1773471Y571695D02*
X1767455D01*
G01X1715461Y587223D02*
X1717500D01*
X1718000Y587723D01*
G01X1746000Y574000D02*
X1745250Y574750D01*
Y577100D01*
G01X1749971Y564015D02*
X1756242D01*
X1756417Y563840D01*
G01X1741314Y581186D02*
Y584463D01*
X1742381Y585530D01*
G01X1742200Y552863D02*
Y553703D01*
X1744832Y556335D01*
X1749971D01*
G01X1733000Y557000D02*
X1733001D01*
X1735500Y559499D01*
Y563000D01*
G01X1756578Y586743D02*
Y584492D01*
X1753836Y581750D01*
X1748800D01*
G01X1748750Y577100D02*
Y579500D01*
X1748800Y579550D01*
Y581750D01*
G01X1735500Y563000D02*
Y566000D01*
G01X1732500Y554000D02*
Y556500D01*
X1733000Y557000D01*
G01X1724899Y584748D02*
X1727190Y587039D01*
Y588640D01*
G01X1737814Y581186D02*
Y584814D01*
X1739500Y586500D01*
G01X1737814Y576682D02*
Y581186D01*
G01X1779000Y598900D02*
X1778400D01*
X1776610Y597110D01*
X1772300D01*
G01X1748800Y589430D02*
X1744481D01*
X1742381Y591530D01*
G01X1733096Y600844D02*
Y597795D01*
X1732443Y597142D01*
G01X1742509Y595869D02*
X1743750Y597110D01*
X1748800D01*
G01X1724041Y592773D02*
X1723983Y592715D01*
X1718721D01*
X1718008Y592002D01*
G01X1724041Y598679D02*
X1721239D01*
X1720784Y599134D01*
X1716399D01*
X1715399Y598134D01*
Y594143D01*
X1717511Y592031D01*
X1717979D01*
X1718008Y592002D01*
G01X1736245Y596711D02*
X1739211D01*
G01X1828500Y1000D02*
Y3375D01*
X1828824Y3699D01*
G01X1804508Y11858D02*
X1806607Y13957D01*
Y17268D01*
G01X1781407Y30668D02*
Y27796D01*
X1782371Y26832D01*
G01X1816693Y13331D02*
X1816057Y13967D01*
Y17268D01*
G01X1808444Y37152D02*
Y36156D01*
X1809757Y34843D01*
Y30668D01*
G01X1800307D02*
Y34102D01*
X1799774Y34635D01*
Y34890D01*
G01X1797157Y17268D02*
Y13245D01*
X1798676Y11726D01*
G01X1790857Y30668D02*
Y34743D01*
X1790700Y34900D01*
G01X1819207Y30668D02*
Y34907D01*
X1819800Y35500D01*
G01X1782371Y26832D02*
X1778257Y22718D01*
Y17268D01*
G01X1815500Y6000D02*
Y3458D01*
X1815863Y3095D01*
Y3036D01*
X1819699Y-800D01*
X1822335D01*
X1824043Y-2508D01*
Y-13521D01*
X1826822Y-16300D01*
X1831000D01*
G01X1829636Y26680D02*
X1828657Y27659D01*
Y30668D01*
G01X1811500Y6000D02*
X1815500D01*
G01X1831000Y-16300D02*
X1831600Y-15700D01*
X1833600D01*
G01X1792196Y6061D02*
X1789421D01*
X1788421Y7061D01*
Y8122D01*
G01X1837800Y-3600D02*
X1836874D01*
X1835874Y-4600D01*
Y-5980D01*
G01X1828874D02*
Y-4280D01*
X1832000Y-1154D01*
Y1000D01*
G01D02*
X1833200D01*
X1833400Y800D01*
X1835500D01*
G01D02*
Y-1700D01*
G01X1824350Y88150D02*
X1825850D01*
X1827000Y87000D01*
G01D02*
X1827500Y87500D01*
X1829500D01*
G01X1829550Y94550D02*
X1827000D01*
G01X1782548Y87031D02*
X1779349D01*
X1778868Y86550D01*
X1776900D01*
G01X1792935Y136789D02*
Y134100D01*
X1794408Y132627D01*
X1800000D01*
G01D02*
Y130059D01*
G01X1798055Y143789D02*
X1800264D01*
G01X1811348Y145937D02*
Y143448D01*
G01X1803848Y151937D02*
X1801366D01*
G01X1795950Y108000D02*
Y104791D01*
X1796059Y104682D01*
Y104402D01*
G01X1801070Y115000D02*
X1802400D01*
X1803400Y114000D01*
G01X1787500Y152500D02*
Y155170D01*
G01X1821587Y100524D02*
X1825029D01*
X1829061Y104556D01*
X1833047D01*
G01X1793750Y120000D02*
Y121446D01*
X1793000Y122196D01*
Y124941D01*
G01X1799250Y120000D02*
X1796500D01*
G01D02*
X1793750D01*
G01X1787500Y152500D02*
X1788200D01*
X1788700Y152000D01*
X1788708D01*
X1788916Y151792D01*
X1791584D01*
X1792292Y152500D01*
X1793000D01*
G01X1803058Y143733D02*
Y143351D01*
X1802485Y142778D01*
Y140039D01*
G01X1833023Y101490D02*
X1830989D01*
X1830316Y102163D01*
G01X1824350Y97950D02*
X1827000D01*
X1827150Y97800D01*
G01D02*
X1827200Y97850D01*
X1829550D01*
G01X1824152Y155563D02*
X1826407D01*
X1828960Y153010D01*
G01X1822848Y149437D02*
X1823937D01*
X1826605Y152105D01*
X1828055D01*
X1828960Y153010D01*
G01X1806598Y155437D02*
X1807348Y154687D01*
Y151937D01*
G01X1812848Y157531D02*
X1811451D01*
X1809810Y155890D01*
G01Y155858D02*
Y155890D01*
G01D02*
X1809357Y155437D01*
X1806598D01*
G01X1784750Y126500D02*
Y124000D01*
G01X1828936Y249900D02*
Y244106D01*
X1828937Y244105D01*
G01X1835000Y586250D02*
X1833592D01*
X1832155Y584813D01*
Y583007D01*
X1830722Y581574D01*
X1822757D01*
G01X1800206Y569763D02*
X1794963D01*
X1794000Y568800D01*
G01X1801200Y529800D02*
X1800207Y530793D01*
Y534330D01*
G01Y552047D02*
X1807600D01*
G01X1822758Y540236D02*
X1828684D01*
X1828700Y540252D01*
G01X1822758Y546141D02*
X1828441D01*
X1828800Y546500D01*
G01X1822758Y552047D02*
X1828647D01*
X1828900Y552300D01*
G01X1828875Y563674D02*
X1828691Y563858D01*
X1822757D01*
G01X1828824Y557663D02*
X1828535Y557952D01*
X1822758D01*
G01X1800206Y581574D02*
X1804874D01*
X1806200Y582900D01*
G01X1800207Y557952D02*
X1793336D01*
X1793320Y557968D01*
G01X1822757Y569763D02*
X1828411D01*
X1828700Y569474D01*
G01X1835000Y586250D02*
Y587841D01*
X1836281Y589122D01*
G01X1800206Y563858D02*
X1806126D01*
X1807958Y565690D01*
G01X1807752Y538501D02*
X1806017Y540236D01*
G01X1800207Y546141D02*
X1805199D01*
G01X1834000Y532500D02*
Y534900D01*
G01X1806017Y540236D02*
X1800207D01*
G01X1805199Y546141D02*
X1806200Y547142D01*
Y549200D01*
G01X1838000Y549700D02*
X1836000Y547700D01*
Y546500D01*
G01X1780756Y576990D02*
X1783110D01*
X1783700Y576400D01*
G01X1782000Y585000D02*
X1784600D01*
X1785050Y584550D01*
G01X1816100Y576200D02*
X1817200D01*
X1817731Y575669D01*
X1822757D01*
G01X1794776Y574776D02*
Y574665D01*
X1794755Y574644D01*
Y573845D01*
X1794669Y573759D01*
Y572769D01*
X1791800Y569900D01*
Y567200D01*
X1792100Y566900D01*
G01X1822757Y591417D02*
X1825014Y593674D01*
Y593695D01*
G01X1794500Y612500D02*
X1794099D01*
X1791217Y615382D01*
X1788500D01*
G01X1780000Y604500D02*
X1786500D01*
X1794500Y612500D01*
G01X1791500Y606500D02*
Y599000D01*
X1787500Y595000D01*
G01X1838100Y3900D02*
Y2900D01*
X1839000Y2000D01*
Y800D01*
G01X1883090Y69285D02*
X1886590D01*
G01X1847000Y81300D02*
Y86500D01*
G01X1883090Y69285D02*
X1881354D01*
X1877270Y65201D01*
Y63473D01*
G01X1890090Y69285D02*
X1891889D01*
X1895330Y65844D01*
Y64390D01*
G01X1842964Y101426D02*
X1844140D01*
X1845140Y100426D01*
Y97404D01*
X1844957Y97221D01*
G01X1883090Y72785D02*
X1886590D01*
G01D02*
X1890090D01*
G01D02*
X1893381D01*
X1893961Y73365D01*
G01X1894834Y139286D02*
X1894771Y139223D01*
Y138671D01*
X1893370Y137270D01*
X1891130D01*
X1890360Y136500D01*
Y133750D01*
G01X1871855Y104188D02*
X1872390Y104723D01*
Y106521D01*
X1872630Y106761D01*
Y109250D01*
G01X1890360D02*
Y112640D01*
X1887300Y115700D01*
G01X1872630Y133750D02*
Y130370D01*
X1875700Y127300D01*
G01X1897640Y140100D02*
X1895648D01*
X1894834Y139286D01*
G01D02*
X1894020Y140100D01*
X1892370D01*
G01X1850700Y156000D02*
X1853365Y153335D01*
G01X1878540Y133750D02*
Y135940D01*
X1878950Y136350D01*
Y137400D01*
G01X1853365Y153335D02*
X1862335D01*
X1862500Y153500D01*
G01X1893750Y112630D02*
X1897670D01*
X1899790Y110510D01*
G01X1886420Y133750D02*
Y137800D01*
X1885700Y138520D01*
Y141200D01*
G01X1897536Y114600D02*
X1893750D01*
G01X1897536Y120510D02*
X1893750D01*
G01X1857620Y135210D02*
X1858900Y133930D01*
Y130497D01*
X1858970Y130427D01*
Y130092D01*
X1860813Y128249D01*
X1861921D01*
X1865577Y124593D01*
Y124450D01*
G01D02*
X1869250D01*
G01X1880510Y133750D02*
Y136052D01*
X1880971Y136513D01*
Y137929D01*
X1880844Y138056D01*
Y138185D01*
X1879136Y139893D01*
X1878753D01*
G01X1867280Y135406D02*
X1868719D01*
X1869834Y134291D01*
Y131520D01*
X1869250Y130936D01*
Y130360D01*
G01X1855663Y145698D02*
X1852669Y148692D01*
Y150348D01*
G01X1851860Y143880D02*
X1853845D01*
X1855663Y145698D01*
G01D02*
X1858663D01*
X1859163Y145198D01*
G01X1895673Y151800D02*
Y155900D01*
G01X1875900Y158850D02*
X1874650D01*
X1872513Y156713D01*
X1867003D01*
X1863750Y159966D01*
G01X1853150Y169600D02*
X1850100D01*
X1848948Y168448D01*
X1846163D01*
G01D02*
X1845111Y169500D01*
X1842500D01*
G01X1863750Y159966D02*
Y163750D01*
G01X1875900Y158850D02*
X1878900D01*
X1879150Y159100D01*
G01X1868375Y171900D02*
X1868575Y172100D01*
G01X1868375Y171900D02*
X1868175Y172100D01*
G01X1868575D02*
X1874721D01*
X1875900Y170921D01*
Y168850D01*
G01X1868175Y172100D02*
X1861972D01*
X1860700Y170828D01*
Y165600D01*
X1862550Y163750D01*
X1863750D01*
G01X1889300Y172116D02*
X1886884D01*
X1886400Y172600D01*
G01X1897760Y202210D02*
Y213641D01*
X1897450Y213951D01*
G01X1889300Y179990D02*
X1887810D01*
X1886450Y181350D01*
X1881400D01*
G01X1879938Y185588D02*
Y182812D01*
X1881400Y181350D01*
G01X1889300Y170147D02*
X1886547D01*
X1886400Y170000D01*
G01X1889300Y160305D02*
X1886895D01*
X1886200Y161000D01*
G01X1889300Y176053D02*
X1884014D01*
X1883930Y176137D01*
G01X1889300Y178021D02*
X1887079D01*
X1886400Y178700D01*
G01X1839400Y450440D02*
X1839620D01*
X1841736Y448324D01*
Y441754D01*
G01X1868204Y521126D02*
X1861206D01*
X1860280Y520200D01*
G01X1840000Y522500D02*
X1837500D01*
X1836600Y521600D01*
G01X1891750Y562500D02*
Y564000D01*
X1890750Y565000D01*
X1889500D01*
X1889000Y565500D01*
Y568300D01*
G01X1890400Y554600D02*
X1893200D01*
X1894299Y555699D01*
Y557790D01*
G01X1872350Y580350D02*
Y581778D01*
X1871019Y583109D01*
Y583245D01*
X1870892D01*
G01X1872350Y580350D02*
Y579220D01*
X1874900Y576670D01*
Y574350D01*
G01X1844100Y551000D02*
X1842518D01*
X1841118Y549600D01*
Y546500D01*
G01X1878450Y548650D02*
X1876070Y551030D01*
Y552500D01*
G01X1870950Y545500D02*
Y542650D01*
X1870250Y541950D01*
G01X1873150Y561050D02*
Y562450D01*
X1874825Y564125D01*
G01X1842500Y534500D02*
X1841118Y535882D01*
Y539500D01*
G01X1894299Y557790D02*
Y561499D01*
X1893298Y562500D01*
X1891750D01*
G01X1874825Y564125D02*
X1876650Y562300D01*
Y561050D01*
G01X1861961Y557512D02*
X1860515D01*
X1859167Y558860D01*
Y559350D01*
G01X1870100Y561150D02*
X1871150Y562200D01*
Y565850D01*
G01X1865461Y557512D02*
X1866462D01*
X1870100Y561150D01*
G01X1889000Y575700D02*
Y577992D01*
X1887892Y579100D01*
X1882624D01*
X1879862Y581862D01*
G01X1883000Y554600D02*
X1880650D01*
X1879550Y553500D01*
X1878500D01*
G01X1861250Y549500D02*
Y545000D01*
G01D02*
Y542750D01*
X1858500Y540000D01*
G01X1873150Y557550D02*
X1876650D01*
G01X1862500Y586250D02*
X1858000D01*
G01X1862000Y566250D02*
X1859681D01*
X1858681Y567250D01*
Y568087D01*
G01X1878500Y553500D02*
Y555700D01*
X1876650Y557550D01*
G01X1879862Y581862D02*
X1879074D01*
X1877562Y580350D01*
X1875850D01*
G01X1878500Y553500D02*
Y552000D01*
X1880926Y549574D01*
Y546774D01*
X1881600Y546100D01*
G01X1888268Y599287D02*
X1891086Y602105D01*
G01D02*
X1893904Y604923D01*
G01X1891086Y602105D02*
X1893904Y599287D01*
G01X1926890Y73106D02*
X1922800Y77196D01*
Y87400D01*
G01X1955531Y148110D02*
X1960758D01*
X1962800Y146068D01*
Y143700D01*
G01X1955531Y155984D02*
X1949408D01*
X1945156Y160236D01*
G01X1932700Y136563D02*
X1928585D01*
X1928100Y136078D01*
G01X1942637Y100877D02*
X1943490Y101730D01*
X1946190D01*
G01X1955426Y98644D02*
X1952564D01*
X1952440Y98520D01*
G01X1905450Y124742D02*
X1908739Y121453D01*
X1908742D01*
X1909195Y121000D01*
X1913700D01*
X1915000Y122300D01*
Y127200D01*
X1913360Y128840D01*
X1911440D01*
G01X1900200Y123600D02*
X1902001D01*
X1903143Y124742D01*
X1905450D01*
G01X1911440Y128840D02*
X1911750Y129150D01*
Y133010D01*
G01X1911231Y137097D02*
X1911750Y136578D01*
Y133010D01*
G01X1906590Y110820D02*
Y110560D01*
X1906600Y110550D01*
Y106320D01*
X1906871Y106049D01*
G01X1931000Y150500D02*
X1936500D01*
X1937000Y150000D01*
G01X1921800Y137300D02*
Y135200D01*
X1922000Y135000D01*
Y132500D01*
G01X1921199Y140499D02*
X1921800Y139898D01*
Y137300D01*
G01X1911231Y137097D02*
X1903703D01*
X1900700Y140100D01*
X1897640D01*
G01X1899790Y110510D02*
X1900270D01*
X1900560Y110800D01*
X1903070D01*
X1903090Y110820D01*
G01X1944500Y183900D02*
Y185905D01*
X1943559Y186846D01*
X1941609D01*
G01X1953740Y213897D02*
X1951001D01*
X1950000Y212896D01*
Y207893D01*
G01X1965057Y176447D02*
X1962967D01*
X1958252Y171732D01*
X1955531D01*
G01X1966542Y179606D02*
X1955531D01*
G01Y163858D02*
X1959570D01*
X1961472Y165760D01*
G01X1922800Y199550D02*
X1919800D01*
G01X1928000Y199350D02*
X1931483D01*
G01X1922800Y199550D02*
X1927800D01*
X1928000Y199350D01*
G01X1923700Y176053D02*
X1927608D01*
X1928218Y175443D01*
G01X1901579Y190300D02*
Y193721D01*
X1901100Y194200D01*
G01X1923700Y178021D02*
X1928091D01*
X1928249Y178179D01*
G01X1946105Y230344D02*
Y231756D01*
X1949900Y235551D01*
X1953740D01*
G01X1933900Y479530D02*
X1938870D01*
X1939000Y479400D01*
G01X1929480Y475430D02*
Y472880D01*
G01X1933900Y487210D02*
X1937340D01*
X1938300Y486250D01*
G01X1924754Y495775D02*
X1934597D01*
G01X1912890Y483910D02*
X1909690Y487110D01*
Y497330D01*
X1912510Y500150D01*
X1920379D01*
X1924754Y495775D01*
G01X1923900Y484650D02*
X1920230D01*
X1919230Y483650D01*
Y483430D01*
G01X1916390Y483910D02*
X1916870Y483430D01*
X1919230D01*
G01X1919000Y487210D02*
X1918420D01*
X1918240Y487390D01*
X1916460D01*
G01X1923900Y487210D02*
X1923630Y487480D01*
X1919270D01*
X1919000Y487210D01*
G01X1914911Y495775D02*
X1912960Y493824D01*
Y487390D01*
G01X1921800Y586100D02*
X1921900Y586200D01*
X1925103D01*
X1925803Y585500D01*
G01X1933500Y540000D02*
Y536588D01*
X1929453Y532541D01*
G01X1908400Y556800D02*
Y557600D01*
X1909700Y558900D01*
X1915500D01*
X1916593Y557807D01*
X1919504D01*
G01Y576807D02*
X1915593D01*
G01X1918200Y548600D02*
X1920200D01*
X1923600Y552000D01*
Y554200D01*
G01X1905100Y538000D02*
Y534000D01*
X1905000Y533900D01*
G01X1923600Y572300D02*
X1924300Y573000D01*
X1926692D01*
X1926750Y572942D01*
G01X1905100Y538000D02*
X1900900Y542200D01*
Y545400D01*
X1901841Y546341D01*
X1904000D01*
G01X1921244Y540400D02*
Y533750D01*
G01X1930250Y572942D02*
Y574750D01*
X1930921Y575421D01*
Y578500D01*
G01D02*
X1932000D01*
X1933500Y580000D01*
X1935450D01*
X1937250Y578200D01*
G01X1899950Y539500D02*
Y534000D01*
X1900250Y533700D01*
G01X1918200Y545100D02*
X1917300D01*
X1915050Y547350D01*
Y547900D01*
G01X1911000Y546341D02*
X1913241D01*
X1914800Y547900D01*
X1915050D01*
G01X1929600Y590100D02*
Y588578D01*
X1928362Y587340D01*
Y585500D01*
G01X1927015Y611391D02*
X1924000D01*
G01X1931199Y605040D02*
X1929189Y607050D01*
X1923910D01*
X1922900Y606040D01*
Y604450D01*
G01X1934776Y599040D02*
X1936280D01*
X1938000Y597320D01*
G01X1926100Y590100D02*
X1925200D01*
X1923504Y591796D01*
Y592500D01*
G01X1926400Y603700D02*
X1928260Y601840D01*
Y595519D01*
X1931679Y592100D01*
X1933219D01*
X1935359Y589960D01*
X1944882D01*
G01X1942241Y603067D02*
X1944882Y605708D01*
G01D02*
X1947523Y608349D01*
G01X1942241D02*
X1944882Y605708D01*
G01D02*
X1947523Y603067D01*
G01X1934739Y596040D02*
X1935540D01*
X1937100Y594480D01*
X1937870D01*
G01X1929600Y590100D02*
X1932390D01*
G01X1926400Y594700D02*
Y594190D01*
X1929600Y590990D01*
Y590100D01*
G01X1962800Y143700D02*
X1965008D01*
X1969653Y139055D01*
X1970787D01*
G01Y196535D02*
Y198059D01*
X1967817Y201029D01*
G01X1960433Y213997D02*
X1961890Y211043D01*
G01X1960433Y235451D02*
Y236948D01*
X1961890Y238405D01*
X-13780Y598560D03*
X-3937Y-43307D03*
X-7874Y216181D03*
Y325315D03*
X40512Y458744D03*
X-4488Y425472D03*
X-3937Y646063D03*
X99980Y136909D03*
X133563Y183126D03*
Y419626D03*
X224410Y301378D03*
X326772Y163582D03*
Y439173D03*
X500000Y163582D03*
Y439173D03*
X602362Y214764D03*
Y387992D03*
X638541Y171945D03*
Y454425D03*
X783171Y183126D03*
X752641Y159945D03*
X783171Y419626D03*
X752641Y442425D03*
X874016Y301378D03*
X976378Y163582D03*
Y439173D03*
X1149606Y163582D03*
Y439173D03*
X1251969Y214764D03*
Y387992D03*
X1288068Y171945D03*
Y454425D03*
X1401516Y23976D03*
X1402168Y159945D03*
Y442425D03*
X1454685Y338189D03*
X1466693Y375787D03*
X1504666Y29882D03*
X1527844Y80791D03*
Y159531D03*
X1536123Y23968D03*
X1572599Y505315D03*
X1628142Y240199D03*
Y263999D03*
X1600355Y527165D03*
X1638131Y525946D03*
Y475946D03*
X1611283Y567874D03*
Y615236D03*
X1712012Y195587D03*
X1699600Y235400D03*
Y454297D03*
X1674921Y528523D03*
X1658528Y567874D03*
X1705772D03*
X1674921Y545059D03*
X1705772Y615236D03*
X1724606Y235430D03*
X1724807Y451179D03*
X1773347Y528523D03*
Y545059D03*
X1836693Y120158D03*
X1800986Y523267D03*
X1800985Y602503D03*
X1872343Y29874D03*
X1854501Y195587D03*
X1866923Y235400D03*
X1841929Y235430D03*
X1859854Y501441D03*
Y525063D03*
X1956693Y-43307D03*
X1954804Y120158D03*
X1956890Y211535D03*
Y237126D03*
X1955506Y454297D03*
X1930319Y451179D03*
X1956693Y646063D03*
X1969291Y486064D03*
Y497874D03*
G54D145*
X721000Y5000D03*
X720043Y589702D03*
X1585641Y588048D03*
X1850700Y156000D03*
G54D316*
X1851504Y497504D03*
X1868204Y505378D03*
X1851504D03*
X1868204Y513252D03*
X1851504D03*
X1868204Y521126D03*
X1851504D03*
X1868204Y497504D03*
Y529000D03*
X1851504D03*
G54D61*
X-1950Y457450D03*
X-6550Y493850D03*
X85467Y302966D03*
X76500Y347900D03*
X84164Y380790D03*
X199221Y111179D03*
X317912Y108520D03*
X324046Y108154D03*
X353842Y114416D03*
X305817Y112075D03*
X313267Y115125D03*
X370193Y114952D03*
X361803Y113813D03*
X406851Y492615D03*
X418874Y498682D03*
X427596Y494704D03*
X419651Y492659D03*
X721921Y258921D03*
X718246Y258806D03*
X831125Y119452D03*
X829466Y109026D03*
X841741Y173258D03*
X832370Y160129D03*
X967478Y108478D03*
X972825Y107325D03*
X942425Y128074D03*
X955425Y112075D03*
X962875Y115125D03*
X951175Y122825D03*
X1019801Y114952D03*
X1011411Y113813D03*
X1004250Y115216D03*
X1248531Y115203D03*
G54D136*
X651950Y261750D03*
G54D217*
X1430570Y457961D03*
G54D362*
G01X146290Y-42265D02*
X443071D01*
G02Y-45915I0J-1825D01*
G01X145585D01*
X144250Y-47250D01*
X45500D01*
X40500Y-42250D01*
G01X160431Y22923D02*
Y27899D01*
G01X130313Y22923D02*
Y27899D01*
G01X153738Y22923D02*
Y27899D01*
G01X123620Y22923D02*
Y27899D01*
G01X147045Y22923D02*
Y27899D01*
G01X167124Y22923D02*
Y27899D01*
G01X140352Y41033D02*
Y37045D01*
X139306Y35999D01*
Y33114D01*
X141880Y30540D01*
G01X140352Y22923D02*
Y26240D01*
X138706Y27886D01*
Y28800D01*
X139438Y29532D01*
Y30503D01*
X138446Y31495D01*
X137551D01*
X136806Y30750D01*
G01X143699Y41033D02*
X143698Y41032D01*
Y36708D01*
X144571Y35835D01*
Y32913D01*
X143729Y32071D01*
X142958D01*
X141880Y33149D01*
G01X137006Y22923D02*
Y25351D01*
X135289Y27068D01*
X134956Y27792D01*
Y31013D01*
X135277Y31896D01*
X136780Y33399D01*
G01X133659Y3233D02*
X132959Y-4100D01*
G01X163777Y3233D02*
Y-2008D01*
X163391Y-4100D01*
G01X160431Y-14877D02*
Y-9901D01*
G01X130313Y-14877D02*
Y-9901D01*
G01X157084Y3233D02*
Y-692D01*
X157602Y-1210D01*
Y-2090D01*
X157084Y-2608D01*
Y-3700D01*
G01X153738Y-14877D02*
Y-9901D01*
G01X126966Y3233D02*
Y-2008D01*
X126580Y-4100D01*
G01X123620Y-14877D02*
Y-9901D01*
G01X150392Y3233D02*
Y-600D01*
X150912Y-1120D01*
Y-1980D01*
X150392Y-2500D01*
Y-3699D01*
X150391Y-3700D01*
G01X147045Y-14877D02*
Y-9901D01*
G01X167124Y-14877D02*
Y-9901D01*
G01X140352Y3233D02*
Y-755D01*
X139306Y-1801D01*
Y-4686D01*
X141880Y-7260D01*
G01X140352Y-14877D02*
Y-11560D01*
X138706Y-9914D01*
Y-9000D01*
X139438Y-8268D01*
Y-7297D01*
X138446Y-6305D01*
X137626D01*
X136881Y-7050D01*
X136806D01*
G01X143699Y3233D02*
Y-1093D01*
X144571Y-1965D01*
Y-4887D01*
X143729Y-5729D01*
X142958D01*
X141880Y-4651D01*
G01X137006Y-14877D02*
Y-12449D01*
X135289Y-10732D01*
X134956Y-10008D01*
Y-6787D01*
X135277Y-5904D01*
X136780Y-4401D01*
G01X133659Y78833D02*
X133341Y75500D01*
X132959Y71500D01*
G01X163777Y78833D02*
Y73592D01*
X163391Y71500D01*
G01X160431Y92757D02*
X160192Y92996D01*
Y103892D01*
X178000Y121700D01*
Y127564D01*
X189045Y138609D01*
Y149371D01*
X196155Y156481D01*
Y181038D01*
X201525Y186408D01*
Y187326D01*
X199986Y188866D01*
Y189784D01*
X200942Y190740D01*
X201860D01*
X203399Y189200D01*
X204317D01*
X250823Y235706D01*
X264092D01*
G01X160431Y60723D02*
Y65699D01*
G01X163477Y87714D02*
X161632Y89559D01*
Y90720D01*
X162892Y93800D01*
Y102992D01*
X180519Y120619D01*
Y126519D01*
X191564Y137564D01*
Y148326D01*
X198674Y155436D01*
Y179799D01*
X252031Y233156D01*
X264036D01*
G01X130313Y60723D02*
Y65699D01*
G01X157084Y78833D02*
Y74908D01*
X157602Y74390D01*
Y73510D01*
X157084Y72992D01*
Y71900D01*
G01X153738Y60723D02*
Y65699D01*
G01X126966Y78833D02*
Y73592D01*
X126580Y71500D01*
G01X123620Y65699D02*
Y60723D01*
G01X150392Y78833D02*
Y75000D01*
X150912Y74480D01*
Y73620D01*
X150392Y73100D01*
Y71901D01*
X150391Y71900D01*
G01X147045Y60723D02*
Y65699D01*
G01X167124Y92757D02*
X165584Y94297D01*
Y101984D01*
X182420Y118820D01*
X187720D01*
X190762Y121862D01*
Y123122D01*
X190112Y123772D01*
X185650D01*
X185000Y124422D01*
Y125772D01*
X185650Y126422D01*
X190112D01*
X190762Y127072D01*
Y130526D01*
X194083Y133847D01*
Y143359D01*
X197581Y146857D01*
Y150780D01*
X201193Y154392D01*
Y178560D01*
X253192Y230559D01*
X262992D01*
G01X167124Y60723D02*
Y65699D01*
G01X169770Y87714D02*
X167766Y89718D01*
Y90874D01*
X168966Y92074D01*
Y93574D01*
X168307Y94233D01*
Y101008D01*
X183603Y116301D01*
X189000Y116300D01*
X193281Y120581D01*
Y129481D01*
X196602Y132802D01*
Y141102D01*
X200100Y144600D01*
Y148880D01*
X203712Y152492D01*
Y177321D01*
X254247Y227856D01*
X262783D01*
G01X140352Y78833D02*
Y74605D01*
X138848Y73101D01*
Y71401D01*
X140149Y70100D01*
X141031D01*
X141880Y70949D01*
G01X140352Y60723D02*
Y63296D01*
X138706Y64942D01*
Y66600D01*
X139438Y67332D01*
Y68303D01*
X138446Y69295D01*
X137626D01*
X136881Y68550D01*
X136806D01*
G01X143699Y78833D02*
Y74849D01*
X143848Y74700D01*
Y69300D01*
X142888Y68340D01*
X141880D01*
G01X137006Y60723D02*
Y63151D01*
X135289Y64868D01*
X134956Y65592D01*
Y68813D01*
X135277Y69696D01*
X136780Y71199D01*
G01X133659Y41033D02*
X133035Y34500D01*
X132959Y33700D01*
G01X163777Y41033D02*
Y35792D01*
X163539Y34500D01*
X163391Y33700D01*
G01X157084Y41033D02*
Y37108D01*
X157602Y36590D01*
Y35710D01*
X157084Y35192D01*
Y34100D01*
G01X126966Y41033D02*
Y35792D01*
X126728Y34500D01*
X126580Y33700D01*
G01X150392Y41033D02*
Y37200D01*
X150912Y36680D01*
Y35820D01*
X150392Y35300D01*
Y34101D01*
X150391Y34100D01*
G01X265495Y357309D02*
X257312D01*
X164992Y449629D01*
Y497800D01*
X162266Y500526D01*
Y511452D01*
X160431Y513287D01*
Y518157D01*
G01X265520Y360500D02*
X257879D01*
X167692Y450687D01*
Y498999D01*
X164915Y501776D01*
Y511676D01*
X163477Y513114D01*
G01X160431Y523900D02*
Y528899D01*
G01X130313Y523900D02*
Y528899D01*
G01X153738Y523900D02*
Y528899D01*
G01X123620Y523900D02*
Y528899D01*
G01X147045Y523900D02*
Y528899D01*
G01X265605Y363160D02*
X258977D01*
X170392Y451745D01*
Y500600D01*
X167492Y503500D01*
Y507300D01*
X169046Y508854D01*
Y510672D01*
X167124Y512594D01*
Y518157D01*
G01Y523900D02*
Y528899D01*
G01X140352Y523900D02*
Y526496D01*
X138706Y528142D01*
Y529800D01*
X139438Y530532D01*
Y531503D01*
X138446Y532495D01*
X137626D01*
X136881Y531750D01*
X136806D01*
G01X137006Y523900D02*
Y526351D01*
X135289Y528068D01*
X135040Y528610D01*
X134956Y528792D01*
Y532013D01*
X135277Y532896D01*
X136780Y534399D01*
G01X133659Y542010D02*
Y542033D01*
X132959Y534700D01*
G01X163777Y542010D02*
Y536792D01*
X163391Y534700D01*
G01X157084Y542010D02*
Y538108D01*
X157602Y537590D01*
Y536710D01*
X157084Y536192D01*
Y535100D01*
G01X126966Y542010D02*
Y536792D01*
X126580Y534700D01*
G01X150392Y542010D02*
Y538200D01*
X150912Y537680D01*
Y536820D01*
X150392Y536300D01*
Y535101D01*
X150391Y535100D01*
G01X140352Y542010D02*
Y537805D01*
X138848Y536301D01*
Y534601D01*
X140149Y533300D01*
X141031D01*
X141880Y534149D01*
G01X143699Y542010D02*
Y538049D01*
X143848Y537900D01*
Y532500D01*
X142888Y531540D01*
X141880D01*
G01X133659Y579810D02*
Y579833D01*
X132959Y572500D01*
G01X163777Y579810D02*
Y574592D01*
X163391Y572500D01*
G01X160431Y561700D02*
Y566699D01*
G01X130313Y561700D02*
Y566699D01*
G01X157084Y579810D02*
Y575908D01*
X157602Y575390D01*
Y574510D01*
X157084Y573992D01*
Y572900D01*
G01X153738Y561700D02*
Y566699D01*
G01X126966Y579810D02*
Y574592D01*
X126580Y572500D01*
G01X123620Y561700D02*
Y566699D01*
G01X150392Y579810D02*
Y576000D01*
X150912Y575480D01*
Y574620D01*
X150392Y574100D01*
Y572901D01*
X150391Y572900D01*
G01X147045Y561700D02*
Y566699D01*
G01X167124Y561700D02*
Y566699D01*
G01X140352Y579810D02*
Y575605D01*
X138848Y574101D01*
Y572401D01*
X140149Y571100D01*
X141031D01*
X141880Y571949D01*
G01X140352Y561700D02*
Y564296D01*
X138706Y565942D01*
Y567600D01*
X139438Y568332D01*
Y569303D01*
X138446Y570295D01*
X137626D01*
X136881Y569550D01*
X136806D01*
G01X143699Y579810D02*
Y575849D01*
X143848Y575700D01*
Y570300D01*
X142888Y569340D01*
X141880D01*
G01X137006Y561700D02*
Y564151D01*
X135289Y565868D01*
X134956Y566592D01*
Y569813D01*
X135277Y570696D01*
X136780Y572199D01*
G01X133659Y617610D02*
Y617633D01*
X132959Y610300D01*
G01X163777Y617610D02*
Y612392D01*
X163391Y610300D01*
G01X160431Y599500D02*
Y604499D01*
G01X130313Y599500D02*
Y604499D01*
G01X157084Y617610D02*
Y613708D01*
X157602Y613190D01*
Y612310D01*
X157084Y611792D01*
Y610700D01*
G01X153738Y599500D02*
Y604499D01*
G01X126966Y617610D02*
Y612392D01*
X126580Y610300D01*
G01X123620Y599500D02*
Y604499D01*
G01X150392Y617610D02*
Y613800D01*
X150912Y613280D01*
Y612420D01*
X150392Y611900D01*
Y610701D01*
X150391Y610700D01*
G01X147045Y599500D02*
Y604499D01*
G01X167124Y599500D02*
Y604499D01*
G01X140352Y617610D02*
Y613405D01*
X138848Y611901D01*
Y610201D01*
X140149Y608900D01*
X141031D01*
X141880Y609749D01*
G01X140352Y599500D02*
Y602096D01*
X138706Y603742D01*
Y605400D01*
X139438Y606132D01*
Y607103D01*
X138446Y608095D01*
X137626D01*
X136881Y607350D01*
X136806D01*
G01X143699Y617610D02*
Y613649D01*
X143848Y613500D01*
Y608100D01*
X142888Y607140D01*
X141880D01*
G01X137006Y599500D02*
Y601951D01*
X135289Y603668D01*
X134956Y604392D01*
Y607613D01*
X135277Y608496D01*
X136780Y609999D01*
G01X190549Y22923D02*
Y27899D01*
G01X183856Y22923D02*
Y27899D01*
G01X203935Y22923D02*
Y27899D01*
G01X227360Y22923D02*
Y27899D01*
G01X197242Y22923D02*
Y27899D01*
G01X220667Y22923D02*
Y27899D01*
G01X177163Y22923D02*
Y26240D01*
X175517Y27886D01*
Y28800D01*
X176249Y29532D01*
Y30503D01*
X175257Y31495D01*
X174362D01*
X173617Y30750D01*
G01X213974Y22923D02*
Y26240D01*
X212328Y27886D01*
Y28800D01*
X213060Y29532D01*
Y30503D01*
X212068Y31495D01*
X211173D01*
X210428Y30750D01*
G01X177163Y41033D02*
Y37045D01*
X176117Y35999D01*
Y33114D01*
X178691Y30540D01*
G01X213974Y41033D02*
Y37045D01*
X212928Y35999D01*
Y33114D01*
X215502Y30540D01*
G01X173817Y22923D02*
Y25351D01*
X172100Y27068D01*
X171767Y27792D01*
Y31013D01*
X172088Y31896D01*
X173591Y33399D01*
G01X210628Y22923D02*
Y25351D01*
X208911Y27068D01*
X208578Y27792D01*
Y31013D01*
X208899Y31896D01*
X210402Y33399D01*
G01X180510Y41033D02*
X180509Y41032D01*
Y36708D01*
X181382Y35835D01*
Y32913D01*
X180540Y32071D01*
X179769D01*
X178691Y33149D01*
G01X217321Y41033D02*
X217320Y41032D01*
Y36708D01*
X218193Y35835D01*
Y32913D01*
X217351Y32071D01*
X216580D01*
X215502Y33149D01*
G01X193896Y3233D02*
X193895Y3232D01*
Y-692D01*
X194413Y-1210D01*
Y-2090D01*
X193895Y-2608D01*
Y-3700D01*
G01X190549Y-14877D02*
Y-9901D01*
G01X187203Y3233D02*
Y-600D01*
X187723Y-1120D01*
Y-1980D01*
X187203Y-2500D01*
Y-3699D01*
X187202Y-3700D01*
G01X183856Y-14877D02*
Y-9901D01*
G01X207281Y3233D02*
X206581Y-4100D01*
G01X203935Y-14877D02*
Y-9901D01*
G01X230707Y3233D02*
X230706Y3232D01*
Y-692D01*
X231224Y-1210D01*
Y-2090D01*
X230706Y-2608D01*
Y-3700D01*
G01X227360Y-14877D02*
Y-9901D01*
G01X200588Y3233D02*
Y-2008D01*
X200202Y-4100D01*
G01X197242Y-14877D02*
Y-9901D01*
G01X224014Y3233D02*
Y-600D01*
X224534Y-1120D01*
Y-1980D01*
X224014Y-2500D01*
Y-3699D01*
X224013Y-3700D01*
G01X220667Y-14877D02*
Y-9901D01*
G01X170470Y3233D02*
X169770Y-4100D01*
G01X177163Y-14877D02*
Y-11560D01*
X175517Y-9914D01*
Y-9000D01*
X176249Y-8268D01*
Y-7297D01*
X175257Y-6305D01*
X174437D01*
X173692Y-7050D01*
X173617D01*
G01X213974Y-14877D02*
Y-11560D01*
X212328Y-9914D01*
Y-9000D01*
X213060Y-8268D01*
Y-7297D01*
X212068Y-6305D01*
X211248D01*
X210503Y-7050D01*
X210428D01*
G01X177163Y3233D02*
Y-755D01*
X176117Y-1801D01*
Y-4686D01*
X178691Y-7260D01*
G01X213974Y3233D02*
Y-755D01*
X212928Y-1801D01*
Y-4686D01*
X215502Y-7260D01*
G01X173817Y-14877D02*
Y-12449D01*
X172100Y-10732D01*
X171767Y-10008D01*
Y-6787D01*
X172088Y-5904D01*
X173591Y-4401D01*
G01X210628Y-14877D02*
Y-12449D01*
X208911Y-10732D01*
X208578Y-10008D01*
Y-6787D01*
X208899Y-5904D01*
X210402Y-4401D01*
G01X180510Y3233D02*
Y-1093D01*
X181382Y-1965D01*
Y-4887D01*
X180540Y-5729D01*
X179769D01*
X178691Y-4651D01*
G01X217321Y3233D02*
Y-1093D01*
X218193Y-1965D01*
Y-4887D01*
X217351Y-5729D01*
X216580D01*
X215502Y-4651D01*
G01X193896Y78833D02*
X193895Y78832D01*
Y74908D01*
X194413Y74390D01*
Y73510D01*
X193895Y72992D01*
Y71900D01*
G01X190549Y92757D02*
X192584Y94792D01*
X202580D01*
X226330Y118542D01*
Y119462D01*
X225376Y120416D01*
X224456D01*
X211230Y107190D01*
X210310D01*
X209356Y108144D01*
Y109064D01*
X225718Y125426D01*
Y130200D01*
G01X190549Y60723D02*
Y65699D01*
G01X193895Y87714D02*
X191403Y90206D01*
X190434D01*
X188684Y91956D01*
Y94684D01*
X190700Y96700D01*
X200700D01*
X206700Y102700D01*
Y110700D01*
X218168Y122168D01*
Y123088D01*
X217214Y124042D01*
X216294D01*
X212036Y119784D01*
X211116D01*
X210162Y120738D01*
Y121658D01*
X216294Y127790D01*
X217214D01*
X220042Y124962D01*
X220962D01*
X222829Y126829D01*
Y141300D01*
G01X187203Y78833D02*
Y75000D01*
X187723Y74480D01*
Y73620D01*
X187203Y73100D01*
Y71901D01*
X187202Y71900D01*
G01X199221Y111179D02*
X197375Y109333D01*
Y108625D01*
X200496Y105504D01*
Y104796D01*
X197460Y101760D01*
X196540D01*
X193525Y104775D01*
X192817D01*
X182892Y94850D01*
Y93721D01*
X183856Y92757D01*
G01Y60723D02*
Y65699D01*
G01X187202Y87714D02*
X185166Y89750D01*
Y91174D01*
X185892Y91900D01*
Y95192D01*
X190550Y99850D01*
X200050D01*
X203500Y103300D01*
Y111600D01*
X207000Y115100D01*
Y122800D01*
X213828Y129628D01*
Y134900D01*
G01X207281Y78833D02*
X206963Y75500D01*
X206581Y71500D01*
G01X203935Y60723D02*
Y65699D01*
G01X230707Y78833D02*
X230706Y78832D01*
Y74908D01*
X231224Y74390D01*
Y73510D01*
X230706Y72992D01*
Y71900D01*
G01X227360Y60723D02*
Y65699D01*
G01X200588Y78833D02*
Y73592D01*
X200202Y71500D01*
G01X197242Y60723D02*
Y65699D01*
G01X224014Y78833D02*
Y75000D01*
X224534Y74480D01*
Y73620D01*
X224014Y73100D01*
Y71901D01*
X224013Y71900D01*
G01X220667Y60723D02*
Y65699D01*
G01X170470Y78833D02*
X170152Y75500D01*
X169770Y71500D01*
G01X177163Y60723D02*
Y63296D01*
X175517Y64942D01*
Y66600D01*
X176249Y67332D01*
Y68303D01*
X175257Y69295D01*
X174437D01*
X173692Y68550D01*
X173617D01*
G01X173591Y89900D02*
X174293D01*
X175362Y90969D01*
Y93430D01*
X174392Y94400D01*
X172892D01*
X172134Y95158D01*
Y96158D01*
X172667Y96691D01*
Y97625D01*
X172134Y98158D01*
Y99506D01*
X174164Y101536D01*
X175136D01*
X175700Y102100D01*
Y103072D01*
X176428Y103800D01*
X177100D01*
X177800Y104500D01*
Y105172D01*
X178828Y106200D01*
X179800D01*
X180800Y107200D01*
Y108172D01*
X185128Y112500D01*
X186300D01*
X187100Y111700D01*
X189000D01*
X189800Y112500D01*
X191000D01*
X196950Y118450D01*
Y126650D01*
X203884Y133584D01*
Y135243D01*
X200516Y138611D01*
Y139825D01*
X203900Y143209D01*
Y147490D01*
X207381Y150971D01*
Y173000D01*
X207881Y173500D01*
X209926D01*
X211100Y174674D01*
Y179296D01*
X255945Y224141D01*
X262512D01*
G01X213974Y60723D02*
Y63296D01*
X212328Y64942D01*
Y66600D01*
X213060Y67332D01*
Y68303D01*
X212068Y69295D01*
X211248D01*
X210503Y68550D01*
X210428D01*
G01X177163Y78833D02*
Y74605D01*
X175592Y73034D01*
Y71468D01*
X176960Y70100D01*
X177842D01*
X178691Y70949D01*
G01Y87514D02*
X176896Y89309D01*
Y99177D01*
X178069Y100350D01*
X182923D01*
X199750Y117177D01*
Y125034D01*
X206516Y131800D01*
Y146543D01*
X210131Y150158D01*
Y161577D01*
X211304Y162750D01*
X216231D01*
X216731Y163250D01*
Y165000D01*
X216231Y165500D01*
X211073D01*
X209900Y166673D01*
Y169577D01*
X211073Y170750D01*
X213250D01*
X213750Y171250D01*
Y178038D01*
X256778Y221066D01*
X263144D01*
G01X213974Y78833D02*
Y74605D01*
X212470Y73101D01*
Y71401D01*
X213771Y70100D01*
X214653D01*
X215502Y70949D01*
G01X173817Y60723D02*
Y63151D01*
X172100Y64868D01*
X171767Y65592D01*
Y68813D01*
X172088Y69696D01*
X173591Y71199D01*
G01X195800Y124600D02*
Y118927D01*
X190523Y113650D01*
X189323D01*
X188523Y112850D01*
X187577D01*
X186777Y113650D01*
X184651D01*
X170984Y99983D01*
Y94681D01*
X171742Y93923D01*
Y89149D01*
X173591Y87300D01*
G01X210628Y60723D02*
Y63151D01*
X208911Y64868D01*
X208578Y65592D01*
Y68813D01*
X208899Y69696D01*
X210402Y71199D01*
G01X180510Y78833D02*
Y74849D01*
X180659Y74700D01*
Y69300D01*
X179699Y68340D01*
X178691D01*
G01X200900Y120704D02*
Y116700D01*
X183400Y99200D01*
X178546D01*
X178046Y98700D01*
Y95046D01*
X178592Y94500D01*
X180092D01*
X180592Y94000D01*
Y90599D01*
X180107Y90114D01*
X178691D01*
G01X217321Y78833D02*
Y74849D01*
X217470Y74700D01*
Y69300D01*
X216510Y68340D01*
X215502D01*
G01X193896Y41033D02*
Y37109D01*
X193895Y37108D01*
X194413Y36590D01*
Y35710D01*
X193895Y35192D01*
Y34100D01*
G01X187203Y41033D02*
Y37200D01*
X187723Y36680D01*
Y35820D01*
X187203Y35300D01*
Y34101D01*
X187202Y34100D01*
G01X207281Y41033D02*
X206657Y34500D01*
X206581Y33700D01*
G01X230707Y41033D02*
X230706Y41032D01*
Y37108D01*
X231224Y36590D01*
Y35710D01*
X230706Y35192D01*
Y34100D01*
G01X200588Y41033D02*
Y35792D01*
X200350Y34500D01*
X200202Y33700D01*
G01X224014Y41033D02*
Y37200D01*
X224534Y36680D01*
Y35820D01*
X224014Y35300D01*
Y34101D01*
X224013Y34100D01*
G01X170470Y41033D02*
X169846Y34500D01*
X169770Y33700D01*
G01X225718Y130200D02*
Y132418D01*
X227600Y134300D01*
Y144802D01*
X229500Y146702D01*
Y177100D01*
X262944Y210544D01*
G01X222829Y141300D02*
Y143594D01*
X226500Y147265D01*
Y177859D01*
X261000Y212359D01*
G01X210896Y140300D02*
Y142796D01*
X212850Y144750D01*
X216500D01*
X220881Y149131D01*
Y154619D01*
X220200Y155300D01*
X218841D01*
X218341Y154800D01*
Y151141D01*
X217100Y149900D01*
X214300D01*
X213800Y150400D01*
Y157600D01*
X214300Y158100D01*
X219900D01*
X220400Y158600D01*
Y169600D01*
X217419Y172581D01*
Y176294D01*
X258125Y217000D01*
G01X199221Y111179D02*
X204000Y115958D01*
Y123701D01*
X210896Y130597D01*
Y140300D01*
G01X213828Y134900D02*
Y140900D01*
X214328Y141400D01*
X215978D01*
X216478Y140900D01*
Y132600D01*
X216978Y132100D01*
X219800D01*
X220300Y132600D01*
Y144628D01*
X223400Y147728D01*
Y178517D01*
X259383Y214500D01*
G01X195800Y124600D02*
Y127127D01*
X202734Y134061D01*
Y134766D01*
X199366Y138134D01*
Y140302D01*
X202750Y143686D01*
Y147967D01*
X206231Y151448D01*
Y173477D01*
X207404Y174650D01*
X209449D01*
X209950Y175151D01*
Y179773D01*
X255468Y225291D01*
X262512D01*
G01X200900Y120704D02*
Y124557D01*
X207666Y131323D01*
Y134294D01*
X208166Y134794D01*
Y135794D01*
X207666Y136294D01*
Y137294D01*
X208166Y137794D01*
Y138794D01*
X207666Y139294D01*
Y140294D01*
X208166Y140794D01*
Y141794D01*
X207666Y142294D01*
Y143294D01*
X208166Y143794D01*
Y144794D01*
X207666Y145294D01*
Y146066D01*
X211281Y149681D01*
Y161100D01*
X211781Y161600D01*
X216708D01*
X217881Y162773D01*
Y165477D01*
X216708Y166650D01*
X211550D01*
X211050Y167150D01*
Y169100D01*
X211550Y169600D01*
X213727D01*
X214900Y170773D01*
Y177561D01*
X257255Y219916D01*
X263144D01*
G01X231492Y140500D02*
Y142792D01*
X233592Y144892D01*
Y168449D01*
X237398Y172255D01*
Y173175D01*
X236596Y173977D01*
Y174897D01*
X237550Y175851D01*
X238470D01*
X239272Y175049D01*
X240192D01*
X241146Y176003D01*
Y176923D01*
X240344Y177725D01*
Y178645D01*
X241298Y179599D01*
X242218D01*
X243020Y178797D01*
X243940D01*
X255016Y189873D01*
X255018D01*
G01X234053Y112327D02*
X231492Y114888D01*
Y140500D01*
G01X265700Y366500D02*
X259395D01*
X173089Y452806D01*
Y459159D01*
X173839Y459909D01*
X175442D01*
X176092Y460559D01*
Y461909D01*
X175442Y462559D01*
X173839D01*
X173189Y463209D01*
Y464559D01*
X173839Y465209D01*
X175442D01*
X176092Y465859D01*
Y467209D01*
X175442Y467859D01*
X173839D01*
X173089Y468609D01*
Y502204D01*
X170292Y505001D01*
Y506100D01*
X171766Y507574D01*
Y512426D01*
X171078Y513114D01*
X169770D01*
G01X265892Y371555D02*
X259753D01*
X177129Y454179D01*
Y456187D01*
X177818Y456876D01*
X179097D01*
X180472Y458251D01*
Y469591D01*
X178897Y471166D01*
X177618D01*
X176916Y471868D01*
Y511975D01*
X173591Y515300D01*
G01X265892Y370405D02*
X259276D01*
X175979Y453702D01*
Y456664D01*
X177341Y458026D01*
X178620D01*
X179322Y458728D01*
Y469114D01*
X178420Y470016D01*
X177141D01*
X175766Y471391D01*
Y504413D01*
X175392Y504787D01*
Y505787D01*
X175766Y506161D01*
Y507451D01*
X175404Y507813D01*
Y508813D01*
X175766Y509175D01*
Y511498D01*
X174564Y512700D01*
X173591D01*
G01X266484Y385393D02*
X262871D01*
X197724Y450540D01*
Y498710D01*
X197034Y499400D01*
X195724D01*
X195034Y498710D01*
Y487690D01*
X194344Y487000D01*
X193034D01*
X192344Y487690D01*
Y511374D01*
X190549Y513169D01*
Y518157D01*
G01X266034Y387943D02*
X264149D01*
X200392Y451700D01*
Y487878D01*
X201042Y488528D01*
X202392D01*
X203042Y487878D01*
Y475250D01*
X203692Y474600D01*
X205042D01*
X205692Y475250D01*
Y501428D01*
X204742Y502378D01*
X196914D01*
X195012Y504280D01*
Y511997D01*
X193895Y513114D01*
G01X266665Y378760D02*
X261890D01*
X192372Y448278D01*
Y463610D01*
X191682Y464300D01*
X190372D01*
X189682Y463610D01*
Y453990D01*
X188992Y453300D01*
X187682D01*
X186992Y453990D01*
Y506000D01*
X185992Y507000D01*
Y510800D01*
X183856Y512936D01*
Y518157D01*
G01X266525Y382843D02*
X261614D01*
X195029Y449428D01*
Y483810D01*
X194439Y484400D01*
X193129D01*
X192339Y483610D01*
Y467647D01*
X191649Y466957D01*
X190339D01*
X189649Y467647D01*
Y507043D01*
X188692Y508000D01*
Y511624D01*
X187202Y513114D01*
G01X265372Y374281D02*
X260935D01*
X183022Y452194D01*
Y471003D01*
X179922Y474103D01*
Y476797D01*
X183022Y479897D01*
Y481983D01*
X182320Y482685D01*
X181087D01*
X179712Y484060D01*
Y487100D01*
X181087Y488475D01*
X182320D01*
X183022Y489177D01*
Y491263D01*
X182320Y491965D01*
X181087D01*
X179712Y493340D01*
Y496380D01*
X181087Y497755D01*
X182320D01*
X183022Y498457D01*
Y499851D01*
X179355Y503518D01*
Y504974D01*
X179645Y505264D01*
Y506264D01*
X179145Y506764D01*
Y507764D01*
X179645Y508264D01*
Y509264D01*
X179145Y509764D01*
Y510764D01*
X179645Y511264D01*
Y511961D01*
X178692Y512914D01*
X178691D01*
G01X265392Y375431D02*
X261412D01*
X184172Y452671D01*
Y471480D01*
X181072Y474580D01*
Y476320D01*
X184172Y479420D01*
Y482460D01*
X182797Y483835D01*
X181564D01*
X180862Y484537D01*
Y486623D01*
X181564Y487325D01*
X182797D01*
X184172Y488700D01*
Y491740D01*
X182797Y493115D01*
X181564D01*
X180862Y493817D01*
Y495903D01*
X181564Y496605D01*
X182797D01*
X184172Y497980D01*
Y500328D01*
X180795Y503705D01*
Y513411D01*
X178692Y515514D01*
X178691D01*
G01X190549Y523900D02*
Y528899D01*
G01X183856Y523900D02*
Y528899D01*
G01X203935Y523900D02*
Y528899D01*
G01X227360Y523900D02*
Y528899D01*
G01X197242Y523900D02*
Y528899D01*
G01X220667Y523900D02*
Y528899D01*
G01X177163Y523900D02*
Y526496D01*
X175517Y528142D01*
Y529800D01*
X176249Y530532D01*
Y531503D01*
X175257Y532495D01*
X174437D01*
X173692Y531750D01*
X173617D01*
G01X213974Y523900D02*
Y526496D01*
X212328Y528142D01*
Y529800D01*
X213060Y530532D01*
Y531503D01*
X212068Y532495D01*
X211248D01*
X210503Y531750D01*
X210428D01*
G01X173817Y523900D02*
Y526351D01*
X172100Y528068D01*
X171851Y528610D01*
X171767Y528792D01*
Y532013D01*
X172088Y532896D01*
X173591Y534399D01*
G01X210628Y523900D02*
Y526351D01*
X208911Y528068D01*
X208662Y528610D01*
X208578Y528792D01*
Y532013D01*
X208899Y532896D01*
X210402Y534399D01*
G01X280656Y402349D02*
X265804D01*
X237809Y430344D01*
X231492Y445593D01*
Y497100D01*
X232892Y498500D01*
X233292D01*
G01X193896Y542010D02*
X193895D01*
Y538108D01*
X194413Y537590D01*
Y536710D01*
X193895Y536192D01*
Y535100D01*
G01X187203Y542010D02*
Y538200D01*
X187723Y537680D01*
Y536820D01*
X187203Y536300D01*
Y535101D01*
X187202Y535100D01*
G01X207281Y542010D02*
Y542033D01*
X206581Y534700D01*
G01X230707Y542010D02*
X230706D01*
Y538108D01*
X231224Y537590D01*
Y536710D01*
X230706Y536192D01*
Y535100D01*
G01X200588Y542010D02*
Y536792D01*
X200202Y534700D01*
G01X224014Y542010D02*
Y538200D01*
X224534Y537680D01*
Y536820D01*
X224014Y536300D01*
Y535101D01*
X224013Y535100D01*
G01X170470Y542010D02*
Y542033D01*
X169770Y534700D01*
G01X177163Y542010D02*
Y537805D01*
X175592Y536234D01*
Y534668D01*
X176960Y533300D01*
X177842D01*
X178691Y534149D01*
G01X213974Y542010D02*
Y537805D01*
X212470Y536301D01*
Y534601D01*
X213771Y533300D01*
X214653D01*
X215502Y534149D01*
G01X180510Y542010D02*
Y538049D01*
X180659Y537900D01*
Y532500D01*
X179699Y531540D01*
X178691D01*
G01X217321Y542010D02*
Y538049D01*
X217470Y537900D01*
Y532500D01*
X216510Y531540D01*
X215502D01*
G01X193896Y579810D02*
X193895D01*
Y575908D01*
X194413Y575390D01*
Y574510D01*
X193895Y573992D01*
Y572900D01*
G01X190549Y561700D02*
Y566699D01*
G01X187203Y579810D02*
Y576000D01*
X187723Y575480D01*
Y574620D01*
X187203Y574100D01*
Y572901D01*
X187202Y572900D01*
G01X183856Y561700D02*
Y566699D01*
G01X207281Y579810D02*
Y579833D01*
X206581Y572500D01*
G01X203935Y561700D02*
Y566699D01*
G01X230707Y579810D02*
X230706D01*
Y575908D01*
X231224Y575390D01*
Y574510D01*
X230706Y573992D01*
Y572900D01*
G01X227360Y561700D02*
Y566699D01*
G01X200588Y579810D02*
Y574592D01*
X200202Y572500D01*
G01X197242Y561700D02*
Y566699D01*
G01X224014Y579810D02*
Y576000D01*
X224534Y575480D01*
Y574620D01*
X224014Y574100D01*
Y572901D01*
X224013Y572900D01*
G01X220667Y561700D02*
Y566699D01*
G01X170470Y579810D02*
Y579833D01*
X169770Y572500D01*
G01X177163Y561700D02*
Y564296D01*
X175517Y565942D01*
Y567600D01*
X176249Y568332D01*
Y569303D01*
X175257Y570295D01*
X174437D01*
X173692Y569550D01*
X173617D01*
G01X213974Y561700D02*
Y564296D01*
X212328Y565942D01*
Y567600D01*
X213060Y568332D01*
Y569303D01*
X212068Y570295D01*
X211248D01*
X210503Y569550D01*
X210428D01*
G01X177163Y579810D02*
Y575605D01*
X175592Y574034D01*
Y572468D01*
X176960Y571100D01*
X177842D01*
X178691Y571949D01*
G01X213974Y579810D02*
Y575605D01*
X212470Y574101D01*
Y572401D01*
X213771Y571100D01*
X214653D01*
X215502Y571949D01*
G01X173817Y561700D02*
Y564151D01*
X172100Y565868D01*
X171767Y566592D01*
Y569813D01*
X172088Y570696D01*
X173591Y572199D01*
G01X210628Y561700D02*
Y564151D01*
X208911Y565868D01*
X208578Y566592D01*
Y569813D01*
X208899Y570696D01*
X210402Y572199D01*
G01X180510Y579810D02*
Y575849D01*
X180659Y575700D01*
Y570300D01*
X179699Y569340D01*
X178691D01*
G01X217321Y579810D02*
Y575849D01*
X217470Y575700D01*
Y570300D01*
X216510Y569340D01*
X215502D01*
G01X193896Y617610D02*
X193895D01*
Y613708D01*
X194413Y613190D01*
Y612310D01*
X193895Y611792D01*
Y610700D01*
G01X190549Y599500D02*
Y604499D01*
G01X187203Y617610D02*
Y613800D01*
X187723Y613280D01*
Y612420D01*
X187203Y611900D01*
Y610701D01*
X187202Y610700D01*
G01X183856Y599500D02*
Y604499D01*
G01X207281Y617610D02*
Y617633D01*
X206581Y610300D01*
G01X203935Y599500D02*
Y604499D01*
G01X230707Y617610D02*
X230706D01*
Y613708D01*
X231224Y613190D01*
Y612310D01*
X230706Y611792D01*
Y610700D01*
G01X227360Y599500D02*
Y604499D01*
G01X200588Y617610D02*
Y612392D01*
X200202Y610300D01*
G01X197242Y599500D02*
Y604499D01*
G01X224014Y617610D02*
Y613800D01*
X224534Y613280D01*
Y612420D01*
X224014Y611900D01*
Y610701D01*
X224013Y610700D01*
G01X220667Y599500D02*
Y604499D01*
G01X170470Y617610D02*
Y617633D01*
X169770Y610300D01*
G01X177163Y599500D02*
Y602096D01*
X175517Y603742D01*
Y605400D01*
X176249Y606132D01*
Y607103D01*
X175257Y608095D01*
X174437D01*
X173692Y607350D01*
X173617D01*
G01X213974Y599500D02*
Y602096D01*
X212328Y603742D01*
Y605400D01*
X213060Y606132D01*
Y607103D01*
X212068Y608095D01*
X211248D01*
X210503Y607350D01*
X210428D01*
G01X177163Y617610D02*
Y613405D01*
X175592Y611834D01*
Y610268D01*
X176960Y608900D01*
X177842D01*
X178691Y609749D01*
G01X213974Y617610D02*
Y613405D01*
X212470Y611901D01*
Y610201D01*
X213771Y608900D01*
X214653D01*
X215502Y609749D01*
G01X173817Y599500D02*
Y601951D01*
X172100Y603668D01*
X171767Y604392D01*
Y607613D01*
X172088Y608496D01*
X173591Y609999D01*
G01X210628Y599500D02*
Y601951D01*
X208911Y603668D01*
X208578Y604392D01*
Y607613D01*
X208899Y608496D01*
X210402Y609999D01*
G01X180510Y617610D02*
Y613649D01*
X180659Y613500D01*
Y608100D01*
X179699Y607140D01*
X178691D01*
G01X217321Y617610D02*
Y613649D01*
X217470Y613500D01*
Y608100D01*
X216510Y607140D01*
X215502D01*
G01X240746Y22923D02*
Y27899D01*
G01X264171Y22923D02*
Y27899D01*
G01X234053Y22923D02*
Y27899D01*
G01X257478Y22923D02*
Y27899D01*
G01X250785Y22923D02*
Y26240D01*
X249139Y27886D01*
Y28800D01*
X249871Y29532D01*
Y30503D01*
X248879Y31495D01*
X247984D01*
X247239Y30750D01*
G01X287596Y22923D02*
Y26240D01*
X285950Y27886D01*
Y28800D01*
X286682Y29532D01*
Y30503D01*
X285690Y31495D01*
X284795D01*
X284050Y30750D01*
G01X250785Y41033D02*
Y36805D01*
X249214Y35234D01*
Y33668D01*
X250582Y32300D01*
X251464D01*
X252313Y33149D01*
G01X287596Y41033D02*
Y36805D01*
X286025Y35234D01*
Y33668D01*
X287393Y32300D01*
X288275D01*
X289124Y33149D01*
G01X247439Y22923D02*
Y25351D01*
X245722Y27068D01*
X245389Y27792D01*
Y31013D01*
X245710Y31896D01*
X247213Y33399D01*
G01X284250Y22923D02*
Y25351D01*
X282533Y27068D01*
X282200Y27792D01*
Y31013D01*
X282521Y31896D01*
X284024Y33399D01*
G01X254132Y41033D02*
Y37049D01*
X254281Y36900D01*
Y31500D01*
X253321Y30540D01*
X252313D01*
G01X290943Y41033D02*
Y37049D01*
X291092Y36900D01*
Y31500D01*
X290132Y30540D01*
X289124D01*
G01X277557Y22923D02*
Y27899D01*
G01X270864Y22923D02*
Y27899D01*
G01X244092Y3233D02*
X243392Y-4100D01*
G01X240746Y-14877D02*
Y-9901D01*
G01X267518Y3233D02*
X267517Y3232D01*
Y-692D01*
X268035Y-1210D01*
Y-2090D01*
X267517Y-2608D01*
Y-3700D01*
G01X264171Y-14877D02*
Y-9901D01*
G01X237399Y3233D02*
Y-2008D01*
X237013Y-4100D01*
G01X234053Y-14877D02*
Y-9901D01*
G01X260825Y3233D02*
Y-600D01*
X261345Y-1120D01*
Y-1980D01*
X260825Y-2500D01*
Y-3699D01*
X260824Y-3700D01*
G01X257478Y-14877D02*
Y-9901D01*
G01X250785Y-14877D02*
Y-11560D01*
X249139Y-9914D01*
Y-9000D01*
X249871Y-8268D01*
Y-7297D01*
X248879Y-6305D01*
X248059D01*
X247314Y-7050D01*
X247239D01*
G01X287596Y-14877D02*
Y-11560D01*
X285950Y-9914D01*
Y-9000D01*
X286682Y-8268D01*
Y-7297D01*
X285690Y-6305D01*
X284870D01*
X284125Y-7050D01*
X284050D01*
G01X250785Y3233D02*
Y-755D01*
X249739Y-1801D01*
Y-4686D01*
X252313Y-7260D01*
G01X287596Y3233D02*
Y-755D01*
X286550Y-1801D01*
Y-4686D01*
X289124Y-7260D01*
G01X247439Y-14877D02*
Y-12449D01*
X245722Y-10732D01*
X245389Y-10008D01*
Y-6787D01*
X245710Y-5904D01*
X247213Y-4401D01*
G01X284250Y-14877D02*
Y-12449D01*
X282533Y-10732D01*
X282200Y-10008D01*
Y-6787D01*
X282521Y-5904D01*
X284024Y-4401D01*
G01X254132Y3233D02*
Y-1093D01*
X255004Y-1965D01*
Y-4887D01*
X254162Y-5729D01*
X253391D01*
X252313Y-4651D01*
G01X290943Y3233D02*
X290942Y3232D01*
Y-1092D01*
X291815Y-1965D01*
Y-4887D01*
X290973Y-5729D01*
X290202D01*
X289124Y-4651D01*
G01X280903Y3233D02*
X280203Y-4100D01*
G01X277557Y-14877D02*
Y-9901D01*
G01X274210Y3233D02*
Y-2008D01*
X273824Y-4100D01*
G01X270864Y-14877D02*
Y-9901D01*
G01X244092Y78833D02*
X243774Y75500D01*
X243392Y71500D01*
G01X240746Y60723D02*
Y65699D01*
G01X267518Y78833D02*
X267517Y78832D01*
Y74908D01*
X268035Y74390D01*
Y73510D01*
X267517Y72992D01*
Y71900D01*
G01X264171Y60723D02*
Y65699D01*
G01X237399Y78833D02*
Y73592D01*
X237013Y71500D01*
G01X234053Y60723D02*
Y65699D01*
G01X260825Y78833D02*
Y75000D01*
X261345Y74480D01*
Y73620D01*
X260825Y73100D01*
Y71901D01*
X260824Y71900D01*
G01X257478Y60723D02*
Y65699D01*
G01X250785Y60723D02*
Y63296D01*
X249139Y64942D01*
Y66600D01*
X249871Y67332D01*
Y68303D01*
X248879Y69295D01*
X248059D01*
X247314Y68550D01*
X247239D01*
G01X287596Y60723D02*
Y63296D01*
X285950Y64942D01*
Y66600D01*
X286682Y67332D01*
Y68303D01*
X285690Y69295D01*
X284870D01*
X284125Y68550D01*
X284050D01*
G01X250785Y78833D02*
Y74605D01*
X249281Y73101D01*
Y71401D01*
X250582Y70100D01*
X251464D01*
X252313Y70949D01*
G01X287596Y78833D02*
Y74605D01*
X286092Y73101D01*
Y71401D01*
X287393Y70100D01*
X288275D01*
X289124Y70949D01*
G01X247439Y60723D02*
Y63151D01*
X245722Y64868D01*
X245389Y65592D01*
Y68813D01*
X245710Y69696D01*
X247213Y71199D01*
G01X284250Y60723D02*
Y63151D01*
X282533Y64868D01*
X282200Y65592D01*
Y68813D01*
X282521Y69696D01*
X284024Y71199D01*
G01X254132Y78833D02*
Y74849D01*
X254281Y74700D01*
Y69300D01*
X253321Y68340D01*
X252313D01*
G01X290943Y78833D02*
Y74849D01*
X291092Y74700D01*
Y69300D01*
X290132Y68340D01*
X289124D01*
G01X280903Y78833D02*
X280585Y75500D01*
X280203Y71500D01*
G01X277557Y60723D02*
Y65699D01*
G01X274210Y78833D02*
Y73592D01*
X273824Y71500D01*
G01X270864Y60723D02*
Y65699D01*
G01X244092Y41033D02*
X243468Y34500D01*
X243392Y33700D01*
G01X267518Y41033D02*
X267517Y41032D01*
Y37108D01*
X268035Y36590D01*
Y35710D01*
X267517Y35192D01*
Y34100D01*
G01X237399Y41033D02*
Y35792D01*
X237161Y34500D01*
X237013Y33700D01*
G01X260825Y41033D02*
Y37200D01*
X261345Y36680D01*
Y35820D01*
X260825Y35300D01*
Y34101D01*
X260824Y34100D01*
G01X280903Y41033D02*
X280279Y34500D01*
X280203Y33700D01*
G01X274210Y41033D02*
Y35792D01*
X273972Y34500D01*
X273824Y33700D01*
G01X239892Y135000D02*
Y132691D01*
X239242Y132041D01*
X237842D01*
X237192Y131391D01*
Y130041D01*
X237842Y129391D01*
X239242D01*
X239892Y128741D01*
Y127391D01*
X239242Y126741D01*
X237842D01*
X237192Y126091D01*
Y124741D01*
X237842Y124091D01*
X239242D01*
X239892Y123441D01*
Y122091D01*
X239242Y121441D01*
X237842D01*
X237192Y120791D01*
Y119441D01*
X237842Y118791D01*
X239242D01*
X239892Y118141D01*
Y113181D01*
X240746Y112327D01*
G01X258630Y186261D02*
X258629D01*
X239202Y166834D01*
Y150641D01*
X239892Y149951D01*
Y135000D01*
G01X242592Y142000D02*
Y148101D01*
X245742Y151251D01*
Y152678D01*
X245092Y153328D01*
X244242D01*
X243592Y153978D01*
Y155328D01*
X244242Y155978D01*
X245092D01*
X245742Y156628D01*
Y157978D01*
X245092Y158628D01*
X242642D01*
X241992Y159278D01*
Y160628D01*
X242642Y161278D01*
X245092D01*
X245742Y161928D01*
Y169757D01*
X260438Y184453D01*
G01X243392Y106934D02*
X240416D01*
X239766Y107584D01*
Y108674D01*
X242592Y111500D01*
Y142000D01*
G01X267186Y141000D02*
Y169877D01*
X271099Y173790D01*
G01X264171Y112327D02*
X261892Y114606D01*
Y116689D01*
X262582Y117379D01*
Y120069D01*
X261892Y120759D01*
Y135450D01*
X262542Y136100D01*
X263932D01*
X264582Y135450D01*
Y128490D01*
X265172Y127900D01*
X266482D01*
X267186Y128604D01*
Y141000D01*
G01X270504Y136000D02*
Y140900D01*
X270483Y140921D01*
Y141655D01*
X271133Y142305D01*
X272542D01*
X273192Y142955D01*
Y144305D01*
X272542Y144955D01*
X271133D01*
X270483Y145605D01*
Y146955D01*
X271133Y147605D01*
X272542D01*
X273192Y148255D01*
Y149605D01*
X272542Y150255D01*
X271133D01*
X270483Y150905D01*
Y152255D01*
X271133Y152905D01*
X272542D01*
X273192Y153555D01*
Y154905D01*
X272542Y155555D01*
X271133D01*
X270483Y156205D01*
Y157555D01*
X271133Y158205D01*
X271242D01*
X271892Y158855D01*
Y160205D01*
X271242Y160855D01*
X271133D01*
X270483Y161505D01*
Y169566D01*
X272903Y171986D01*
G01X267517Y107284D02*
X265192Y109609D01*
Y110200D01*
X265992Y111000D01*
Y121601D01*
X270504Y126113D01*
Y136000D01*
G01X234192Y134000D02*
Y137800D01*
X236492Y140100D01*
Y167700D01*
X256792Y188000D01*
G01X237099Y107284D02*
X237067D01*
X235192Y109159D01*
Y110800D01*
X235878Y111486D01*
Y114364D01*
X234192Y116050D01*
Y134000D01*
G01X257478Y112327D02*
X256492Y113313D01*
Y117446D01*
X255802Y118136D01*
X255782D01*
X255092Y118826D01*
Y120136D01*
X255782Y120826D01*
X255802D01*
X256492Y121516D01*
Y122826D01*
X255802Y123516D01*
X255782D01*
X255092Y124206D01*
Y125516D01*
X255782Y126206D01*
X255802D01*
X256492Y126896D01*
Y130000D01*
G01D02*
Y163350D01*
X256992Y163850D01*
X258682D01*
X259182Y163350D01*
Y155600D01*
X259682Y155100D01*
X261372D01*
X261872Y155600D01*
Y171787D01*
X267487Y177402D01*
G01X259149Y140500D02*
Y146860D01*
X259839Y147550D01*
X261149D01*
X261839Y146860D01*
Y144650D01*
X262489Y144000D01*
X263879D01*
X264529Y144650D01*
Y170836D01*
X269291Y175598D01*
G01X260824Y107284D02*
X258992Y109116D01*
Y111143D01*
X259692Y111843D01*
Y113557D01*
X259149Y114100D01*
Y140500D01*
G01X249872Y141500D02*
Y140120D01*
X248497Y138745D01*
X247144D01*
X246442Y138043D01*
Y135957D01*
X247144Y135255D01*
X248619D01*
X249942Y133932D01*
Y130788D01*
X248619Y129465D01*
X247144D01*
X246442Y128763D01*
Y127550D01*
X246962Y127030D01*
Y126030D01*
X246442Y125510D01*
Y124550D01*
X246962Y124030D01*
Y123030D01*
X246442Y122510D01*
Y121550D01*
X246962Y121030D01*
Y120030D01*
X246442Y119510D01*
Y118550D01*
X246962Y118030D01*
Y117030D01*
X246442Y116510D01*
Y115550D01*
X246892Y115100D01*
X248245D01*
X249008Y114337D01*
Y111277D01*
X248245Y110514D01*
X247213D01*
G01X263043Y181816D02*
X249842Y168615D01*
Y149708D01*
X246742Y146608D01*
Y145185D01*
X247392Y144535D01*
X248497D01*
X249872Y143160D01*
Y141500D01*
G01X298849Y169612D02*
X295236Y165999D01*
Y165291D01*
X294528Y164584D01*
X293821D01*
X293114Y163877D01*
Y163169D01*
X292406Y162462D01*
X291699D01*
X290992Y161755D01*
Y160755D01*
X291492Y160255D01*
Y159255D01*
X290992Y158755D01*
Y157400D01*
X291492Y156900D01*
Y155900D01*
X290992Y155400D01*
Y154400D01*
X291492Y153900D01*
Y152900D01*
X290992Y152400D01*
Y151000D01*
X291492Y150500D01*
Y149500D01*
X290992Y149000D01*
Y147900D01*
X291492Y147400D01*
Y146400D01*
X290992Y145900D01*
Y144366D01*
X292058Y143300D01*
X294303D01*
X295692Y141911D01*
Y137963D01*
X294369Y136640D01*
X292442D01*
X291942Y136140D01*
Y134490D01*
X292442Y133990D01*
X294369D01*
X295692Y132667D01*
Y129322D01*
X294231Y127861D01*
Y127153D01*
X293523Y126446D01*
X292816D01*
X292109Y125739D01*
Y125031D01*
X291401Y124324D01*
X290694D01*
X289987Y123617D01*
Y122909D01*
X289279Y122202D01*
X288572D01*
X287865Y121495D01*
Y120787D01*
X287157Y120080D01*
X286450D01*
X285743Y119373D01*
Y118665D01*
X285035Y117958D01*
X284328D01*
X283621Y117251D01*
Y115801D01*
X284422Y115000D01*
X284792D01*
X285819Y113973D01*
Y111077D01*
X285256Y110514D01*
X284024D01*
G01X252612Y135500D02*
Y129476D01*
X250492Y127356D01*
Y114480D01*
X250544Y114428D01*
Y109424D01*
X252313Y107655D01*
G01X264856Y180014D02*
X252612Y167770D01*
Y135500D01*
G01X300576Y167679D02*
X297792Y164895D01*
Y162094D01*
X295892Y160194D01*
Y148986D01*
X297792Y147086D01*
Y143700D01*
X298392Y143100D01*
Y127500D01*
X295372Y124480D01*
Y123748D01*
X293087Y121463D01*
X292355D01*
X287355Y116463D01*
Y109424D01*
X289124Y107655D01*
G01X247239Y107865D02*
X245292Y109812D01*
Y125500D01*
G01D02*
Y129240D01*
X246667Y130615D01*
X248142D01*
X248792Y131265D01*
Y133455D01*
X248142Y134105D01*
X246667D01*
X245292Y135480D01*
Y138520D01*
X246667Y139895D01*
X248020D01*
X248722Y140597D01*
Y142683D01*
X248020Y143385D01*
X246915D01*
X245592Y144708D01*
Y147085D01*
X248692Y150185D01*
Y169092D01*
X262230Y182630D01*
G01X298036Y170426D02*
X289842Y162232D01*
Y143889D01*
X291581Y142150D01*
X293826D01*
X294542Y141434D01*
Y138440D01*
X293892Y137790D01*
X291965D01*
X290792Y136617D01*
Y134013D01*
X291965Y132840D01*
X293892D01*
X294542Y132190D01*
Y129799D01*
X282471Y117728D01*
Y115324D01*
X282583Y115212D01*
Y114292D01*
X282192Y113901D01*
Y109723D01*
X284050Y107865D01*
G01X252339Y110264D02*
X253419D01*
X254192Y111037D01*
Y113900D01*
X253292Y114800D01*
X252192D01*
X251642Y115350D01*
Y116310D01*
X252162Y116830D01*
Y117830D01*
X251642Y118350D01*
Y119310D01*
X252162Y119830D01*
Y120830D01*
X251642Y121350D01*
Y123500D01*
G01D02*
Y126879D01*
X253762Y128999D01*
Y167293D01*
X265669Y179200D01*
G01X301390Y166865D02*
X298942Y164417D01*
Y161617D01*
X297042Y159717D01*
Y158717D01*
X297542Y158217D01*
Y157217D01*
X297042Y156717D01*
Y155717D01*
X297542Y155217D01*
Y154217D01*
X297042Y153717D01*
Y152717D01*
X297542Y152217D01*
Y151217D01*
X297042Y150717D01*
Y149463D01*
X298942Y147563D01*
Y144177D01*
X299542Y143577D01*
Y142577D01*
X300042Y142077D01*
Y141077D01*
X299542Y140577D01*
Y139577D01*
X300042Y139077D01*
Y138077D01*
X299542Y137577D01*
Y136577D01*
X300042Y136077D01*
Y135077D01*
X299542Y134577D01*
Y133537D01*
X299941Y133138D01*
Y132138D01*
X299542Y131739D01*
Y127023D01*
X296522Y124003D01*
Y123271D01*
X293564Y120313D01*
X292832D01*
X289892Y117373D01*
Y114800D01*
X291992Y112700D01*
Y110900D01*
X291356Y110264D01*
X289150D01*
G01X294618Y174222D02*
X284592Y164196D01*
Y153893D01*
X283942Y153243D01*
X282742D01*
X282092Y152593D01*
Y151243D01*
X282742Y150593D01*
X283942D01*
X284592Y149943D01*
Y148593D01*
X283942Y147943D01*
X282742D01*
X282092Y147293D01*
Y145943D01*
X282742Y145293D01*
X283942D01*
X284592Y144643D01*
Y143293D01*
X283942Y142643D01*
X282742D01*
X282092Y141993D01*
Y140643D01*
X282742Y139993D01*
X283942D01*
X284592Y139343D01*
Y137993D01*
X283942Y137343D01*
X282742D01*
X282092Y136693D01*
Y135343D01*
X282742Y134693D01*
X283942D01*
X284592Y134043D01*
Y132693D01*
X283942Y132043D01*
X282742D01*
X282092Y131393D01*
Y130043D01*
X282742Y129393D01*
X283942D01*
X284592Y128743D01*
Y127549D01*
X276792Y119749D01*
Y113092D01*
X277557Y112327D01*
G01X296326Y172323D02*
X287292Y163289D01*
Y142250D01*
X288242Y141300D01*
Y139150D01*
X287292Y138200D01*
Y130950D01*
X288842Y129400D01*
Y127901D01*
X279492Y118551D01*
Y111500D01*
X278292Y110300D01*
X277192D01*
X275892Y109000D01*
Y106400D01*
X275292Y105800D01*
Y103000D01*
X275992Y102300D01*
X279552D01*
X280203Y102951D01*
Y106934D01*
G01X290975Y177992D02*
X281883Y168900D01*
X280785D01*
X279513Y170172D01*
X278415D01*
X277639Y169396D01*
Y168298D01*
X278911Y167026D01*
Y165928D01*
X276692Y163709D01*
Y140465D01*
X275916Y139689D01*
X274818D01*
X274042Y138913D01*
Y137815D01*
X274818Y137039D01*
X275916D01*
X276692Y136263D01*
Y135165D01*
X275916Y134389D01*
X274818D01*
X274042Y133613D01*
Y132515D01*
X274818Y131739D01*
X275916D01*
X276692Y130963D01*
Y127449D01*
X270864Y121621D01*
Y112327D01*
G01X292823Y176233D02*
X279492Y162902D01*
Y126351D01*
X274092Y120951D01*
Y112700D01*
X271019Y109627D01*
Y107934D01*
X271669Y107284D01*
X273910D01*
G01X273489Y261760D02*
X271239D01*
G01X273489Y335860D02*
X271239D01*
G01X266729D02*
X264179D01*
G01X273489Y331960D02*
X271239D01*
G01X266729D02*
X264179D01*
G01X273489Y339760D02*
X271239D01*
G01X270109Y337809D02*
X267859D01*
G01X290389Y333909D02*
X288139D01*
G01X283629Y330009D02*
X281379D01*
G01X280249Y339760D02*
X277999D01*
G01X290389Y330009D02*
X288139D01*
G01X287009Y328060D02*
X284759D01*
G01X287009Y339760D02*
X284759D01*
G01X280249Y335860D02*
X277999D01*
G01X280249Y331960D02*
X277999D01*
G01X287009Y335860D02*
X284759D01*
G01X283629Y333909D02*
X281379D01*
G01X290389Y337809D02*
X288139D01*
G01X290389Y372909D02*
X288139D01*
G01X283629Y369010D02*
X281379D01*
G01X283629Y380709D02*
X281379D01*
G01X280249Y378760D02*
X277999D01*
G01X290389Y369010D02*
X288139D01*
G01X287009Y367060D02*
X284759D01*
G01X287009Y378760D02*
X284759D01*
G01X280249Y374860D02*
X277999D01*
G01X266729Y351460D02*
X264179D01*
G01X273489D02*
X271239D01*
G01X266729Y347560D02*
X264179D01*
G01X273489D02*
X271239D01*
G01X273489Y343660D02*
X271239D01*
G01X287009Y374860D02*
X284759D01*
G01X280249Y370959D02*
X277999D01*
G01X270109Y345609D02*
X267859D01*
G01X290389Y376809D02*
X288139D01*
G01X283629Y372909D02*
X281379D01*
G01X287009Y359260D02*
X284759D01*
G01X283629Y361209D02*
X281379D01*
G01X290389Y349509D02*
X288139D01*
G01X287009Y347560D02*
X284759D01*
G01X280249Y355360D02*
X277999D01*
G01X280249Y359260D02*
X277999D01*
G01X287009Y386560D02*
X284759D01*
G01X287009Y394359D02*
X284759D01*
G01X283629Y388509D02*
X281379D01*
G01X283629Y392410D02*
X281379D01*
G01X293769Y386560D02*
X291519D01*
G01X293769Y394359D02*
X291519D01*
G01X283629Y341709D02*
X281379D01*
G01X290389Y353409D02*
X288139D01*
G01X283629Y349509D02*
X281379D01*
G01X287009Y355360D02*
X284759D01*
G01X290389Y388509D02*
X288139D01*
G01X280249Y351460D02*
X277999D01*
G01X290389Y396309D02*
X288139D01*
G01X290389Y357309D02*
X288139D01*
G01X290389Y384609D02*
X288139D01*
G01X283629Y353409D02*
X281379D01*
G01X290389Y392410D02*
X288139D01*
G01X281235Y407449D02*
X269788D01*
X240909Y436328D01*
X238692Y441679D01*
Y446703D01*
X239342Y447353D01*
X239842D01*
X240492Y448003D01*
Y449303D01*
X239842Y449953D01*
X239342D01*
X238692Y450603D01*
Y451903D01*
X239342Y452553D01*
X239842D01*
X240492Y453203D01*
Y454503D01*
X239842Y455153D01*
X239342D01*
X238692Y455803D01*
Y457103D01*
X239342Y457753D01*
X239842D01*
X240492Y458403D01*
Y459703D01*
X239842Y460353D01*
X239342D01*
X238692Y461003D01*
Y462303D01*
X239342Y462953D01*
X240068D01*
X240744Y463629D01*
Y464929D01*
X240120Y465553D01*
X239342D01*
X238692Y466203D01*
Y495000D01*
X239592Y495900D01*
G01X243392Y495694D02*
X244814D01*
X245392Y495116D01*
Y491788D01*
X244892Y491288D01*
X241978D01*
X241378Y490688D01*
Y489238D01*
X241878Y488738D01*
X242792D01*
X243432Y488098D01*
Y486698D01*
X242932Y486198D01*
X241892D01*
X241292Y485598D01*
Y484141D01*
X241865Y483568D01*
X242743D01*
X243443Y482868D01*
Y481568D01*
X242843Y480968D01*
X241865D01*
X241215Y480318D01*
Y479018D01*
X241865Y478368D01*
X242819D01*
X243469Y477718D01*
Y476418D01*
X242819Y475768D01*
X241866D01*
X241216Y475118D01*
Y473818D01*
X241866Y473168D01*
X242818D01*
X243468Y472518D01*
Y471218D01*
X242818Y470568D01*
X241866D01*
X241216Y469918D01*
Y468618D01*
X241866Y467968D01*
X242642D01*
X243292Y467318D01*
Y457686D01*
X242576Y456970D01*
Y455964D01*
X243292Y455248D01*
Y445108D01*
X242642Y444458D01*
X241864D01*
X241214Y443808D01*
Y442458D01*
X241864Y441808D01*
X242642D01*
X243292Y441158D01*
Y437509D01*
X270802Y409999D01*
X281235D01*
G01X284548Y425049D02*
X281094D01*
X263453Y442690D01*
Y447614D01*
X264242Y448403D01*
X265542D01*
X266192Y449053D01*
Y450353D01*
X265542Y451003D01*
X264142D01*
X263492Y451653D01*
Y452953D01*
X264142Y453603D01*
X265942D01*
X266592Y454253D01*
Y455553D01*
X265942Y456203D01*
X264142D01*
X263492Y456853D01*
Y458153D01*
X264142Y458803D01*
X265942D01*
X266592Y459453D01*
Y460753D01*
X265942Y461403D01*
X264142D01*
X263327Y462218D01*
Y486335D01*
X265292Y488300D01*
Y492700D01*
X265692Y493100D01*
Y494800D01*
X267392Y496500D01*
Y498500D01*
X266492Y499400D01*
X265084D01*
X264171Y498487D01*
G01X267584Y493919D02*
X267865Y494200D01*
X268992D01*
X269492Y493700D01*
Y488350D01*
X268992Y487850D01*
X268286D01*
X267492Y487056D01*
Y485651D01*
X268159Y484984D01*
X268892D01*
X269492Y484384D01*
Y483084D01*
X268792Y482384D01*
X266392D01*
X265892Y481884D01*
Y480431D01*
X266542Y479781D01*
X268842D01*
X269492Y479131D01*
Y477781D01*
X268842Y477131D01*
X266542D01*
X265892Y476481D01*
Y475131D01*
X266542Y474481D01*
X268842D01*
X269492Y473831D01*
Y472481D01*
X268842Y471831D01*
X266542D01*
X265892Y471181D01*
Y469831D01*
X266542Y469181D01*
X268842D01*
X269492Y468531D01*
Y467181D01*
X268842Y466531D01*
X266542D01*
X265892Y465881D01*
Y464400D01*
X266392Y463900D01*
X268691D01*
X269492Y463099D01*
Y459000D01*
X268892Y458400D01*
Y456800D01*
X269492Y456200D01*
Y452939D01*
X268792Y452239D01*
Y449699D01*
X269492Y448999D01*
Y446268D01*
X268842Y445618D01*
X266902D01*
X266252Y444968D01*
Y443618D01*
X266902Y442968D01*
X268842D01*
X269492Y442318D01*
Y440350D01*
X282243Y427599D01*
X283848D01*
G01X280174Y404899D02*
X267671D01*
X239489Y433081D01*
X234092Y446111D01*
Y448400D01*
X235992Y450300D01*
Y453000D01*
X234092Y454900D01*
Y456500D01*
X236171Y458579D01*
Y460021D01*
X234092Y462100D01*
Y463700D01*
X236171Y465779D01*
Y467121D01*
X234092Y469200D01*
Y470700D01*
X236171Y472779D01*
Y473921D01*
X234092Y476000D01*
Y477600D01*
X235792Y479300D01*
Y480601D01*
X234092Y482301D01*
Y484001D01*
X235492Y485401D01*
Y489400D01*
X236892Y490800D01*
G01X257478Y498487D02*
X259392Y496573D01*
Y495100D01*
X258992Y494700D01*
Y489200D01*
X255892Y486100D01*
Y475547D01*
X253595Y473250D01*
Y464649D01*
X256045Y462199D01*
X257229D01*
X258058Y461370D01*
Y455282D01*
X257428Y454652D01*
X256755D01*
X256204Y454101D01*
Y452462D01*
X256704Y451962D01*
X257428D01*
X257928Y451462D01*
Y448286D01*
X257238Y447596D01*
X255878D01*
X255175Y446893D01*
Y445583D01*
X255852Y444906D01*
X257238D01*
X258032Y444112D01*
Y440709D01*
X278792Y419949D01*
X286241D01*
G01X260824Y493744D02*
X262192D01*
X262692Y493244D01*
Y489300D01*
X260585Y487193D01*
Y484376D01*
X259895Y483686D01*
X259182D01*
X258492Y482996D01*
Y481686D01*
X259182Y480996D01*
X260123D01*
X260787Y480332D01*
Y479022D01*
X260071Y478306D01*
X259182D01*
X258492Y477616D01*
Y476306D01*
X259182Y475616D01*
X260146D01*
X260785Y474977D01*
Y473667D01*
X260044Y472926D01*
X256881D01*
X256165Y472210D01*
Y470900D01*
X256829Y470236D01*
X260147D01*
X260787Y469596D01*
Y468148D01*
X260185Y467546D01*
X256906D01*
X256241Y466881D01*
Y465571D01*
X256956Y464856D01*
X259895D01*
X260585Y464166D01*
Y456259D01*
X261386Y455458D01*
Y454387D01*
X260585Y453586D01*
Y447359D01*
X259860Y446634D01*
Y445864D01*
X260585Y445139D01*
Y441758D01*
X279844Y422499D01*
X285148D01*
G01X286648Y413699D02*
X286647Y413700D01*
X273668D01*
X247162Y440206D01*
Y476401D01*
X247792Y477031D01*
Y482368D01*
X247162Y482998D01*
Y486171D01*
X250266Y489275D01*
Y492871D01*
X247228Y495909D01*
G01X306969Y427165D02*
X287266Y446868D01*
Y492848D01*
X284170Y495944D01*
X284039D01*
G01X252313Y493214D02*
X253286D01*
X254216Y492284D01*
Y489624D01*
X252042Y487450D01*
Y486350D01*
X251396Y485704D01*
Y484796D01*
X252042Y484150D01*
Y483150D01*
X251492Y482600D01*
Y481600D01*
X252042Y481050D01*
Y479850D01*
X251522Y479330D01*
Y478270D01*
X252042Y477750D01*
Y476906D01*
X249922Y474786D01*
Y460828D01*
X251297Y459453D01*
X253584D01*
X254101Y458936D01*
Y457215D01*
X253609Y456723D01*
X251297D01*
X249922Y455348D01*
Y453068D01*
X251297Y451693D01*
X252020D01*
X252722Y450991D01*
Y449665D01*
X252020Y448963D01*
X251505D01*
X250292Y447750D01*
Y446650D01*
X249792Y446150D01*
Y445050D01*
X250292Y444550D01*
Y442850D01*
X251921Y441221D01*
Y440514D01*
X252700Y439735D01*
X253407D01*
X254184Y438958D01*
Y438251D01*
X254963Y437472D01*
X255670D01*
X256447Y436695D01*
Y435988D01*
X257226Y435209D01*
X257933D01*
X258710Y434432D01*
Y433725D01*
X259489Y432946D01*
X260196D01*
X260973Y432169D01*
Y431462D01*
X261752Y430683D01*
X262459D01*
X263236Y429906D01*
Y429199D01*
X264015Y428420D01*
X264722D01*
X265499Y427643D01*
Y426936D01*
X266278Y426157D01*
X266985D01*
X267831Y425311D01*
Y424604D01*
X268610Y423825D01*
X269317D01*
X270094Y423048D01*
Y422341D01*
X270873Y421562D01*
X271580D01*
X272357Y420785D01*
Y420078D01*
X273136Y419299D01*
X273843D01*
X274620Y418522D01*
Y417815D01*
X275399Y417036D01*
X276106D01*
X276883Y416259D01*
X286648D01*
G01X308846Y429663D02*
X307050Y431459D01*
X306285D01*
X305578Y432166D01*
Y432931D01*
X304653Y433856D01*
X303889D01*
X303182Y434563D01*
Y435327D01*
X302475Y436034D01*
X301711D01*
X301004Y436741D01*
Y437505D01*
X300297Y438212D01*
X299533D01*
X298826Y438919D01*
Y439683D01*
X298119Y440390D01*
X297355D01*
X296648Y441097D01*
Y441861D01*
X295941Y442568D01*
X295177D01*
X294470Y443275D01*
Y444039D01*
X293763Y444746D01*
Y445677D01*
X293332Y446108D01*
Y447108D01*
X293763Y447539D01*
Y448615D01*
X293143Y449235D01*
Y450235D01*
X293763Y450855D01*
Y451855D01*
X293143Y452475D01*
Y453475D01*
X293763Y454095D01*
Y455095D01*
X293143Y455715D01*
Y456715D01*
X293763Y457335D01*
Y458335D01*
X293143Y458955D01*
Y459955D01*
X293763Y460575D01*
Y461583D01*
X293108Y462238D01*
X291381D01*
X290000Y463619D01*
Y466062D01*
X291367Y467429D01*
X293192D01*
X293842Y468079D01*
Y469379D01*
X293192Y470029D01*
X291254D01*
X289931Y471352D01*
Y473606D01*
X291116Y474791D01*
Y478361D01*
X290742Y478735D01*
Y479959D01*
X291116Y480333D01*
Y481400D01*
X290616Y481900D01*
Y482900D01*
X291116Y483400D01*
Y484400D01*
X290616Y484900D01*
Y485900D01*
X291116Y486400D01*
Y487400D01*
X290616Y487900D01*
Y488900D01*
X291116Y489400D01*
Y492325D01*
X290097Y493344D01*
X289124D01*
G01X286648Y412549D02*
X286171D01*
X286170Y412550D01*
X273191D01*
X272284Y413457D01*
X271577D01*
X270799Y414235D01*
Y414942D01*
X270022Y415719D01*
X269315D01*
X268536Y416498D01*
Y417205D01*
X246012Y439729D01*
Y476878D01*
X246642Y477508D01*
Y481891D01*
X246012Y482521D01*
Y486648D01*
X246650Y487286D01*
Y487804D01*
X247358Y488512D01*
X247876D01*
X249116Y489752D01*
Y492394D01*
X248301Y493209D01*
X247228D01*
G01X306192Y426314D02*
X286116Y446390D01*
Y478550D01*
X285666Y479000D01*
Y480000D01*
X286116Y480450D01*
Y481500D01*
X285616Y482000D01*
Y483000D01*
X286116Y483500D01*
Y484500D01*
X285616Y485000D01*
Y486000D01*
X286116Y486500D01*
Y487460D01*
X285596Y487980D01*
Y488980D01*
X286116Y489500D01*
Y492370D01*
X285111Y493375D01*
X284070D01*
X284039Y493344D01*
G01X252313Y495814D02*
X255366Y492761D01*
Y489147D01*
X253192Y486973D01*
Y476429D01*
X251072Y474309D01*
Y461305D01*
X251774Y460603D01*
X254061D01*
X255251Y459413D01*
Y456738D01*
X254086Y455573D01*
X251774D01*
X251072Y454871D01*
Y453545D01*
X251774Y452843D01*
X252497D01*
X253872Y451468D01*
Y449188D01*
X252497Y447813D01*
X251982D01*
X251442Y447273D01*
Y443327D01*
X277360Y417409D01*
X286648D01*
Y417399D01*
G01X309659Y430477D02*
X294913Y445223D01*
Y462060D01*
X293585Y463388D01*
X291858D01*
X291150Y464096D01*
Y465585D01*
X291844Y466279D01*
X293669D01*
X294992Y467602D01*
Y469856D01*
X293669Y471179D01*
X291731D01*
X291081Y471829D01*
Y473129D01*
X292266Y474314D01*
Y492802D01*
X289124Y495944D01*
G01X301992Y423258D02*
X280876Y444374D01*
Y445822D01*
X280226Y446472D01*
X279092D01*
X278592Y446972D01*
Y448622D01*
X279092Y449122D01*
X280226D01*
X280876Y449772D01*
Y459557D01*
X278092Y462341D01*
Y487300D01*
X278366Y487574D01*
Y493974D01*
X279392Y495000D01*
Y496809D01*
X277557Y498644D01*
G01X304588Y424312D02*
X283492Y445408D01*
Y461445D01*
X282842Y462095D01*
X282092D01*
X281592Y462595D01*
Y464245D01*
X282092Y464745D01*
X282992D01*
X283567Y465320D01*
Y466670D01*
X282842Y467395D01*
X281476D01*
X280826Y468045D01*
Y469395D01*
X281476Y470045D01*
X282968D01*
X283593Y470670D01*
Y472020D01*
X282918Y472695D01*
X281476D01*
X280826Y473345D01*
Y474695D01*
X281476Y475345D01*
X282842D01*
X283492Y475995D01*
Y477716D01*
X282566Y478642D01*
X281502D01*
X280852Y479292D01*
Y480642D01*
X281502Y481292D01*
X282370D01*
X283020Y481942D01*
Y483292D01*
X282370Y483942D01*
X281502D01*
X280852Y484592D01*
Y485942D01*
X281502Y486592D01*
X282370D01*
X283020Y487242D01*
Y488804D01*
X282166Y489658D01*
Y491281D01*
X280203Y493244D01*
G01X299323Y418666D02*
X272816Y445173D01*
Y489776D01*
X272092Y490500D01*
Y494401D01*
X272892Y495201D01*
Y497599D01*
X271847Y498644D01*
X271092D01*
G01X300747Y420939D02*
X275566Y446120D01*
Y450658D01*
X276241Y451333D01*
X277579D01*
X278229Y451983D01*
Y453333D01*
X277579Y453983D01*
X276592D01*
X276092Y454483D01*
Y456133D01*
X276592Y456633D01*
X277579D01*
X278229Y457283D01*
Y458633D01*
X277579Y459283D01*
X276241D01*
X275566Y459958D01*
Y488374D01*
X275792Y488600D01*
Y492644D01*
X274692Y493744D01*
X273992D01*
G01X240746Y523900D02*
Y528899D01*
G01X264171Y523900D02*
Y528899D01*
G01X234053Y523900D02*
Y528899D01*
G01X257478Y523900D02*
Y528899D01*
G01X250785Y523900D02*
Y526496D01*
X249139Y528142D01*
Y529800D01*
X249871Y530532D01*
Y531503D01*
X248879Y532495D01*
X248059D01*
X247314Y531750D01*
X247239D01*
G01X287596Y523900D02*
Y526496D01*
X285950Y528142D01*
Y529800D01*
X286682Y530532D01*
Y531503D01*
X285690Y532495D01*
X284870D01*
X284125Y531750D01*
X284050D01*
G01X247439Y523900D02*
Y526351D01*
X245722Y528068D01*
X245473Y528610D01*
X245389Y528792D01*
Y532013D01*
X245710Y532896D01*
X247213Y534399D01*
G01X284250Y523900D02*
Y526351D01*
X282533Y528068D01*
X282284Y528610D01*
X282200Y528792D01*
Y532013D01*
X282521Y532896D01*
X284024Y534399D01*
G01X277557Y523900D02*
Y528899D01*
G01X270864Y523900D02*
Y528899D01*
G01X244092Y542010D02*
Y542033D01*
X243392Y534700D01*
G01X267518Y542010D02*
X267517D01*
Y538108D01*
X268035Y537590D01*
Y536710D01*
X267517Y536192D01*
Y535100D01*
G01X237399Y542010D02*
Y536792D01*
X237013Y534700D01*
G01X260825Y542010D02*
Y538200D01*
X261345Y537680D01*
Y536820D01*
X260825Y536300D01*
Y535101D01*
X260824Y535100D01*
G01X250785Y542010D02*
Y537805D01*
X249281Y536301D01*
Y534601D01*
X250582Y533300D01*
X251464D01*
X252313Y534149D01*
G01X287596Y542010D02*
Y537805D01*
X286092Y536301D01*
Y534601D01*
X287393Y533300D01*
X288275D01*
X289124Y534149D01*
G01X254132Y542010D02*
Y538049D01*
X254281Y537900D01*
Y532500D01*
X253321Y531540D01*
X252313D01*
G01X290943Y542010D02*
Y538049D01*
X291092Y537900D01*
Y532500D01*
X290132Y531540D01*
X289124D01*
G01X280903Y542010D02*
Y542033D01*
X280203Y534700D01*
G01X274210Y542010D02*
Y536792D01*
X273824Y534700D01*
G01X244092Y579810D02*
Y579833D01*
X243392Y572500D01*
G01X240746Y561700D02*
Y566699D01*
G01X267518Y579810D02*
X267517D01*
Y575908D01*
X268035Y575390D01*
Y574510D01*
X267517Y573992D01*
Y572900D01*
G01X264171Y561700D02*
Y566699D01*
G01X237399Y579810D02*
Y574592D01*
X237013Y572500D01*
G01X234053Y561700D02*
Y566699D01*
G01X260825Y579810D02*
Y576000D01*
X261345Y575480D01*
Y574620D01*
X260825Y574100D01*
Y572901D01*
X260824Y572900D01*
G01X257478Y561700D02*
Y566699D01*
G01X250785Y561700D02*
Y564296D01*
X249139Y565942D01*
Y567600D01*
X249871Y568332D01*
Y569303D01*
X248879Y570295D01*
X248059D01*
X247314Y569550D01*
X247239D01*
G01X287596Y561700D02*
Y564296D01*
X285950Y565942D01*
Y567600D01*
X286682Y568332D01*
Y569303D01*
X285690Y570295D01*
X284870D01*
X284125Y569550D01*
X284050D01*
G01X250785Y579810D02*
Y575605D01*
X249281Y574101D01*
Y572401D01*
X250582Y571100D01*
X251464D01*
X252313Y571949D01*
G01X287596Y579810D02*
Y575605D01*
X286092Y574101D01*
Y572401D01*
X287393Y571100D01*
X288275D01*
X289124Y571949D01*
G01X247439Y561700D02*
Y564151D01*
X245722Y565868D01*
X245389Y566592D01*
Y569813D01*
X245710Y570696D01*
X247213Y572199D01*
G01X284250Y561700D02*
Y564151D01*
X282533Y565868D01*
X282200Y566592D01*
Y569813D01*
X282521Y570696D01*
X284024Y572199D01*
G01X254132Y579810D02*
Y575849D01*
X254281Y575700D01*
Y570300D01*
X253321Y569340D01*
X252313D01*
G01X290943Y579810D02*
Y575849D01*
X291092Y575700D01*
Y570300D01*
X290132Y569340D01*
X289124D01*
G01X280903Y579810D02*
Y579833D01*
X280203Y572500D01*
G01X277557Y561700D02*
Y566699D01*
G01X274210Y579810D02*
Y574592D01*
X273824Y572500D01*
G01X270864Y561700D02*
Y566699D01*
G01X244092Y617610D02*
Y617633D01*
X243392Y610300D01*
G01X240746Y599500D02*
Y604499D01*
G01X267518Y617610D02*
X267517D01*
Y613708D01*
X268035Y613190D01*
Y612310D01*
X267517Y611792D01*
Y610700D01*
G01X264171Y599500D02*
Y604499D01*
G01X237399Y617610D02*
Y612392D01*
X237013Y610300D01*
G01X234053Y599500D02*
Y604499D01*
G01X260825Y617610D02*
Y613800D01*
X261345Y613280D01*
Y612420D01*
X260825Y611900D01*
Y610701D01*
X260824Y610700D01*
G01X257478Y599500D02*
Y604499D01*
G01X250785Y599500D02*
Y602096D01*
X249139Y603742D01*
Y605400D01*
X249871Y606132D01*
Y607103D01*
X248879Y608095D01*
X248059D01*
X247314Y607350D01*
X247239D01*
G01X287596Y599500D02*
Y602096D01*
X285950Y603742D01*
Y605400D01*
X286682Y606132D01*
Y607103D01*
X285690Y608095D01*
X284870D01*
X284125Y607350D01*
X284050D01*
G01X250785Y617610D02*
Y613405D01*
X249281Y611901D01*
Y610201D01*
X250582Y608900D01*
X251464D01*
X252313Y609749D01*
G01X287596Y617610D02*
Y613405D01*
X286092Y611901D01*
Y610201D01*
X287393Y608900D01*
X288275D01*
X289124Y609749D01*
G01X247439Y599500D02*
Y601951D01*
X245722Y603668D01*
X245389Y604392D01*
Y607613D01*
X245710Y608496D01*
X247213Y609999D01*
G01X284250Y599500D02*
Y601951D01*
X282533Y603668D01*
X282200Y604392D01*
Y607613D01*
X282521Y608496D01*
X284024Y609999D01*
G01X254132Y617610D02*
Y613649D01*
X254281Y613500D01*
Y608100D01*
X253321Y607140D01*
X252313D01*
G01X290943Y617610D02*
Y613649D01*
X291092Y613500D01*
Y608100D01*
X290132Y607140D01*
X289124D01*
G01X280903Y617610D02*
Y617633D01*
X280203Y610300D01*
G01X277557Y599500D02*
Y604499D01*
G01X274210Y617610D02*
Y612392D01*
X273824Y610300D01*
G01X270864Y599500D02*
Y604499D01*
G01X321061Y22923D02*
Y28014D01*
G01X324407Y22923D02*
Y28014D01*
G01X314368Y22923D02*
Y28014D01*
G01X300982Y22923D02*
Y27899D01*
G01X294289Y22923D02*
Y27899D01*
G01X331100Y28014D02*
Y22923D01*
G01X354525Y28022D02*
Y22923D01*
G01X351179Y28022D02*
Y22923D01*
G01X344486D02*
Y28022D01*
G01X341140D02*
Y22923D01*
G01X334447D02*
Y28013D01*
X334446Y28014D01*
G01X321061Y-14877D02*
Y-7108D01*
G01X327754Y3233D02*
Y-1743D01*
G01X324407Y-14877D02*
Y-9901D01*
G01Y3233D02*
Y-4536D01*
G01X314368Y-14877D02*
Y-7108D01*
G01X311021Y3233D02*
Y-4536D01*
G01X304329Y3233D02*
X304328Y3232D01*
Y-692D01*
X304846Y-1210D01*
Y-2090D01*
X304328Y-2608D01*
Y-3700D01*
G01X300982Y-14877D02*
Y-9901D01*
G01X297636Y3233D02*
Y-600D01*
X298156Y-1120D01*
Y-1980D01*
X297636Y-2500D01*
Y-3699D01*
X297635Y-3700D01*
G01X294289Y-14877D02*
Y-9901D01*
G01X334447Y3233D02*
Y-1743D01*
G01X331100Y-14877D02*
Y-9786D01*
G01X354525Y-14877D02*
X354526Y-14876D01*
Y-7108D01*
G01X354525Y3233D02*
Y-1742D01*
G01X351179Y-14877D02*
Y-9901D01*
G01X347833Y3233D02*
Y-1743D01*
G01X344486Y3233D02*
Y-4536D01*
G01Y-14877D02*
Y-9786D01*
G01X337793Y3233D02*
Y-4536D01*
G01X341140Y-14877D02*
Y-7108D01*
G01X334447Y-14877D02*
Y-7108D01*
G01X321061Y92757D02*
Y96269D01*
X323792Y99000D01*
X325892D01*
X331592Y104700D01*
Y114748D01*
G01X321061Y60723D02*
Y65814D01*
G01X327754Y78833D02*
Y73757D01*
G01Y87392D02*
Y89804D01*
X335792Y97842D01*
Y104069D01*
G01X324407Y60723D02*
Y65814D01*
G01Y89964D02*
Y94982D01*
X325417Y95992D01*
X326758D01*
X327604Y95146D01*
X328312D01*
X329443Y96277D01*
Y96985D01*
X328568Y97860D01*
Y98780D01*
X329487Y99699D01*
X330407D01*
X331431Y98675D01*
X332139D01*
X333270Y99806D01*
Y100514D01*
X332246Y101538D01*
Y102458D01*
X333692Y103904D01*
Y110190D01*
G01X324407Y78833D02*
Y73757D01*
G01X314368Y60723D02*
Y65814D01*
G01X311021Y78833D02*
Y81771D01*
X308692Y84100D01*
Y85300D01*
X309992Y86600D01*
Y88400D01*
X308992Y89400D01*
Y90700D01*
X310192Y91900D01*
Y99500D01*
X315892Y105200D01*
Y106500D01*
X317912Y108520D01*
G01X314368Y92657D02*
Y97176D01*
X320042Y102850D01*
Y104150D01*
X324046Y108154D01*
G01X324692Y114882D02*
Y112300D01*
X317892Y105500D01*
Y104299D01*
X312192Y98599D01*
Y91500D01*
X312992Y90700D01*
Y89200D01*
X312292Y88500D01*
Y85985D01*
X311021Y84714D01*
G01X304329Y78833D02*
X304328Y78832D01*
Y74908D01*
X304846Y74390D01*
Y73510D01*
X304328Y72992D01*
Y71900D01*
G01X300982Y60723D02*
Y65699D01*
G01X297636Y78833D02*
Y75000D01*
X298156Y74480D01*
Y73620D01*
X297636Y73100D01*
Y71901D01*
X297635Y71900D01*
G01X294289Y60723D02*
Y65699D01*
G01X334447Y78833D02*
Y73757D01*
G01X331100Y65814D02*
Y60723D01*
G01X354415Y92757D02*
Y94785D01*
X353714Y96478D01*
Y103936D01*
G01X354525Y65822D02*
Y60723D01*
G01Y78833D02*
Y73858D01*
X354526Y73857D01*
Y73757D01*
G01X365882Y188215D02*
Y120839D01*
X355699Y110656D01*
Y109379D01*
X356349Y108729D01*
X356982D01*
X357482Y108229D01*
Y106579D01*
X356982Y106079D01*
X356349D01*
X355699Y105429D01*
Y104079D01*
X356349Y103429D01*
X356757D01*
X357407Y102779D01*
Y101429D01*
X356757Y100779D01*
X356349D01*
X355699Y100129D01*
Y98658D01*
X357343Y97014D01*
Y95086D01*
X356190Y93933D01*
Y91265D01*
X355492Y90567D01*
Y89600D01*
X356130Y88962D01*
Y88042D01*
X355480Y87392D01*
X354415D01*
G01X351179Y65822D02*
Y60723D01*
G01X353842Y114416D02*
X351677Y112251D01*
Y94853D01*
X352640Y93890D01*
Y90521D01*
X352083Y89964D01*
X351179D01*
G01X347833Y78833D02*
Y73757D01*
G01X349692Y108643D02*
Y91600D01*
X348766Y90674D01*
Y88325D01*
X347833Y87392D01*
G01X344486Y78833D02*
Y73757D01*
G01X347592Y103993D02*
Y95098D01*
X346008Y93514D01*
Y92052D01*
X346311Y91749D01*
Y88719D01*
X344486Y86894D01*
Y84714D01*
G01Y89964D02*
X343682Y89160D01*
X342761D01*
X341965Y89956D01*
Y91055D01*
X343292Y92382D01*
Y93627D01*
X345492Y95827D01*
Y112063D01*
G01X344486Y60723D02*
Y65822D01*
G01X337793Y84599D02*
Y87299D01*
X335792Y89300D01*
Y91000D01*
X337892Y93100D01*
Y113956D01*
G01X337793Y78833D02*
Y73757D01*
G01X353972Y186457D02*
Y129662D01*
X340230Y115920D01*
Y114164D01*
X340836Y113558D01*
X341853D01*
X342518Y112893D01*
Y111543D01*
X341883Y110908D01*
X340527D01*
X339877Y110258D01*
Y108804D01*
X340377Y108304D01*
X342685D01*
X343375Y107614D01*
Y106354D01*
X342725Y105704D01*
X340926D01*
X340201Y104979D01*
Y103679D01*
X340776Y103104D01*
X342786D01*
X343436Y102454D01*
Y101154D01*
X342786Y100504D01*
X340600D01*
X339903Y99807D01*
Y98429D01*
X340403Y97929D01*
X342438D01*
X343176Y97191D01*
Y96050D01*
X342335Y95209D01*
X341790D01*
X341140Y94559D01*
Y92757D01*
G01Y65822D02*
Y60723D01*
G01X334447D02*
Y65813D01*
X334446Y65814D01*
G01X327754Y41033D02*
Y35957D01*
G01X324407Y41033D02*
Y35957D01*
G01X311021Y41033D02*
Y35957D01*
G01X304329Y41033D02*
X304328Y41032D01*
Y37108D01*
X304846Y36590D01*
Y35710D01*
X304328Y35192D01*
Y34100D01*
G01X297636Y41033D02*
Y37200D01*
X298156Y36680D01*
Y35820D01*
X297636Y35300D01*
Y34101D01*
X297635Y34100D01*
G01X334447Y41033D02*
Y35957D01*
G01X354525Y41033D02*
Y36058D01*
X354526Y36057D01*
Y35957D01*
G01X347833Y41033D02*
Y35957D01*
G01X344486Y41033D02*
Y35957D01*
G01X337793Y41033D02*
Y35957D01*
G01X331592Y114748D02*
Y118979D01*
X346032Y133419D01*
Y186625D01*
G01X335792Y104069D02*
Y117253D01*
X350002Y131463D01*
Y186360D01*
G01X333692Y110190D02*
Y118116D01*
X348017Y132441D01*
Y186310D01*
G01X327092Y103021D02*
X329573Y105502D01*
Y107022D01*
G01D02*
Y119923D01*
X344047Y134397D01*
Y186736D01*
G01X317912Y108520D02*
X322692Y113300D01*
Y122000D01*
X334707Y134015D01*
Y134724D01*
X333031Y136400D01*
Y137295D01*
X333985Y138249D01*
X334930D01*
X336203Y136976D01*
X336912D01*
X338092Y138156D01*
Y182563D01*
G01X324046Y108154D02*
X326792Y110900D01*
Y120101D01*
X342062Y135371D01*
Y182619D01*
G01X340077Y182436D02*
Y136385D01*
X324692Y121000D01*
Y114882D01*
G01X353714Y103936D02*
Y111479D01*
X363897Y121662D01*
Y188142D01*
G01X361912Y188639D02*
Y122486D01*
X353842Y114416D01*
G01X359927Y189913D02*
Y123310D01*
X349692Y113075D01*
Y108643D01*
G01X357942Y189634D02*
Y124134D01*
X347592Y113784D01*
Y103993D01*
G01X345492Y112063D02*
Y114492D01*
X348288Y117288D01*
Y118206D01*
X347401Y119093D01*
Y120012D01*
X348322Y120933D01*
X349240D01*
X350128Y120045D01*
X351045D01*
X351966Y120966D01*
Y121885D01*
X351026Y122825D01*
Y123907D01*
X351864Y124745D01*
X352784D01*
X353806Y123723D01*
X354723D01*
X355644Y124644D01*
Y125562D01*
X354757Y126449D01*
Y127368D01*
X355957Y128568D01*
Y185958D01*
G01X337892Y113956D02*
Y116390D01*
X351987Y130485D01*
Y186312D01*
G01X300982Y109700D02*
X303442D01*
X305817Y112075D01*
G01D02*
X310992Y117250D01*
Y129650D01*
X315342Y134000D01*
Y141600D01*
X315992Y142250D01*
X317342D01*
X317992Y141600D01*
Y137750D01*
X318642Y137100D01*
X319992D01*
X320642Y137750D01*
Y145727D01*
X319992Y146377D01*
X315992D01*
X311869Y150500D01*
X309642D01*
X307692Y152450D01*
Y160497D01*
X307968Y160773D01*
G01X304178Y107684D02*
X305826D01*
X313267Y115125D01*
G01D02*
X314492Y116350D01*
Y124050D01*
X323192Y132750D01*
Y148000D01*
X316192Y155000D01*
Y160050D01*
X315692Y160550D01*
X313692D01*
X313192Y160050D01*
Y156700D01*
X312192Y155700D01*
X311092D01*
X310388Y156404D01*
Y160796D01*
G01X303258Y165111D02*
X301942Y163795D01*
Y148251D01*
X305693Y144500D01*
X309542D01*
X310042Y144000D01*
Y136350D01*
X309392Y135700D01*
X308042D01*
X307392Y136350D01*
Y140800D01*
X306892Y141300D01*
X305242D01*
X304742Y140800D01*
Y126000D01*
X294889Y116147D01*
Y110927D01*
G01X305358Y163620D02*
X304592Y162854D01*
Y149700D01*
X306992Y147300D01*
X310592D01*
X312742Y145150D01*
Y135150D01*
X307742Y130150D01*
Y125200D01*
X306049Y123507D01*
Y122587D01*
X307004Y121632D01*
Y120712D01*
X306050Y119758D01*
X305130D01*
X304175Y120713D01*
X303255D01*
X302301Y119759D01*
Y118009D01*
X301257Y116965D01*
X299507D01*
X297592Y115050D01*
Y110600D01*
X294472Y107480D01*
Y105558D01*
X294946Y105084D01*
X297635D01*
G01X341088Y211060D02*
Y210239D01*
X342218Y209109D01*
G01X344468Y224709D02*
X342218D01*
G01X347848Y230559D02*
X345598D01*
G01X334328Y253960D02*
X332078D01*
G01X307289Y339760D02*
X305039D01*
G01X300529Y335860D02*
X298279D01*
G01X334328D02*
X332078D01*
G01X344468Y337809D02*
X342218D01*
G01X341088Y335860D02*
X338838D01*
G01X307289D02*
X305039D01*
G01X303909Y333909D02*
X301659D01*
G01X297149Y337809D02*
X294899D01*
G01X337708D02*
X335458D01*
G01X320808Y328060D02*
X318558D01*
G01X320808Y335860D02*
X318558D01*
G01X300529Y339760D02*
X298279D01*
G01X337708Y333909D02*
X335458D01*
G01X320808Y324160D02*
X318558D01*
G01X320808Y331960D02*
X318558D01*
G01X317428Y326110D02*
X315178D01*
G01X317428Y333909D02*
X315178D01*
G01X327568Y328060D02*
X325318D01*
G01X327568Y331960D02*
X325318D01*
G01X314048Y328060D02*
X311798D01*
G01X314048Y331960D02*
X311798D01*
G01X324188Y326110D02*
X321938D01*
G01X324188Y333909D02*
X321938D01*
G01X349574Y406130D02*
Y451922D01*
X331830Y469666D01*
Y503162D01*
X326742Y508250D01*
Y510344D01*
X321061Y516025D01*
Y518157D01*
G01X344468Y396309D02*
X341900D01*
X341892Y396301D01*
G01X351669Y407377D02*
Y452727D01*
X333930Y470466D01*
Y472157D01*
X334580Y472807D01*
X335578D01*
X336212Y473441D01*
Y474791D01*
X335546Y475457D01*
X334580D01*
X333930Y476107D01*
Y490705D01*
X334580Y491355D01*
X335747D01*
X336413Y492021D01*
Y493371D01*
X335779Y494005D01*
X334580D01*
X333930Y494655D01*
Y503734D01*
X334839Y504643D01*
Y506814D01*
X333391Y508262D01*
X330230D01*
X329092Y509400D01*
Y511100D01*
X329646Y511654D01*
Y513470D01*
X327752Y515364D01*
X324407D01*
G01X347848Y386560D02*
X345598D01*
G01X329730Y489798D02*
Y468765D01*
X347479Y451016D01*
Y405432D01*
G01X345384Y403714D02*
Y450211D01*
X326922Y468673D01*
Y497170D01*
G01X343091Y402909D02*
Y449049D01*
X324784Y467356D01*
Y494890D01*
X312992Y506682D01*
Y510900D01*
X312092Y511800D01*
Y513200D01*
X313192Y514300D01*
Y516881D01*
X314368Y518057D01*
G01X340996Y402882D02*
Y447473D01*
X322686Y465783D01*
Y493948D01*
X311021Y505613D01*
Y510114D01*
G01X300529Y374860D02*
X298279D01*
G01X300529Y382660D02*
X298279D01*
G01X310668Y376809D02*
X308418D01*
G01X310668Y380709D02*
X308418D01*
G01X297149Y376809D02*
X294899D01*
G01X297149Y380709D02*
X294899D01*
G01X307289Y374860D02*
X305039D01*
G01X307289Y382660D02*
X305039D01*
G01X303909Y376809D02*
X301659D01*
G01X330948Y353409D02*
X328698D01*
G01X303909Y384609D02*
X301659D01*
G01X330948Y361209D02*
X328698D01*
G01X303909Y372909D02*
X301659D01*
G01X330948Y349509D02*
X328698D01*
G01X303909Y380709D02*
X301659D01*
G01X330948Y357309D02*
X328698D01*
G01X327568Y351460D02*
X325318D01*
G01X327568Y359260D02*
X325318D01*
G01X337708Y353409D02*
X335458D01*
G01X337708Y357309D02*
X335458D01*
G01X324188Y353409D02*
X321938D01*
G01X324188Y357309D02*
X321938D01*
G01X334328Y351460D02*
X332078D01*
G01X334328Y359260D02*
X332078D01*
G01X351228Y392410D02*
X348978Y388509D01*
G01X344468Y380709D02*
X342218D01*
G01X357954Y408976D02*
Y455549D01*
X343056Y470447D01*
Y496811D01*
X342226Y497641D01*
Y499574D01*
X343056Y500404D01*
Y502111D01*
X342113Y503054D01*
Y504761D01*
X343056Y505704D01*
Y507834D01*
X342356Y508534D01*
Y510864D01*
X344947Y513455D01*
Y514903D01*
X344486Y515364D01*
G01X353764Y408372D02*
Y453532D01*
X338441Y468855D01*
Y474232D01*
X339013Y474804D01*
Y476154D01*
X338363Y476804D01*
X337638D01*
X336988Y477454D01*
Y478804D01*
X337638Y479454D01*
X338363D01*
X339013Y480104D01*
Y481529D01*
X338363Y482179D01*
X337167D01*
X336516Y482830D01*
Y484179D01*
X337166Y484829D01*
X338363D01*
X339013Y485479D01*
Y486829D01*
X338363Y487479D01*
X337413D01*
X336763Y488129D01*
Y489479D01*
X337413Y490129D01*
X337977D01*
X338983Y491135D01*
Y494140D01*
X337793Y495330D01*
Y509999D01*
G01X355859Y408774D02*
Y454367D01*
X341021Y469205D01*
Y495571D01*
X340192Y496400D01*
Y510500D01*
X339292Y511400D01*
Y513679D01*
X341140Y515527D01*
Y518157D01*
G01X351228Y400209D02*
Y402764D01*
X351192Y402800D01*
G01X347848Y378760D02*
X345598D01*
G01X351228Y380709D02*
X348978D01*
G01X297149Y388509D02*
X294899D01*
G01X297149Y392410D02*
X294899D01*
G01X314082Y436813D02*
X308159Y442736D01*
Y464200D01*
X307659Y464700D01*
X306009D01*
X305509Y464200D01*
Y461517D01*
X304859Y460867D01*
X303509D01*
X302892Y461484D01*
Y491500D01*
X301092Y493300D01*
G01X311171Y432548D02*
X297692Y446027D01*
Y476403D01*
X297042Y477053D01*
X295520D01*
X294870Y477703D01*
Y479053D01*
X295520Y479703D01*
X297042D01*
X297692Y480353D01*
Y481703D01*
X297042Y482353D01*
X295520D01*
X294870Y483003D01*
Y484353D01*
X295520Y485003D01*
X297042D01*
X297692Y485653D01*
Y487000D01*
X296534Y488158D01*
Y490958D01*
X294392Y493100D01*
G01X312483Y434807D02*
X305540Y441750D01*
Y455300D01*
X305040Y455800D01*
X303390D01*
X302890Y455300D01*
Y447016D01*
X302290Y446416D01*
X300940D01*
X300240Y447116D01*
Y488152D01*
X299066Y489326D01*
Y493713D01*
X297835Y494944D01*
G01X347848Y355360D02*
X345598D01*
G01X351228Y357309D02*
X348978D01*
G01X303909Y365109D02*
X301659D01*
G01X300529Y367060D02*
X298279D01*
G01X307289Y355360D02*
X305039D01*
G01X303909Y353409D02*
X301659D01*
G01X297149Y361209D02*
X294899D01*
G01X297149Y365109D02*
X294899D01*
G01X320808Y363160D02*
X318558D01*
G01X314048Y367060D02*
X311798D01*
G01X324188Y372909D02*
X321938D01*
G01X320808Y374860D02*
X318558D01*
G01X317428Y361209D02*
X315178D01*
G01X314048Y363160D02*
X311798D01*
G01X324188Y369010D02*
X321938D01*
G01X317428Y372909D02*
X315178D01*
G01X334328Y343660D02*
X332078D01*
G01X344468Y341709D02*
X342218D01*
G01X330948D02*
X328698D01*
G01X300529Y347560D02*
X298279D01*
G01X341088Y343660D02*
X338838D01*
G01X297149Y345609D02*
X294899D01*
G01X303909D02*
X301659D01*
G01X297149Y341709D02*
X294899D01*
G01X307289Y359260D02*
X305039D01*
G01X300529Y355360D02*
X298279D01*
G01X303909Y361209D02*
X301659D01*
G01X320808Y367060D02*
X318558D01*
G01X297149Y357309D02*
X294899D01*
G01X314048Y370959D02*
X311798D01*
G01X337708Y345609D02*
X335458D01*
G01X303909Y341709D02*
X301659D01*
G01X307289Y363160D02*
X305039D01*
G01X324188Y365109D02*
X321938D01*
G01X300529Y359260D02*
X298279D01*
G01X317428Y369010D02*
X315178D01*
G01X337708Y341709D02*
X335458D01*
G01X307289Y343660D02*
X305039D01*
G01X360049Y409566D02*
Y456451D01*
X345126Y471374D01*
Y509474D01*
X344486Y510114D01*
G01X315621Y438843D02*
X310729Y443735D01*
Y479500D01*
X310229Y480000D01*
X308579D01*
X308079Y479500D01*
Y469888D01*
X307429Y469238D01*
X306079D01*
X305429Y469888D01*
Y492463D01*
X304392Y493500D01*
Y494700D01*
G01X321061Y523900D02*
Y529014D01*
G01X324407Y523900D02*
Y529014D01*
G01X314368Y523900D02*
Y520623D01*
X316292Y518699D01*
Y517242D01*
X315592Y516542D01*
Y514600D01*
X318142Y512050D01*
X318542D01*
X320292Y510300D01*
Y509800D01*
X325192Y504900D01*
X326892D01*
X329730Y502062D01*
Y489798D01*
G01X300982Y523900D02*
Y528899D01*
G01X294289Y523900D02*
Y528899D01*
G01X331100Y523900D02*
Y529014D01*
G01X354525Y523900D02*
Y529022D01*
G01X366334Y410519D02*
Y458934D01*
X351665Y473603D01*
Y499745D01*
X353092Y501172D01*
Y503465D01*
X351695Y504862D01*
Y507365D01*
X352657Y508327D01*
Y511535D01*
X352222Y511970D01*
Y513654D01*
X353174Y514606D01*
Y516805D01*
X354526Y518157D01*
G01X368429Y410774D02*
Y459994D01*
X355373Y473050D01*
Y482639D01*
X353739Y484273D01*
Y487913D01*
X354994Y489168D01*
Y493288D01*
X353739Y494543D01*
Y498701D01*
X354808Y499770D01*
Y506265D01*
X354307Y506766D01*
Y512792D01*
G01X351179Y523900D02*
Y529022D01*
G01X364239Y410143D02*
Y458094D01*
X349264Y473069D01*
Y508697D01*
X349027Y508934D01*
Y511275D01*
X350046Y512294D01*
Y514231D01*
X351179Y515364D01*
G01X362144Y410009D02*
Y457319D01*
X347279Y472184D01*
Y512238D01*
X347833Y512792D01*
G01X344486Y523900D02*
Y529022D01*
G01X341140Y523900D02*
Y529022D01*
G01X334447Y523900D02*
Y529013D01*
X334446Y529014D01*
G01X327754Y536957D02*
Y542010D01*
G01X324407Y536957D02*
Y542010D01*
G01X311021Y536957D02*
Y542010D01*
G01X304329D02*
X304328D01*
Y538108D01*
X304846Y537590D01*
Y536710D01*
X304328Y536192D01*
Y535100D01*
G01X297636Y542010D02*
Y538200D01*
X298156Y537680D01*
Y536820D01*
X297636Y536300D01*
Y535101D01*
X297635Y535100D01*
G01X334447Y536957D02*
Y542010D01*
G01X354525D02*
Y537058D01*
X354526Y537057D01*
Y536957D01*
G01X347833D02*
Y542010D01*
G01X344486Y536957D02*
Y542010D01*
G01X337793Y536957D02*
Y542010D01*
G01X321061Y561700D02*
Y566814D01*
G01X327754Y574757D02*
Y579810D01*
G01X324407Y561700D02*
Y566814D01*
G01Y574757D02*
Y579810D01*
G01X314368Y561700D02*
Y566814D01*
G01X311021Y574757D02*
Y579810D01*
G01X304329D02*
X304328D01*
Y575908D01*
X304846Y575390D01*
Y574510D01*
X304328Y573992D01*
Y572900D01*
G01X300982Y561700D02*
Y566699D01*
G01X297636Y579810D02*
Y576000D01*
X298156Y575480D01*
Y574620D01*
X297636Y574100D01*
Y572901D01*
X297635Y572900D01*
G01X294289Y561700D02*
Y566699D01*
G01X334447Y574757D02*
Y579810D01*
G01X331100Y561700D02*
Y566814D01*
G01X354525Y561700D02*
Y566822D01*
G01Y579810D02*
Y574858D01*
X354526Y574857D01*
Y574757D01*
G01X351179Y561700D02*
Y566822D01*
G01X347833Y574757D02*
Y579810D01*
G01X344486Y574757D02*
Y579810D01*
G01Y561700D02*
Y566822D01*
G01X337793Y574757D02*
Y579810D01*
G01X341140Y561700D02*
Y566822D01*
G01X334447Y561700D02*
Y566813D01*
X334446Y566814D01*
G01X321061Y599500D02*
Y607292D01*
G01X327754Y617610D02*
Y612457D01*
G01X324407Y599500D02*
Y604499D01*
G01Y617610D02*
Y609864D01*
G01X314368Y599500D02*
Y607292D01*
G01X311021Y609864D02*
Y617610D01*
G01X304329D02*
X304328D01*
Y613708D01*
X304846Y613190D01*
Y612310D01*
X304328Y611792D01*
Y610700D01*
G01X300982Y599500D02*
Y604499D01*
G01X297636Y617610D02*
Y613400D01*
X298156Y612880D01*
Y612020D01*
X297636Y611500D01*
Y610701D01*
X297635Y610700D01*
G01X294289Y599500D02*
Y604499D01*
G01X334447Y617610D02*
Y612457D01*
G01X331100Y599500D02*
Y604614D01*
G01X354525Y599500D02*
Y599523D01*
X354526Y599524D01*
Y607292D01*
G01X354525Y617610D02*
Y612358D01*
G01X351179Y599500D02*
Y604499D01*
G01X347833Y617610D02*
Y612357D01*
G01X344486Y617610D02*
Y609864D01*
G01Y599500D02*
Y604614D01*
G01X337793Y617610D02*
Y609864D01*
G01X341140Y599500D02*
Y607292D01*
G01X334447Y599500D02*
Y607292D01*
G01X404722Y22923D02*
Y28021D01*
X404723Y28022D01*
G01X364565Y22923D02*
Y28014D01*
G01X361218Y22923D02*
Y28014D01*
G01X414762Y22923D02*
Y28021D01*
G01X398029Y28007D02*
Y22923D01*
G01X408069Y28007D02*
Y22923D01*
G01X404722Y-14877D02*
Y-9901D01*
G01X401376Y3233D02*
Y-1742D01*
X401375Y-1743D01*
G01X364565Y-14877D02*
Y-9786D01*
G01Y3233D02*
Y-1858D01*
G01X361218Y-14877D02*
Y-9786D01*
G01Y3233D02*
Y-1858D01*
G01X414762Y-14877D02*
Y-7109D01*
X414761Y-7108D01*
G01X398029Y-14877D02*
Y-9901D01*
G01X404722Y3233D02*
Y-4536D01*
G01X414762Y3233D02*
Y-1742D01*
X414761Y-1743D01*
G01X408069Y-14877D02*
Y-7109D01*
X408068Y-7108D01*
G01X394683Y3233D02*
Y-2200D01*
G01X404722Y89964D02*
X404016Y89258D01*
X401518D01*
X399364Y91412D01*
Y94128D01*
X393192Y100300D01*
Y101900D01*
X392154Y102938D01*
X390554D01*
X384377Y109115D01*
Y114881D01*
G01X404722Y60723D02*
Y65821D01*
X404723Y65822D01*
G01X401376Y78833D02*
Y73758D01*
X401377Y73757D01*
G01X364565Y60723D02*
Y65127D01*
X363466Y66226D01*
Y67301D01*
X364344Y68178D01*
X366326Y69000D01*
X370209D01*
X375952Y71377D01*
X377320Y72745D01*
X378812Y76350D01*
Y86739D01*
X378594Y87266D01*
X377340Y90293D01*
Y99545D01*
X378422Y100627D01*
Y106505D01*
G01X370193Y114952D02*
X364336Y109095D01*
Y93771D01*
X365607Y92500D01*
G01X364565Y78833D02*
Y81160D01*
X363466Y82259D01*
Y83350D01*
X364116Y84000D01*
X370892D01*
X372567Y85675D01*
Y88376D01*
X374375Y90184D01*
Y94303D01*
X373111Y95567D01*
X368185D01*
X367535Y96217D01*
Y99525D01*
X368185Y100175D01*
X369815D01*
X370240Y99750D01*
X373077D01*
X375287Y101960D01*
Y103892D01*
X373964Y105215D01*
X368121D01*
X367471Y105865D01*
Y107215D01*
X368121Y107865D01*
X373964D01*
X375287Y109188D01*
Y127696D01*
G01X360617Y103689D02*
Y95355D01*
X361017Y94955D01*
Y91087D01*
X361517Y90587D01*
X363155D01*
X364413Y89329D01*
Y88321D01*
X365234Y87500D01*
G01X361218Y60723D02*
Y65227D01*
X362316Y66325D01*
Y67778D01*
X363692Y69154D01*
X366097Y70150D01*
X369980D01*
X375300Y72353D01*
X376344Y73397D01*
X377662Y76579D01*
Y78869D01*
X377182Y79349D01*
Y81299D01*
X377662Y81779D01*
Y86510D01*
X377349Y87266D01*
X376190Y90064D01*
Y95341D01*
X375746Y95785D01*
Y97735D01*
X376190Y98179D01*
Y100022D01*
X377272Y101104D01*
Y105839D01*
X376864Y106247D01*
Y107609D01*
X377272Y108017D01*
Y116996D01*
G01X363186Y108014D02*
Y102731D01*
X362695Y102240D01*
Y100754D01*
X363186Y100263D01*
Y98838D01*
X362696Y98348D01*
Y96950D01*
X363186Y96460D01*
Y92894D01*
X362792Y92500D01*
G01X361218Y78833D02*
Y81411D01*
X362316Y82509D01*
Y83827D01*
X363639Y85150D01*
X370415D01*
X371417Y86152D01*
Y88853D01*
X373225Y90661D01*
Y93826D01*
X372634Y94417D01*
X367708D01*
X366385Y95740D01*
Y100002D01*
X367708Y101325D01*
X370292D01*
X370717Y100900D01*
X372600D01*
X374137Y102437D01*
Y103415D01*
X373487Y104065D01*
X367644D01*
X366321Y105388D01*
Y107692D01*
X367644Y109015D01*
X373487D01*
X374137Y109665D01*
Y140732D01*
G01X361803Y113813D02*
X359467Y111477D01*
Y94878D01*
X359867Y94478D01*
Y90610D01*
X361040Y89437D01*
X362678D01*
X363263Y88852D01*
Y88328D01*
X362435Y87500D01*
G01X414762Y60723D02*
Y65821D01*
X414763Y65822D01*
G01X396832Y114253D02*
X399228Y111857D01*
Y111136D01*
X398302Y110210D01*
Y109190D01*
X399552Y107940D01*
X400472D01*
X401322Y108790D01*
X402295D01*
X403192Y107893D01*
Y101100D01*
X407847Y96445D01*
X408767D01*
X409647Y97325D01*
X410835D01*
X411992Y96168D01*
Y95100D01*
X410606Y93714D01*
Y92214D01*
X408908Y90516D01*
Y89340D01*
X410866Y87382D01*
X411964D01*
X413292Y88710D01*
Y91288D01*
X414761Y92757D01*
G01X398029Y65807D02*
Y60723D01*
G01X382392Y109922D02*
Y108201D01*
X396189Y94404D01*
X398029Y89964D01*
G01X404722Y78833D02*
Y73758D01*
X404723Y73757D01*
G01X414762Y78833D02*
Y73758D01*
X414763Y73757D01*
G01X405733Y104472D02*
Y101559D01*
X407609Y99683D01*
X411645D01*
X417013Y94315D01*
Y91821D01*
X416292Y91100D01*
Y88923D01*
X414761Y87392D01*
G01X408069Y65807D02*
Y60723D01*
G01X389148Y112345D02*
X392745Y108748D01*
Y107161D01*
X392148Y106564D01*
Y105646D01*
X393069Y104725D01*
X393986D01*
X394584Y105323D01*
X395772D01*
X396423Y104672D01*
Y103484D01*
X395226Y102286D01*
Y101368D01*
X396147Y100447D01*
X397064D01*
X398491Y101874D01*
X399411D01*
X400330Y100955D01*
Y100035D01*
X398904Y98609D01*
Y97688D01*
X399823Y96769D01*
X400743D01*
X401941Y97967D01*
X403447D01*
X404097Y97317D01*
Y95810D01*
X402999Y94712D01*
Y93693D01*
X404690Y92002D01*
X407313D01*
X408068Y92757D01*
G01X394682Y87392D02*
X394683Y87391D01*
Y78833D01*
G01X383938Y103754D02*
X394682Y93010D01*
Y87392D01*
G01X401376Y41033D02*
Y35958D01*
X401377Y35957D01*
G01X364565Y41033D02*
Y35942D01*
G01X361218Y41033D02*
Y35942D01*
G01X404722Y41033D02*
Y36058D01*
X404723Y36057D01*
Y35957D01*
G01X414762Y41033D02*
Y35958D01*
X414763Y35957D01*
G01X394683Y41033D02*
Y36058D01*
X394684Y36057D01*
Y35957D01*
G01X384377Y114881D02*
Y180486D01*
G01X378422Y106505D02*
Y181266D01*
G01X372152Y182706D02*
Y116911D01*
X370193Y114952D01*
G01X375287Y183105D02*
Y127696D01*
G01X369017Y184533D02*
Y119400D01*
X360617Y111000D01*
Y103689D01*
G01X377272Y116996D02*
Y181268D01*
G01X371002Y182686D02*
Y117388D01*
X369516Y115902D01*
X368823D01*
X367647Y114726D01*
Y114033D01*
X363186Y109572D01*
Y108014D01*
G01X374137Y183105D02*
Y140732D01*
G01X367867Y184533D02*
Y119877D01*
X361803Y113813D01*
G01X388347Y179613D02*
Y119788D01*
X395684Y108807D01*
X398408Y106083D01*
G01D02*
X401375Y103116D01*
G01X398272Y187498D02*
Y124888D01*
X410543Y112617D01*
G01D02*
X416692Y106468D01*
Y104989D01*
X414819Y103116D01*
G01X424817Y111219D02*
X406212Y129824D01*
Y190701D01*
G01X422606Y116393D02*
X408197Y130802D01*
Y193595D01*
X407192Y194600D01*
Y201726D01*
X405755Y203163D01*
X404429D01*
X402381Y205211D01*
X398547D01*
X398546Y205210D01*
G01X390332Y186892D02*
Y120753D01*
X396832Y114253D01*
G01X419092Y104695D02*
Y107031D01*
X400257Y125866D01*
Y187877D01*
G01X405306Y205210D02*
X408442D01*
X409292Y204360D01*
Y195500D01*
X410182Y194610D01*
Y131780D01*
X433172Y108790D01*
G01X405306Y213009D02*
X406883D01*
X411492Y208400D01*
Y196399D01*
X412167Y195724D01*
Y132758D01*
X439767Y105158D01*
G01X416017Y159300D02*
Y143222D01*
X425505Y133734D01*
Y132814D01*
X424522Y131831D01*
X423602D01*
X422067Y133366D01*
X421359D01*
X420165Y132172D01*
Y131464D01*
X451523Y100106D01*
Y92807D01*
X451573Y92757D01*
G01X382392Y180801D02*
Y109922D01*
G01X392317Y187013D02*
Y121675D01*
X405733Y108259D01*
Y104472D01*
G01X386362Y180000D02*
Y115131D01*
X389148Y112345D01*
G01X394302Y187013D02*
Y122690D01*
X404022Y112970D01*
G01D02*
X410692Y106300D01*
Y103766D01*
X410042Y103116D01*
X408126D01*
G01X417190Y112652D02*
X402242Y127600D01*
Y188251D01*
G01X396287Y186770D02*
Y123668D01*
X412792Y107163D01*
Y104540D01*
G01D02*
Y102400D01*
X414492Y100700D01*
X416982D01*
X418791Y98891D01*
Y97605D01*
X420757Y95639D01*
X421873D01*
X424801Y92711D01*
Y89964D01*
G01X404227Y189513D02*
Y128578D01*
X425492Y107313D01*
Y104752D01*
G01X380407Y181141D02*
Y107285D01*
X383938Y103754D01*
G01X418084Y216196D02*
X415634D01*
G01X378267Y213009D02*
X376017D01*
G01X418084Y220096D02*
X415634D01*
G01X418084Y227896D02*
X415634D01*
G01X418084Y231797D02*
X415634D01*
G01X381647Y234460D02*
X379397D01*
G01X378267Y228610D02*
X376017D01*
G01X404722Y515364D02*
X400746D01*
X399492Y514110D01*
Y512000D01*
X399992Y511500D01*
Y509256D01*
X398610Y507874D01*
X395834D01*
X393150Y505190D01*
Y501046D01*
X387967Y495863D01*
Y411056D01*
G01X372637Y390460D02*
X374887D01*
G01X398546Y384609D02*
X396296D01*
G01X378299Y410053D02*
Y465360D01*
X376460Y467199D01*
Y467655D01*
X375080Y469035D01*
X374624D01*
X373192Y470467D01*
Y474576D01*
X371869Y475899D01*
X367776D01*
X367126Y476549D01*
Y477899D01*
X367776Y478549D01*
X374520D01*
X375843Y479872D01*
Y482176D01*
X374520Y483499D01*
X367776D01*
X367126Y484149D01*
Y485499D01*
X367776Y486149D01*
X371051D01*
X372781Y487879D01*
Y491333D01*
G01X364265Y515152D02*
X363349Y516068D01*
Y516792D01*
X361903Y518238D01*
X357479D01*
X356072Y516831D01*
Y514014D01*
X356351Y513735D01*
Y511925D01*
X355967Y511541D01*
Y507693D01*
X357442Y506218D01*
Y473830D01*
X370423Y460849D01*
Y410490D01*
G01X381500Y410133D02*
Y467698D01*
X379161Y470037D01*
Y484578D01*
X377192Y486547D01*
Y498249D01*
G01X374010Y410158D02*
Y435094D01*
X373610Y435494D01*
Y437444D01*
X374010Y437844D01*
Y439794D01*
X373610Y440194D01*
Y442144D01*
X374010Y442544D01*
Y444494D01*
X373610Y444894D01*
Y446844D01*
X374010Y447244D01*
Y449194D01*
X373610Y449594D01*
Y451544D01*
X374010Y451944D01*
Y453894D01*
X373610Y454294D01*
Y456244D01*
X374010Y456644D01*
Y458594D01*
X373610Y458994D01*
Y460944D01*
X374010Y461344D01*
Y463294D01*
X371808Y465496D01*
X371357D01*
X369977Y466876D01*
Y467327D01*
X368705Y468599D01*
X368108D01*
X366729Y469978D01*
Y470575D01*
X365270Y472034D01*
X364601D01*
X363222Y473413D01*
Y474082D01*
X361817Y475487D01*
Y479255D01*
X361319Y479753D01*
Y481703D01*
X361817Y482201D01*
Y484151D01*
X361319Y484649D01*
Y486599D01*
X361817Y487097D01*
Y489047D01*
X363140Y490370D01*
X366288D01*
X366938Y491020D01*
Y492370D01*
X366288Y493020D01*
X363140D01*
X361817Y494343D01*
Y496647D01*
X363140Y497970D01*
X366288D01*
X366938Y498620D01*
Y499970D01*
X366288Y500620D01*
X363140D01*
X361817Y501943D01*
Y505246D01*
X363576Y507005D01*
X367142D01*
X368730Y508593D01*
Y510826D01*
X367406Y512150D01*
X364010D01*
X363487Y511627D01*
Y510892D01*
X364265Y510114D01*
G01X377149Y410073D02*
Y462175D01*
G01X361642Y515200D02*
X362199Y515757D01*
Y516315D01*
X361426Y517088D01*
X357956D01*
X357222Y516354D01*
Y514491D01*
X357501Y514212D01*
Y511448D01*
X357117Y511064D01*
Y508170D01*
X358592Y506695D01*
Y505985D01*
X359156Y505421D01*
Y503515D01*
X358592Y502951D01*
Y501372D01*
X359090Y500874D01*
Y498924D01*
X358592Y498426D01*
Y496476D01*
X359090Y495978D01*
Y494028D01*
X358592Y493530D01*
Y491580D01*
X359090Y491082D01*
Y489132D01*
X358592Y488634D01*
Y486684D01*
X359090Y486186D01*
Y484236D01*
X358592Y483738D01*
Y481788D01*
X359090Y481290D01*
Y479340D01*
X358592Y478842D01*
Y477399D01*
X358900Y477091D01*
Y475791D01*
X358592Y475483D01*
Y474307D01*
X359970Y472929D01*
X360675D01*
X362054Y471549D01*
Y470845D01*
X363476Y469423D01*
X364065D01*
X365445Y468043D01*
Y467454D01*
X366965Y465934D01*
X367508D01*
X368888Y464554D01*
Y464011D01*
X371573Y461326D01*
Y434333D01*
X372023Y433883D01*
Y431933D01*
X371573Y431483D01*
Y429533D01*
X372023Y429083D01*
Y427133D01*
X371573Y426683D01*
Y424733D01*
X372023Y424283D01*
Y422333D01*
X371573Y421883D01*
Y419933D01*
X372023Y419483D01*
Y417533D01*
X371573Y417083D01*
Y410262D01*
G01X380350Y410133D02*
Y453103D01*
G01X375160Y410161D02*
Y463771D01*
X362967Y475964D01*
Y488570D01*
X363617Y489220D01*
X366765D01*
X368088Y490543D01*
Y492847D01*
X366765Y494170D01*
X363617D01*
X362967Y494820D01*
Y496170D01*
X363617Y496820D01*
X366765D01*
X368088Y498143D01*
Y500447D01*
X366765Y501770D01*
X363617D01*
X362967Y502420D01*
Y504769D01*
X364053Y505855D01*
X367619D01*
X369880Y508116D01*
Y511303D01*
X367883Y513300D01*
X363533D01*
X362337Y512104D01*
Y510933D01*
X361518Y510114D01*
G01X394267Y413053D02*
X394152Y413168D01*
Y485823D01*
X398970Y490641D01*
Y491878D01*
X398302Y492546D01*
Y493566D01*
X399552Y494816D01*
X400472D01*
X401207Y494081D01*
X402208D01*
X403192Y495065D01*
Y498191D01*
G01X418874Y498682D02*
X402092Y481900D01*
Y416028D01*
G01X427596Y494704D02*
X410032Y477140D01*
Y413141D01*
X401863Y404972D01*
G01X402192Y402200D02*
X412017Y412025D01*
Y476185D01*
X413578Y477746D01*
Y477747D01*
X431294Y495463D01*
X433555D01*
X435192Y497100D01*
Y499400D01*
G01X414761Y518157D02*
X418035D01*
X419992Y516200D01*
Y514300D01*
X419492Y513800D01*
Y511500D01*
X419920Y511072D01*
Y509228D01*
X416792Y506100D01*
X411462D01*
X407048Y501686D01*
Y495812D01*
X396137Y484901D01*
Y413983D01*
X396367Y413753D01*
G01X404077Y417443D02*
Y480286D01*
X423876Y500085D01*
Y501278D01*
X425888Y503290D01*
X427669D01*
X428835Y504456D01*
Y506099D01*
X430636Y507900D01*
X432539D01*
X434046Y509407D01*
Y510746D01*
X432441Y512351D01*
Y514417D01*
X431494Y515364D01*
G01X413642Y396123D02*
Y407549D01*
X415987Y409894D01*
Y471319D01*
X440192Y495524D01*
Y501244D01*
X446792Y507844D01*
Y510800D01*
X445892Y511700D01*
Y512920D01*
X444880Y515364D01*
G01X405306Y392410D02*
Y393982D01*
X407824Y396500D01*
X410392D01*
X411242Y397350D01*
Y402684D01*
X410592Y403334D01*
X408540D01*
X407953Y403921D01*
Y405271D01*
X408666Y405984D01*
X410592D01*
X411242Y406634D01*
Y408350D01*
X414002Y411110D01*
Y473054D01*
X415046Y474098D01*
X415890D01*
X418160Y476368D01*
Y477288D01*
X417530Y477918D01*
Y478838D01*
X418484Y479792D01*
X419404D01*
X420034Y479162D01*
X420954D01*
X422350Y480558D01*
Y481478D01*
X421692Y482136D01*
Y483041D01*
X422646Y483995D01*
X423581D01*
X424224Y483352D01*
X425144D01*
X426098Y484306D01*
Y485226D01*
X425440Y485884D01*
Y486789D01*
X426394Y487743D01*
X427329D01*
X427972Y487100D01*
X428892D01*
X429846Y488054D01*
Y488974D01*
X429173Y489647D01*
Y490497D01*
X430086Y491410D01*
X431158D01*
X431720Y490848D01*
X432640D01*
X437941Y496149D01*
Y501350D01*
X444880Y508289D01*
Y510114D01*
G01X398029Y515364D02*
X396892Y514227D01*
Y511404D01*
X390750Y505262D01*
Y501697D01*
X385867Y496814D01*
Y410585D01*
G01X372637Y386560D02*
X374887D01*
G01X395166D02*
X392916D01*
G01X392167Y411853D02*
Y487420D01*
X393547Y488800D01*
Y490064D01*
X392420Y491191D01*
Y492676D01*
X394384Y494640D01*
X395760D01*
X397957Y496837D01*
Y498173D01*
X397129Y499001D01*
Y499921D01*
X399032Y501824D01*
X400016D01*
X410984Y512792D01*
X414761D01*
G01X391787Y384609D02*
X389537D01*
G01X390067Y410927D02*
Y494857D01*
X394596Y499386D01*
Y500038D01*
X402892Y508334D01*
Y510900D01*
X408068Y516076D01*
Y518157D01*
G01X401926Y390460D02*
X399676D01*
G01X406851Y492615D02*
X398122Y483886D01*
Y414698D01*
G01X419651Y492659D02*
X406062Y479070D01*
Y417690D01*
G01X400107Y415513D02*
Y482816D01*
X412556Y495265D01*
Y497243D01*
X415965Y500652D01*
X417943D01*
X426592Y509301D01*
Y511901D01*
X425992Y512501D01*
Y514173D01*
X424801Y515364D01*
G01X408047Y418266D02*
Y478055D01*
X438122Y508130D01*
X439317Y508625D01*
X439992Y509300D01*
Y511006D01*
X438187Y515364D01*
G01X383767Y410585D02*
Y497821D01*
X389010Y503064D01*
Y505890D01*
X394682Y511562D01*
Y512792D01*
G01X378267Y384609D02*
X376017D01*
G01X378267Y369010D02*
X376017D01*
G01X361218Y523900D02*
Y521276D01*
X363089Y519405D01*
X363415D01*
X364539Y518281D01*
X366337D01*
X371631Y512987D01*
Y488356D01*
X370574Y487299D01*
X367299D01*
X365976Y485976D01*
Y483672D01*
X367299Y482349D01*
X374043D01*
X374693Y481699D01*
Y480349D01*
X374043Y479699D01*
X367299D01*
X365976Y478376D01*
Y476072D01*
X367299Y474749D01*
X371392D01*
X372042Y474099D01*
Y469990D01*
X377149Y464883D01*
Y462175D01*
G01X380350Y453103D02*
Y467221D01*
X378011Y469560D01*
Y473044D01*
X377513Y473542D01*
Y475492D01*
X378011Y475990D01*
Y484101D01*
X376042Y486070D01*
Y498850D01*
X375592Y499300D01*
Y501250D01*
X376042Y501700D01*
Y503650D01*
X375592Y504100D01*
Y506050D01*
X376042Y506500D01*
Y508450D01*
X375592Y508900D01*
Y510850D01*
X376042Y511300D01*
Y513250D01*
X377992Y515200D01*
Y523572D01*
X376506Y525058D01*
X376031D01*
X374651Y526438D01*
Y526913D01*
X372388Y529176D01*
X371925D01*
X370545Y530556D01*
Y531019D01*
X369060Y532504D01*
X364218D01*
X362316Y534406D01*
Y536431D01*
X361218Y537529D01*
Y542010D01*
G01X404722Y523900D02*
Y529021D01*
X404723Y529022D01*
G01X372781Y491333D02*
Y494182D01*
X373125Y494526D01*
Y496476D01*
X372781Y496820D01*
Y498878D01*
X373125Y499222D01*
Y501172D01*
X372781Y501516D01*
Y503539D01*
X373160Y503918D01*
Y505868D01*
X372781Y506247D01*
Y513464D01*
X366814Y519431D01*
X365016D01*
X364565Y519882D01*
Y523900D01*
G01Y542010D02*
Y537629D01*
X363466Y536530D01*
Y534883D01*
X364695Y533654D01*
X369537D01*
X379142Y524049D01*
Y514723D01*
X377192Y512773D01*
Y498249D01*
G01X403192Y498191D02*
Y501800D01*
X409592Y508200D01*
X412792D01*
X416592Y512000D01*
Y513700D01*
X412892Y517400D01*
Y519101D01*
X414762Y520971D01*
Y523900D01*
G01X398029D02*
Y529007D01*
G01X408069Y523900D02*
Y529007D01*
G01X424801Y523900D02*
Y523923D01*
X424292Y523414D01*
Y518100D01*
X422292Y516100D01*
Y514700D01*
X423292Y513700D01*
Y512100D01*
X422692Y511500D01*
Y509300D01*
X417276Y503884D01*
X412988D01*
X409483Y500379D01*
Y495247D01*
X406851Y492615D01*
G01X401376Y542010D02*
Y536958D01*
X401377Y536957D01*
G01X404722Y542010D02*
Y536958D01*
X404723Y536957D01*
G01X414762Y542010D02*
Y536958D01*
X414763Y536957D01*
G01X394683Y542010D02*
Y537146D01*
X394595Y537058D01*
G01X404722Y561700D02*
Y566821D01*
X404723Y566822D01*
G01X401376Y579810D02*
Y574758D01*
X401377Y574757D01*
G01X364565Y561700D02*
Y566814D01*
G01Y579810D02*
Y574742D01*
G01X361218Y561700D02*
Y566814D01*
G01Y579810D02*
Y574742D01*
G01X414762Y561700D02*
Y566821D01*
X414763Y566822D01*
G01X398029Y561700D02*
Y566807D01*
G01X404722Y579810D02*
Y574858D01*
X404723Y574857D01*
Y574757D01*
G01X414762Y579810D02*
Y574758D01*
X414763Y574757D01*
G01X408069Y561700D02*
Y566807D01*
G01X394683Y579810D02*
Y574858D01*
X394684Y574857D01*
Y574757D01*
G01X404722Y599500D02*
Y604499D01*
G01X401376Y617610D02*
Y612658D01*
G01X364565Y599500D02*
Y604614D01*
G01Y617610D02*
Y612242D01*
G01X361218Y599500D02*
Y604614D01*
G01Y617610D02*
Y612242D01*
G01X414762Y599500D02*
Y607291D01*
X414761Y607292D01*
G01X398029Y599500D02*
Y604499D01*
G01X404722Y617610D02*
Y609864D01*
G01X414762Y617610D02*
Y612658D01*
X414761Y612657D01*
G01X408069Y599500D02*
Y607291D01*
X408068Y607292D01*
G01X394683Y617610D02*
X394682D01*
Y612657D01*
G01X774974Y-41875D02*
X583682D01*
G03Y-45825I0J-1975D01*
G01X776815D01*
G02Y-52075I0J-3125D01*
G01X576785D01*
X572586Y-47876D01*
X471671D01*
X467246Y-52301D01*
G01X774974Y-40725D02*
X583682D01*
G03Y-46975I0J-3125D01*
G01X776815D01*
G02Y-50925I0J-1975D01*
G01X577262D01*
X573063Y-46726D01*
X471671D01*
X467246Y-42301D01*
G01X431494Y28007D02*
Y22923D01*
G01X444880Y28022D02*
Y22923D01*
G01X458266D02*
Y27899D01*
G01X451573Y22923D02*
Y27899D01*
G01X474998Y22923D02*
Y27899D01*
G01X468305Y22923D02*
Y25495D01*
X466658Y27142D01*
Y28800D01*
X467390Y29532D01*
Y30503D01*
X466398Y31495D01*
X465503D01*
X464758Y30750D01*
G01X468305Y41033D02*
X468304Y41032D01*
Y36805D01*
X466800Y35301D01*
Y33601D01*
X468101Y32300D01*
X468983D01*
X469832Y33149D01*
G01X464958Y22923D02*
Y25411D01*
X462792Y27577D01*
Y30693D01*
X463229Y31896D01*
X464732Y33399D01*
G01X471651Y41033D02*
Y37049D01*
X471800Y36900D01*
Y31500D01*
X470840Y30540D01*
X469832D01*
G01X421455Y22923D02*
Y28021D01*
X421456Y28022D01*
G01X424801Y22923D02*
Y28007D01*
G01X438187Y22923D02*
Y28020D01*
X438189Y28022D01*
G01X438187Y3233D02*
Y-4536D01*
G01X431494Y-14877D02*
Y-9901D01*
G01X444880Y-14877D02*
Y-9786D01*
G01Y3233D02*
Y-4536D01*
G01X461612Y3233D02*
X460912Y-4100D01*
G01X458266Y-14877D02*
Y-9901D01*
G01X454919Y3233D02*
Y-2008D01*
X454533Y-4100D01*
G01X451573Y-14877D02*
Y-9901D01*
G01X474998Y-14877D02*
Y-9901D01*
G01X468305Y-14877D02*
Y-11561D01*
X466658Y-9914D01*
Y-9000D01*
X467390Y-8268D01*
Y-7297D01*
X466398Y-6305D01*
X465578D01*
X464833Y-7050D01*
X464758D01*
G01X468305Y3233D02*
X468304Y3232D01*
Y-755D01*
X467258Y-1801D01*
Y-4686D01*
X469832Y-7260D01*
G01X464958Y-14877D02*
Y-12448D01*
X463241Y-10731D01*
X462908Y-10008D01*
Y-6787D01*
X463229Y-5904D01*
X464732Y-4401D01*
G01X471651Y3233D02*
X471650Y3232D01*
Y-1092D01*
X472523Y-1965D01*
Y-4887D01*
X471681Y-5729D01*
X470910D01*
X469832Y-4651D01*
G01X428147Y3233D02*
Y-1743D01*
G01X421455Y-14877D02*
X421454Y-14876D01*
Y-7108D01*
G01X434840Y3233D02*
Y-1743D01*
G01X424801Y-14877D02*
Y-9786D01*
G01X438187Y-14877D02*
Y-9786D01*
G01X431494Y65807D02*
Y60723D01*
G01X444880Y65822D02*
Y60723D01*
G01Y78833D02*
Y81813D01*
X442792Y83901D01*
Y85900D01*
X443392Y86500D01*
Y88200D01*
X442392Y89200D01*
X442092D01*
X439592Y91700D01*
Y93900D01*
X432124Y101368D01*
Y106875D01*
X422606Y116393D01*
G01X431494Y89964D02*
Y91898D01*
X430392Y93000D01*
Y97301D01*
X429570Y98123D01*
X428243D01*
X427592Y97472D01*
Y95576D01*
X426942Y94926D01*
X425611D01*
X424838Y95699D01*
Y99355D01*
X423393Y100800D01*
X420792D01*
X419092Y102500D01*
Y104695D01*
G01X433172Y108790D02*
X436692Y105270D01*
Y104526D01*
X434901Y102735D01*
Y101815D01*
X435820Y100896D01*
X436740D01*
X438498Y102654D01*
X439418D01*
X440348Y101724D01*
Y100804D01*
X438578Y99034D01*
Y98114D01*
X439497Y97195D01*
X440417D01*
X442187Y98965D01*
X443107D01*
X444092Y97980D01*
Y90752D01*
X444880Y89964D01*
G01X439767Y105158D02*
X446792Y98133D01*
Y89100D01*
X445993Y88301D01*
Y85827D01*
X444880Y84714D01*
G01X461612Y78833D02*
X461294Y75500D01*
X460912Y71500D01*
G01X454520Y104627D02*
X456742Y102405D01*
Y94281D01*
X458266Y92757D01*
G01Y60723D02*
Y65699D01*
G01X423574Y158900D02*
Y146943D01*
X453344Y117173D01*
Y116253D01*
X452362Y115271D01*
X451442D01*
X449190Y117523D01*
X448214D01*
X447286Y116595D01*
Y115621D01*
X459342Y103565D01*
Y94872D01*
X460358Y93856D01*
Y92316D01*
X458908Y90866D01*
Y89718D01*
X460912Y87714D01*
G01X454919Y78833D02*
Y73592D01*
X454533Y71500D01*
G01X418536Y159100D02*
Y144461D01*
X428692Y134305D01*
Y126695D01*
X454142Y101245D01*
Y93550D01*
X456588Y91104D01*
Y89683D01*
X454619Y87714D01*
G01X451573Y60723D02*
Y65699D01*
G01X433431Y159100D02*
Y155179D01*
X470092Y118518D01*
Y103701D01*
X470593Y103200D01*
X475842D01*
X476492Y102550D01*
Y101050D01*
X475842Y100400D01*
X470442D01*
X469892Y99850D01*
Y97800D01*
X470692Y97000D01*
X475793D01*
X476292Y96501D01*
Y95599D01*
X474998Y94305D01*
Y92757D01*
G01X474326Y112500D02*
Y109758D01*
X479092Y104992D01*
Y94100D01*
X476192Y91200D01*
Y88364D01*
X476842Y87714D01*
X478344D01*
G01X474998Y60723D02*
Y65699D01*
G01X468305Y60723D02*
Y63295D01*
X466658Y64942D01*
Y66600D01*
X467390Y67332D01*
Y68303D01*
X466398Y69295D01*
X465578D01*
X464833Y68550D01*
X464758D01*
G01X427243Y158861D02*
Y148985D01*
X429254Y146974D01*
X429961D01*
X430669Y146266D01*
Y145559D01*
X431686Y144542D01*
X432394D01*
X433101Y143835D01*
Y143127D01*
X436001Y140227D01*
X439338D01*
X441489Y138076D01*
Y136130D01*
X441149Y135790D01*
Y134798D01*
X442625Y133322D01*
X443617D01*
X443957Y133662D01*
X445903D01*
X448054Y131511D01*
Y129565D01*
X447714Y129225D01*
Y128233D01*
X449190Y126757D01*
X450182D01*
X450522Y127097D01*
X452468D01*
X454619Y124946D01*
Y123000D01*
X454279Y122660D01*
Y121668D01*
X455755Y120192D01*
X456747D01*
X457087Y120532D01*
X459033D01*
X461442Y118123D01*
Y111349D01*
X460642Y110549D01*
Y108477D01*
X463292Y105827D01*
Y95628D01*
X463820Y95100D01*
X464692D01*
X466503Y93289D01*
Y90550D01*
X465853Y89900D01*
X464732D01*
G01X468305Y78833D02*
X468304Y78832D01*
Y74605D01*
X466800Y73101D01*
Y71401D01*
X468101Y70100D01*
X468983D01*
X469832Y70949D01*
G01X466112Y114000D02*
Y96180D01*
X468037Y94255D01*
Y89309D01*
X469832Y87514D01*
G01X464958Y60723D02*
Y63152D01*
X463241Y64869D01*
X462908Y65592D01*
Y68813D01*
X463229Y69696D01*
X464732Y71199D01*
G01X460292Y115000D02*
Y111826D01*
X459492Y111026D01*
Y108000D01*
X462142Y105350D01*
Y95151D01*
X462842Y94451D01*
Y89190D01*
X464732Y87300D01*
G01X471651Y78833D02*
Y74849D01*
X471800Y74700D01*
Y69300D01*
X470840Y68340D01*
X469832D01*
G01X467262Y109000D02*
Y96657D01*
X469319Y94600D01*
X470869D01*
X472192Y93277D01*
Y90764D01*
X471542Y90114D01*
X469832D01*
G01X428147Y78833D02*
Y73759D01*
X428149Y73757D01*
G01X421455Y60723D02*
Y65821D01*
X421456Y65822D01*
G01X434840Y78833D02*
Y73759D01*
X434842Y73757D01*
G01X424801Y60723D02*
Y65807D01*
G01X438187Y60723D02*
Y65820D01*
X438189Y65822D01*
G01X425492Y104752D02*
Y102500D01*
X427692Y100300D01*
X430292D01*
X436692Y93900D01*
Y91459D01*
X438187Y89964D01*
G01X444880Y41033D02*
Y35959D01*
X444882Y35957D01*
G01X461612Y41033D02*
X461036Y35000D01*
X460988Y34500D01*
X460912Y33700D01*
G01X454919Y41033D02*
Y35792D01*
X454773Y35000D01*
X454681Y34500D01*
X454533Y33700D01*
G01X428147Y41033D02*
Y35959D01*
X428149Y35957D01*
G01X434840Y41033D02*
Y35959D01*
X434842Y35957D01*
G01X427696Y103100D02*
X429528Y104932D01*
Y106508D01*
X424817Y111219D01*
G01X421055Y159000D02*
Y145703D01*
X443065Y123693D01*
Y122773D01*
X442083Y121791D01*
X441163D01*
X438212Y124742D01*
X437135D01*
X436308Y123915D01*
Y122839D01*
X454520Y104627D01*
G01X438469Y159300D02*
Y157269D01*
X476845Y118893D01*
Y112696D01*
X481691Y107850D01*
Y104000D01*
G01X440988Y159600D02*
Y158314D01*
X479364Y119938D01*
Y115328D01*
X481792Y112900D01*
G01X435950Y159100D02*
Y156224D01*
X474326Y117848D01*
Y112500D01*
G01X429762Y158760D02*
Y153658D01*
X466112Y117308D01*
Y114000D01*
G01X426093Y158861D02*
Y148508D01*
X435524Y139077D01*
X438861D01*
X440339Y137599D01*
Y136607D01*
X439999Y136267D01*
Y134321D01*
X442148Y132172D01*
X444094D01*
X444434Y132512D01*
X445426D01*
X446904Y131034D01*
Y130042D01*
X446564Y129702D01*
Y127756D01*
X448713Y125607D01*
X450659D01*
X450999Y125947D01*
X451991D01*
X453469Y124469D01*
Y123477D01*
X453129Y123137D01*
Y121191D01*
X455278Y119042D01*
X457224D01*
X457564Y119382D01*
X458556D01*
X460292Y117646D01*
Y115000D01*
G01X430912Y158726D02*
Y154135D01*
X467262Y117785D01*
Y109000D01*
G01X421512Y103116D02*
X423392Y104996D01*
Y106450D01*
X417190Y112652D01*
G01X458592Y161000D02*
Y159075D01*
X457942Y158425D01*
X456742D01*
X456092Y157775D01*
Y156425D01*
X456742Y155775D01*
X457942D01*
X458592Y155125D01*
X459967D01*
X461385Y153707D01*
Y152787D01*
X461006Y152408D01*
Y151488D01*
X461960Y150534D01*
X462880D01*
X463259Y150913D01*
X464179D01*
X465133Y149959D01*
Y149039D01*
X464754Y148660D01*
Y147740D01*
X472413Y140081D01*
X478111D01*
X482042Y136150D01*
Y131950D01*
X489958Y124034D01*
Y123114D01*
X488611Y121767D01*
Y120393D01*
X489444Y119560D01*
X490152D01*
X491832Y121240D01*
X492752D01*
X494188Y119804D01*
Y119096D01*
X492292Y117200D01*
Y116300D01*
X493692Y114900D01*
Y113592D01*
X494927Y112357D01*
G01X461692Y161400D02*
Y157012D01*
X476104Y142600D01*
X479292D01*
X484561Y137331D01*
Y133231D01*
X495892Y121900D01*
X497392D01*
X497892Y121400D01*
Y120000D01*
X496902Y119010D01*
Y116000D01*
G01X451992Y163000D02*
X449792D01*
X449292Y163500D01*
Y163900D01*
X448792Y164400D01*
X446542D01*
X445892Y163750D01*
Y159001D01*
X483292Y121601D01*
Y117699D01*
X488634Y112357D01*
G01X455892Y161700D02*
X452392Y158200D01*
Y156300D01*
X486092Y122600D01*
Y118500D01*
X488242Y116350D01*
G01X465554Y161600D02*
Y158364D01*
X466261Y157657D01*
X466968D01*
X467676Y156950D01*
Y156242D01*
X468383Y155535D01*
X469090D01*
X469798Y154828D01*
Y154120D01*
X470997Y152921D01*
X471705D01*
X472413Y152213D01*
Y151505D01*
X473120Y150798D01*
X473827D01*
X474535Y150091D01*
Y149383D01*
X477268Y146650D01*
X481169D01*
X489644Y138175D01*
Y136301D01*
X488534Y135191D01*
Y134485D01*
X489704Y133315D01*
X490410D01*
X491520Y134425D01*
X493394D01*
X496315Y131504D01*
Y129630D01*
X495742Y129057D01*
Y127749D01*
X497291Y126200D01*
X501069D01*
X502242Y125027D01*
Y118322D01*
X500919Y116999D01*
Y115573D01*
X501492Y115000D01*
X502792D01*
X503339Y114453D01*
Y111447D01*
X502406Y110514D01*
X501544D01*
G01X468704Y161700D02*
Y160388D01*
X479592Y149500D01*
X481964D01*
X504854Y126610D01*
Y115180D01*
X504875Y115159D01*
Y109424D01*
X506644Y107655D01*
G01X464404Y161600D02*
Y157887D01*
X476791Y145500D01*
X480692D01*
X488494Y137698D01*
Y136778D01*
X487384Y135668D01*
Y134008D01*
X489227Y132165D01*
X490887D01*
X491997Y133275D01*
X492917D01*
X495165Y131027D01*
Y130107D01*
X494592Y129534D01*
Y127272D01*
X496814Y125050D01*
X500592D01*
X501092Y124550D01*
Y118799D01*
X499769Y117476D01*
Y109666D01*
X501570Y107865D01*
G01X469854Y161700D02*
Y160865D01*
X470561Y160158D01*
X471268D01*
X471976Y159451D01*
Y158743D01*
X472683Y158036D01*
X473390D01*
X474098Y157329D01*
Y156621D01*
X474805Y155914D01*
X475512D01*
X476220Y155207D01*
Y154499D01*
X476927Y153792D01*
X477634D01*
X478342Y153085D01*
Y152377D01*
X480069Y150650D01*
X482441D01*
X506004Y127087D01*
Y116287D01*
X508892Y113399D01*
Y111400D01*
X507756Y110264D01*
X506670D01*
G01X482296Y163803D02*
X485692Y160407D01*
Y158200D01*
X494692Y149200D01*
X502092D01*
X516442Y134850D01*
Y130500D01*
G01X484392Y165900D02*
X488211Y162081D01*
Y159381D01*
X495792Y151800D01*
X503392D01*
X521052Y134140D01*
Y117000D01*
G01X476992Y161900D02*
X479092Y159800D01*
Y157600D01*
X494868Y141824D01*
X495788D01*
X497668Y143704D01*
X498588D01*
X499542Y142750D01*
Y141830D01*
X497662Y139950D01*
Y139030D01*
X498616Y138076D01*
X499536D01*
X501416Y139956D01*
X502336D01*
X503290Y139002D01*
Y138082D01*
X501410Y136202D01*
Y135282D01*
X502364Y134328D01*
X503284D01*
X505164Y136208D01*
X506084D01*
X507038Y135254D01*
Y134334D01*
X505158Y132454D01*
Y131534D01*
X508892Y127800D01*
Y122500D01*
G01X479792Y162700D02*
X482392Y160100D01*
Y157900D01*
X493892Y146400D01*
X500848D01*
X511492Y135675D01*
Y133000D01*
G01X516110Y165830D02*
X516092Y165812D01*
Y159399D01*
X525175Y150316D01*
Y149020D01*
X522384Y146229D01*
Y145507D01*
X523466Y144425D01*
X524174D01*
X527285Y147536D01*
X527993D01*
X529407Y146122D01*
Y145414D01*
X528097Y144104D01*
Y143394D01*
X529363Y142128D01*
X530071D01*
X531382Y143439D01*
X532090D01*
X533747Y141782D01*
Y141074D01*
X530192Y137519D01*
Y135231D01*
X532473Y132950D01*
Y131553D01*
X530492Y129572D01*
Y113753D01*
X531888Y112357D01*
G01X518660Y165438D02*
X518692Y165406D01*
Y160400D01*
X536442Y142650D01*
Y139664D01*
X534992Y138214D01*
Y130509D01*
X533203Y128720D01*
Y119500D01*
G01X532938Y171200D02*
X557692Y146446D01*
Y133500D01*
G01X534102Y173600D02*
X560211Y147491D01*
Y140500D01*
G01X511010Y167318D02*
Y159318D01*
X508146Y156454D01*
Y155746D01*
X509129Y154763D01*
X510049D01*
X510850Y155564D01*
X511770D01*
X515703Y151631D01*
Y150711D01*
X514826Y149834D01*
X513906D01*
X511770Y151970D01*
X510850D01*
X509896Y151016D01*
Y149992D01*
X524392Y135496D01*
Y132500D01*
G01X513560Y166768D02*
Y158232D01*
X521488Y150304D01*
Y149596D01*
X519996Y148104D01*
X519288D01*
X518328Y149064D01*
X517620D01*
X516428Y147872D01*
Y147024D01*
X526911Y136541D01*
Y125000D01*
G01X529692Y167319D02*
X547328Y149683D01*
Y144519D01*
X547978Y143869D01*
X551978D01*
X552628Y143219D01*
Y134350D01*
X551978Y133700D01*
X550628D01*
X549978Y134350D01*
Y137150D01*
X549328Y137800D01*
X547978D01*
X547328Y137150D01*
Y120500D01*
G01X531592Y168982D02*
X555147Y145427D01*
Y139000D01*
G01X522392Y164900D02*
Y161927D01*
X523099Y161220D01*
X523806D01*
X524514Y160513D01*
Y159805D01*
X525498Y158821D01*
X526206D01*
X526913Y158114D01*
Y157406D01*
X540992Y143327D01*
Y141000D01*
G01X525942Y164800D02*
Y163050D01*
X543659Y145333D01*
Y126500D01*
G01X521242Y164900D02*
Y161450D01*
X539842Y142850D01*
Y139500D01*
X537511Y137169D01*
Y135500D01*
G01X527092Y164800D02*
Y163527D01*
X527799Y162820D01*
X528506D01*
X529214Y162113D01*
Y161405D01*
X529998Y160621D01*
X530706D01*
X531413Y159914D01*
Y159206D01*
X532198Y158421D01*
X532906D01*
X533613Y157714D01*
Y157006D01*
X534320Y156299D01*
X535027D01*
X535735Y155592D01*
Y154884D01*
X536442Y154177D01*
X537149D01*
X537857Y153470D01*
Y152762D01*
X544809Y145810D01*
Y135000D01*
G01X458643Y372197D02*
X460893D01*
G01X434983Y374146D02*
X437233D01*
G01X438363Y368296D02*
X440613D01*
G01X431604D02*
X433854D01*
G01X431604Y376096D02*
X433854D01*
G01X441293Y443500D02*
X444492D01*
X451392Y450400D01*
Y460426D01*
X476421Y485455D01*
Y486431D01*
X475061Y487791D01*
Y488816D01*
X475988Y489743D01*
X476915D01*
X478324Y488334D01*
X479300D01*
X482192Y491226D01*
Y507646D01*
X484342Y509796D01*
Y511150D01*
X480392Y515100D01*
Y516858D01*
X481691Y518157D01*
G01X419892Y443500D02*
Y455700D01*
X423092Y458900D01*
Y472976D01*
X444092Y493976D01*
Y498400D01*
X450992Y505300D01*
Y506900D01*
X453545Y509453D01*
Y510947D01*
X452492Y512000D01*
Y517238D01*
X451573Y518157D01*
G01X422435Y443457D02*
Y454543D01*
X425692Y457800D01*
Y471986D01*
X447890Y494184D01*
Y495469D01*
X446987Y496372D01*
Y497194D01*
X448083Y498290D01*
X448956D01*
X451009Y496237D01*
X451929D01*
X452912Y497220D01*
Y498140D01*
X450733Y500319D01*
Y501489D01*
X452057Y502813D01*
X452824D01*
X453707Y501930D01*
X454702D01*
X455913Y503141D01*
Y504362D01*
X454526Y505749D01*
Y506733D01*
X456291Y508498D01*
Y511442D01*
X454619Y513114D01*
G01X441042Y448150D02*
X446192Y453300D01*
Y462742D01*
X457780Y474330D01*
Y479046D01*
X460609Y481875D01*
X461534D01*
X462736Y480673D01*
X463712D01*
X464639Y481600D01*
Y482627D01*
X463488Y483778D01*
Y484754D01*
X475592Y496858D01*
Y508100D01*
X477092Y509600D01*
Y511126D01*
X472892Y515326D01*
Y516051D01*
X474998Y518157D01*
G01X441743Y381947D02*
X443993D01*
G01X441743Y389747D02*
X443993D01*
G01X451883Y383896D02*
X454133D01*
G01X451883Y387796D02*
X454133D01*
G01X438363Y383896D02*
X440613D01*
G01X438363Y387796D02*
X440613D01*
G01X448503Y381947D02*
X450753D01*
G01X448503Y389747D02*
X450753D01*
G01X462023Y381947D02*
X464273D01*
G01X462023Y389747D02*
X464273D01*
G01X472163Y383896D02*
X474413D01*
G01X472163Y387796D02*
X474413D01*
G01X458643Y383896D02*
X460893D01*
G01X458643Y387796D02*
X460893D01*
G01X468783Y381947D02*
X471033D01*
G01X468783Y389747D02*
X471033D01*
G01X431192Y448100D02*
Y449700D01*
X438762Y457270D01*
Y469914D01*
X468792Y499944D01*
Y502000D01*
X468042Y502750D01*
Y505050D01*
X468792Y505800D01*
Y511328D01*
X464820Y515300D01*
X464732D01*
G01X445123Y383896D02*
X447373D01*
G01X465403Y379996D02*
X467653D01*
G01X445123Y391696D02*
X447373D01*
G01X465403D02*
X467653D01*
G01X430042Y448100D02*
Y450177D01*
X437612Y457747D01*
Y461050D01*
X437112Y461550D01*
Y462850D01*
X437612Y463350D01*
Y466550D01*
X437112Y467050D01*
Y468350D01*
X437612Y468850D01*
Y470391D01*
X449743Y482522D01*
Y483229D01*
X450663Y484149D01*
X451370D01*
X467642Y500421D01*
Y501523D01*
X466892Y502273D01*
Y505527D01*
X467642Y506277D01*
Y510851D01*
X465793Y512700D01*
X464732D01*
G01X445123Y379996D02*
X447373D01*
G01X465403Y383896D02*
X467653D01*
G01X435103Y446289D02*
Y447510D01*
X443355Y455762D01*
Y466018D01*
X442514Y466859D01*
Y467879D01*
X443472Y468837D01*
X444288D01*
X445079Y468046D01*
X447105D01*
X449125Y470066D01*
Y472259D01*
X448387Y472997D01*
Y473989D01*
X449611Y475213D01*
X450754D01*
X451642Y474325D01*
X453387D01*
X455185Y476123D01*
Y478069D01*
X454607Y478647D01*
Y479659D01*
X472902Y497954D01*
Y512445D01*
X469833Y515514D01*
X469832D01*
G01X445123Y387796D02*
X447373D01*
G01X465403D02*
X467653D01*
G01X421464Y389747D02*
X423714D01*
G01X421464Y393647D02*
X423714D01*
G01X431604Y383896D02*
X433854D01*
G01X431604Y387796D02*
X433854D01*
G01X421464Y378047D02*
X423714D01*
G01X421464Y381947D02*
X423714D01*
G01X428224D02*
X430474D01*
G01X428224Y389747D02*
X430474D01*
G01X463592Y449100D02*
X464392Y449900D01*
Y453372D01*
X486720Y475700D01*
X491092D01*
X496392Y481000D01*
Y485500D01*
X493992Y487900D01*
Y492400D01*
X493192Y493200D01*
Y494500D01*
X492192Y495500D01*
Y501000D01*
X492892Y501700D01*
X496392D01*
X497077Y501015D01*
Y499485D01*
X496079Y498487D01*
X494777D01*
G01X466192Y448100D02*
X467392Y449300D01*
Y452500D01*
X469792Y454900D01*
X473700D01*
X475692Y456892D01*
Y457990D01*
X474786Y458896D01*
Y459994D01*
X475562Y460770D01*
X476660D01*
X477566Y459864D01*
X478664D01*
X479440Y460640D01*
Y461738D01*
X478534Y462644D01*
Y463742D01*
X479310Y464518D01*
X480408D01*
X481314Y463612D01*
X482412D01*
X483188Y464388D01*
Y465486D01*
X482282Y466392D01*
Y467490D01*
X483058Y468266D01*
X484156D01*
X485062Y467360D01*
X486160D01*
X486936Y468136D01*
Y469234D01*
X486030Y470140D01*
Y471238D01*
X486806Y472014D01*
X487904D01*
X488810Y471108D01*
X489908D01*
X491296Y472496D01*
X491596D01*
X499492Y480392D01*
Y484904D01*
X500317Y485729D01*
Y489000D01*
X498423Y490894D01*
X497723D01*
G01X485792Y443500D02*
X494981Y452689D01*
X500889D01*
X504580Y456380D01*
X507355D01*
X509924Y458949D01*
Y464295D01*
X520832Y475203D01*
Y487160D01*
X519192Y488800D01*
Y494500D01*
X519692Y495000D01*
Y496697D01*
X517902Y498487D01*
G01X487592Y441700D02*
X496000Y450108D01*
X501913D01*
X505663Y453858D01*
X509723D01*
X512497Y456632D01*
Y458153D01*
X513147Y458803D01*
X515351D01*
X516001Y459453D01*
Y460803D01*
X515351Y461453D01*
X513147D01*
X512497Y462103D01*
Y463288D01*
X523392Y474183D01*
Y488300D01*
X522892Y488800D01*
Y492000D01*
X521048Y493844D01*
G01X458392Y451400D02*
Y457922D01*
X467263Y466793D01*
X468183D01*
X468762Y466214D01*
X469682D01*
X470636Y467168D01*
Y468088D01*
X470018Y468706D01*
Y469626D01*
X470972Y470580D01*
X471892D01*
X472510Y469962D01*
X473430D01*
X474384Y470916D01*
Y471836D01*
X473805Y472415D01*
Y473335D01*
X484570Y484100D01*
X488092D01*
X488892Y484900D01*
Y492100D01*
X489592Y492800D01*
Y494500D01*
X490192Y495100D01*
Y496679D01*
X488384Y498487D01*
G01X460992Y450300D02*
X461392Y450700D01*
Y454200D01*
X463564Y456372D01*
Y457292D01*
X462926Y457930D01*
Y458850D01*
X463880Y459804D01*
X464800D01*
X465438Y459166D01*
X466358D01*
X467312Y460120D01*
Y461040D01*
X466674Y461678D01*
Y462598D01*
X467628Y463552D01*
X468548D01*
X469186Y462914D01*
X470106D01*
X476919Y469727D01*
Y472695D01*
X478008Y473784D01*
X478928D01*
X479623Y473089D01*
X480543D01*
X481497Y474043D01*
Y474963D01*
X480802Y475658D01*
Y476578D01*
X481756Y477532D01*
X482676D01*
X483371Y476837D01*
X484291D01*
X485245Y477791D01*
Y478711D01*
X484678Y479278D01*
Y479986D01*
X485844Y481152D01*
X486552D01*
X488804Y478900D01*
X490492D01*
X493031Y481439D01*
Y484661D01*
X491430Y486262D01*
Y491144D01*
G01X480242Y445950D02*
X495940Y461648D01*
X499441D01*
X511717Y473924D01*
X511716Y474898D01*
X511191Y475423D01*
Y476397D01*
X512119Y477325D01*
X513095D01*
X513619Y476801D01*
X514594D01*
X515644Y477851D01*
Y485148D01*
X512592Y488200D01*
Y494100D01*
X513492Y495000D01*
Y496804D01*
X511809Y498487D01*
G01X520792Y438001D02*
Y439501D01*
X526692Y445401D01*
Y447188D01*
X521884Y451994D01*
Y453090D01*
X522662Y453868D01*
X523758D01*
X526511Y451116D01*
X527607D01*
X527992Y451501D01*
Y465200D01*
X534392Y471600D01*
Y485201D01*
X532666Y486927D01*
Y497709D01*
X531988Y498387D01*
X530792D01*
G01X515592Y438200D02*
Y439400D01*
X509892Y445100D01*
Y448500D01*
X522392Y461000D01*
Y467499D01*
X526792Y471899D01*
Y489500D01*
X526392Y489900D01*
Y496590D01*
X524595Y498387D01*
G01X518192Y437650D02*
Y440600D01*
X513092Y445700D01*
Y448100D01*
X514592Y449600D01*
X515690D01*
X518392Y446898D01*
X519490D01*
X520266Y447674D01*
Y448772D01*
X517564Y451474D01*
Y452572D01*
X525092Y460100D01*
Y466200D01*
X529649Y470757D01*
Y487757D01*
X530116Y488224D01*
Y491619D01*
X528191Y493544D01*
G01X530988Y428996D02*
X548039Y446047D01*
Y474947D01*
X550882Y477790D01*
Y483610D01*
X549292Y485200D01*
Y493900D01*
X550292Y494900D01*
Y496815D01*
X548707Y498400D01*
X548492D01*
G01X472163Y368296D02*
X474413D01*
G01X472163Y376096D02*
X474413D01*
G01X468783Y370247D02*
X471033D01*
G01X468783Y374146D02*
X471033D01*
G01X424844Y383896D02*
X427094D01*
G01X474953Y450934D02*
X492839Y468820D01*
X494712D01*
X504572Y478680D01*
Y493300D01*
X503255Y494617D01*
X503155D01*
X501605Y496167D01*
X501560D01*
G01X527392Y435000D02*
X541042Y448650D01*
Y480351D01*
X541416Y480725D01*
Y491790D01*
X540266Y492940D01*
Y494013D01*
X538370Y495909D01*
G01X475542Y370247D02*
X477792D01*
G01X424844Y391696D02*
X427094D01*
G01X475542Y378047D02*
X477792D01*
G01X424844Y379996D02*
X427094D01*
G01X474140Y451748D02*
X492362Y469970D01*
X494235D01*
X495392Y471127D01*
Y472135D01*
X496157Y472900D01*
X497165D01*
X498092Y473827D01*
Y474835D01*
X498757Y475500D01*
X499765D01*
X500992Y476727D01*
Y477735D01*
X501623Y478366D01*
X502631D01*
X503422Y479157D01*
Y492823D01*
X502778Y493467D01*
X501560D01*
G01X526578Y435813D02*
X527285Y436520D01*
Y437227D01*
X527992Y437935D01*
X528700D01*
X529407Y438642D01*
Y439349D01*
X530114Y440057D01*
X530822D01*
X531529Y440764D01*
Y441471D01*
X532236Y442179D01*
X532944D01*
X533651Y442886D01*
Y443593D01*
X534358Y444301D01*
X535066D01*
X535773Y445008D01*
Y445715D01*
X536480Y446423D01*
X537188D01*
X539892Y449127D01*
Y480828D01*
X540266Y481202D01*
Y491313D01*
X538370Y493209D01*
G01X475542Y366347D02*
X477792D01*
G01X424844Y387796D02*
X427094D01*
G01X476992Y446500D02*
X494692Y464200D01*
X498092D01*
X508285Y474393D01*
Y479980D01*
X509064Y480759D01*
X510769D01*
X511942Y481932D01*
Y485136D01*
X510769Y486309D01*
X509068D01*
X508492Y486885D01*
Y488100D01*
X509766Y489374D01*
Y493045D01*
X506644Y496167D01*
G01X543455Y496209D02*
Y496181D01*
X546716Y492920D01*
Y486324D01*
X545316Y484924D01*
Y483550D01*
X545966Y482900D01*
X547137D01*
X548310Y481727D01*
Y479123D01*
X547137Y477950D01*
X545766D01*
X545362Y477546D01*
Y447011D01*
X530392Y432041D01*
G01X475542Y374146D02*
X477792D01*
G01X424844Y364396D02*
X427094D01*
G01X421464Y370247D02*
X423714D01*
G01X434983Y366347D02*
X437233D01*
G01X434983Y370247D02*
X437233D01*
G01X421464Y366347D02*
X423714D01*
G01X431604Y364396D02*
X433854D01*
G01X431604Y372197D02*
X433854D01*
G01X451883Y368296D02*
X454133D01*
G01X451883Y376096D02*
X454133D01*
G01X462023Y370247D02*
X464273D01*
G01X462023Y374146D02*
X464273D01*
G01X448503Y370247D02*
X450753D01*
G01X448503Y374146D02*
X450753D01*
G01X458643Y368296D02*
X460893D01*
G01X458643Y376096D02*
X460893D01*
G01X441743Y354647D02*
X443993D01*
G01X441743Y362447D02*
X443993D01*
G01X451883Y356596D02*
X454133D01*
G01X451883Y360496D02*
X454133D01*
G01X438363Y356596D02*
X440613D01*
G01X438363Y360496D02*
X440613D01*
G01X448503Y354647D02*
X450753D01*
G01X448503Y362447D02*
X450753D01*
G01X462023Y354647D02*
X464273D01*
G01X462023Y362447D02*
X464273D01*
G01X472163Y356596D02*
X474413D01*
G01X472163Y360496D02*
X474413D01*
G01X458643Y356596D02*
X460893D01*
G01X458643Y360496D02*
X460893D01*
G01X468783Y354647D02*
X471033D01*
G01X468783Y362447D02*
X471033D01*
G01X428224Y366347D02*
X430474D01*
G01X455263Y370247D02*
X457513D01*
G01X445123Y356596D02*
X447373D01*
G01X465403D02*
X467653D01*
G01X428224Y370247D02*
X430474D01*
G01X455263Y378047D02*
X457513D01*
G01X445123Y364396D02*
X447373D01*
G01X465403D02*
X467653D01*
G01X428224Y362447D02*
X430474D01*
G01X455263Y366347D02*
X457513D01*
G01X445123Y352696D02*
X447373D01*
G01X465403D02*
X467653D01*
G01X428224Y374146D02*
X430474D01*
G01X455263D02*
X457513D01*
G01X445123Y360496D02*
X447373D01*
G01X465403D02*
X467653D01*
G01X424954Y443937D02*
Y453263D01*
X428292Y456601D01*
Y470984D01*
X449108Y491800D01*
X451308D01*
X456786Y497278D01*
Y498254D01*
X455813Y499227D01*
Y500253D01*
X456740Y501180D01*
X457666D01*
X458689Y500157D01*
X459665D01*
X460592Y501084D01*
Y502500D01*
X458092Y505000D01*
Y506100D01*
X460092Y508100D01*
Y510900D01*
X456492Y514500D01*
Y516383D01*
X458266Y518157D01*
G01X427473Y446981D02*
Y452008D01*
X434236Y458771D01*
Y460176D01*
X433460Y460952D01*
X431668D01*
X430892Y461728D01*
Y462826D01*
X431668Y463602D01*
X433460D01*
X434236Y464378D01*
Y465476D01*
X433460Y466252D01*
X431668D01*
X430892Y467028D01*
Y468126D01*
X431668Y468902D01*
X433460D01*
X434236Y469678D01*
Y472275D01*
X434886Y472925D01*
X436468D01*
X437840Y474297D01*
Y475192D01*
X437422Y475610D01*
Y476530D01*
X438794Y477902D01*
X439714D01*
X440158Y477458D01*
X440977D01*
X442349Y478830D01*
Y479851D01*
X442006Y480194D01*
Y481114D01*
X443378Y482486D01*
X444298D01*
X444741Y482043D01*
X445560D01*
X446932Y483415D01*
Y484436D01*
X446590Y484778D01*
Y485698D01*
X447962Y487070D01*
X448882D01*
X449149Y486803D01*
X450069D01*
X462492Y499226D01*
Y502427D01*
X463142Y503077D01*
X463942D01*
X464592Y503727D01*
Y505667D01*
X463942Y506317D01*
X463142D01*
X462345Y507114D01*
Y508621D01*
X462908Y509184D01*
Y512184D01*
X461978Y513114D01*
X460912D01*
G01X441092Y440900D02*
X445992D01*
X454292Y449200D01*
Y459568D01*
X484892Y490168D01*
Y501400D01*
X485949Y502457D01*
Y503377D01*
X484374Y504952D01*
Y505997D01*
X485746Y507369D01*
X486541D01*
X488241Y505669D01*
X489161D01*
X490492Y507000D01*
Y510900D01*
X488278Y513114D01*
X485037D01*
G01X442792Y446000D02*
X448792Y452000D01*
Y461584D01*
X461462Y474254D01*
Y475201D01*
X460304Y476359D01*
Y477068D01*
X461395Y478159D01*
X462252D01*
X463331Y477080D01*
X464288D01*
X468492Y481284D01*
Y482532D01*
X467183Y483841D01*
Y484880D01*
X468310Y486007D01*
X469223D01*
X470798Y484432D01*
X471774D01*
X472701Y485359D01*
Y486335D01*
X471252Y487784D01*
Y488760D01*
X475442Y492950D01*
X478942D01*
X479592Y493600D01*
Y495540D01*
X478942Y496190D01*
X478842D01*
X478192Y496840D01*
Y499880D01*
X478742Y500430D01*
X479398D01*
X480073Y501105D01*
Y503045D01*
X479448Y503670D01*
X478070D01*
X477570Y504170D01*
Y506920D01*
X479792Y509142D01*
Y511666D01*
X478344Y513114D01*
G01X433892Y446350D02*
X433953Y446411D01*
Y447987D01*
X435460Y449494D01*
Y450201D01*
X436168Y450909D01*
X436875D01*
X437582Y451616D01*
Y452323D01*
X438290Y453031D01*
X438997D01*
X439704Y453738D01*
Y454445D01*
X440412Y455153D01*
X441119D01*
X442205Y456239D01*
Y460739D01*
X441705Y461239D01*
Y462239D01*
X442205Y462739D01*
Y465541D01*
X441364Y466382D01*
Y468356D01*
X442995Y469987D01*
X444765D01*
X445556Y469196D01*
X446628D01*
X447975Y470543D01*
Y471782D01*
X447237Y472520D01*
Y474466D01*
X449134Y476363D01*
X451231D01*
X452119Y475475D01*
X452910D01*
X454035Y476600D01*
Y477592D01*
X453457Y478170D01*
Y480136D01*
X455621Y482300D01*
Y483178D01*
X456329Y483885D01*
X457206D01*
X457913Y484592D01*
Y485469D01*
X458620Y486176D01*
X459497D01*
X460292Y486971D01*
Y487849D01*
X461000Y488556D01*
X461877D01*
X462584Y489263D01*
Y490141D01*
X463292Y490848D01*
X464169D01*
X464876Y491555D01*
Y492433D01*
X465584Y493140D01*
X466461D01*
X467168Y493847D01*
Y494725D01*
X467876Y495432D01*
X468753D01*
X469460Y496139D01*
Y497017D01*
X470168Y497724D01*
X471045D01*
X471752Y498431D01*
Y499577D01*
X471252Y500077D01*
Y501077D01*
X471752Y501577D01*
Y502577D01*
X471252Y503077D01*
Y504077D01*
X471752Y504577D01*
Y505577D01*
X471252Y506077D01*
Y507077D01*
X471752Y507577D01*
Y508577D01*
X471252Y509077D01*
Y510077D01*
X471752Y510577D01*
Y511968D01*
X470806Y512914D01*
X469832D01*
G01X483492Y445600D02*
X495969Y458077D01*
X496677D01*
X497269Y457485D01*
Y455743D01*
X497804Y455208D01*
X499658D01*
X500194Y455744D01*
Y458829D01*
X502086Y460721D01*
X503534D01*
X505313Y458942D01*
X506310D01*
X507264Y459896D01*
Y460739D01*
X505408Y462595D01*
Y463515D01*
X518301Y476408D01*
Y486091D01*
X516592Y487800D01*
Y491907D01*
X514755Y493744D01*
G01X522792Y436700D02*
X531792Y445700D01*
Y463150D01*
X532442Y463800D01*
X533792D01*
X534442Y463150D01*
Y456750D01*
X535092Y456100D01*
X536442D01*
X537092Y456750D01*
Y488900D01*
X536466Y489526D01*
Y492894D01*
X535966Y493394D01*
X534534D01*
G01X476265Y447400D02*
X476759Y447895D01*
Y448603D01*
X477254Y449098D01*
X477962D01*
X478456Y449592D01*
Y450301D01*
X478951Y450796D01*
X479660D01*
X480154Y451290D01*
Y451999D01*
X480649Y452494D01*
X481357D01*
X481851Y452988D01*
Y453697D01*
X482346Y454192D01*
X483055D01*
X483549Y454686D01*
Y455395D01*
X484044Y455890D01*
X484753D01*
X485247Y456384D01*
Y457093D01*
X485742Y457588D01*
X486451D01*
X486945Y458082D01*
Y458791D01*
X487440Y459286D01*
X488149D01*
X488643Y459780D01*
Y460489D01*
X489138Y460984D01*
X489847D01*
X490341Y461478D01*
Y462187D01*
X490836Y462682D01*
X491547D01*
X492041Y463176D01*
Y463885D01*
X492536Y464380D01*
X493245D01*
X494215Y465350D01*
X497615D01*
X498392Y466127D01*
Y467135D01*
X498957Y467700D01*
X499965D01*
X500792Y468527D01*
Y469535D01*
X501357Y470100D01*
X502365D01*
X503192Y470927D01*
Y471935D01*
X503757Y472500D01*
X504765D01*
X507135Y474870D01*
Y475856D01*
X506595Y476396D01*
Y477104D01*
X507135Y477644D01*
Y480457D01*
X508587Y481909D01*
X510292D01*
X510792Y482409D01*
Y484659D01*
X510292Y485159D01*
X508591D01*
X507342Y486408D01*
Y488577D01*
X508616Y489851D01*
Y492568D01*
X507617Y493567D01*
X506644D01*
G01X529628Y432900D02*
X530334Y433607D01*
Y434314D01*
X531041Y435022D01*
X531749D01*
X532455Y435729D01*
Y436436D01*
X533162Y437144D01*
X533870D01*
X534576Y437851D01*
Y438558D01*
X535283Y439266D01*
X535991D01*
X536697Y439973D01*
Y440680D01*
X537404Y441388D01*
X538112D01*
X538818Y442095D01*
Y442802D01*
X539525Y443510D01*
X540233D01*
X540940Y444217D01*
X540939Y444924D01*
X541646Y445632D01*
X542355D01*
X544212Y447490D01*
Y450408D01*
X543712Y450908D01*
Y451908D01*
X544212Y452408D01*
Y453408D01*
X543712Y453908D01*
Y454908D01*
X544212Y455408D01*
Y456408D01*
X543712Y456908D01*
Y457908D01*
X544212Y458408D01*
Y459500D01*
X543712Y460000D01*
Y461000D01*
X544212Y461500D01*
Y462500D01*
X543712Y463000D01*
Y464000D01*
X544212Y464500D01*
Y465500D01*
X543712Y466000D01*
Y467000D01*
X544212Y467500D01*
Y468500D01*
X543712Y469000D01*
Y470000D01*
X544212Y470500D01*
Y471500D01*
X543712Y472000D01*
Y473000D01*
X544212Y473500D01*
Y474500D01*
X543712Y475000D01*
Y476000D01*
X544212Y476500D01*
Y478023D01*
X545289Y479100D01*
X546660D01*
X547160Y479600D01*
Y481250D01*
X546660Y481750D01*
X545489D01*
X544166Y483073D01*
Y485401D01*
X545566Y486801D01*
Y487600D01*
X545066Y488100D01*
Y489100D01*
X545566Y489600D01*
Y492426D01*
X544483Y493509D01*
X543455D01*
G01X418874Y498682D02*
X428492Y508300D01*
Y510300D01*
X429946Y511754D01*
Y514146D01*
X429592Y514500D01*
Y516200D01*
X431292Y517900D01*
Y523721D01*
X431483Y523912D01*
X431494Y523900D01*
G01X444880D02*
Y518388D01*
X443092Y516600D01*
Y514300D01*
X443792Y513600D01*
Y511700D01*
X442542Y510450D01*
Y508750D01*
X441205Y507413D01*
X439668Y506776D01*
X427596Y494704D01*
G01X458266Y523900D02*
Y528899D01*
G01X451573Y523900D02*
Y528899D01*
G01X474998Y523900D02*
Y528899D01*
G01X468305Y523900D02*
Y526495D01*
X466658Y528142D01*
Y529800D01*
X467390Y530532D01*
Y531503D01*
X466398Y532495D01*
X465578D01*
X464833Y531750D01*
X464758D01*
G01X464958Y523900D02*
Y526352D01*
X463241Y528069D01*
X462992Y528610D01*
X462908Y528792D01*
Y532013D01*
X463229Y532896D01*
X464732Y534399D01*
G01X421455Y523900D02*
Y529021D01*
X421456Y529022D01*
G01X438187Y523900D02*
Y517995D01*
X436127Y515935D01*
Y514331D01*
X436892Y513566D01*
Y511500D01*
X436392Y511000D01*
Y509400D01*
X419651Y492659D01*
G01X444880Y542010D02*
Y536959D01*
X444882Y536957D01*
G01X461612Y542010D02*
Y542033D01*
X460912Y534700D01*
G01X454919Y542010D02*
Y536792D01*
X454533Y534700D01*
G01X468305Y542010D02*
X468304D01*
Y537805D01*
X466800Y536301D01*
Y534601D01*
X468101Y533300D01*
X468983D01*
X469832Y534149D01*
G01X471651Y542010D02*
Y538049D01*
X471800Y537900D01*
Y532500D01*
X470840Y531540D01*
X469832D01*
G01X428147Y542010D02*
Y536959D01*
X428149Y536957D01*
G01X434840Y542010D02*
Y536959D01*
X434842Y536957D01*
G01X431494Y561700D02*
Y566807D01*
G01X444880Y561700D02*
Y566822D01*
G01Y579810D02*
Y574759D01*
X444882Y574757D01*
G01X461612Y579810D02*
Y579833D01*
X460912Y572500D01*
G01X458266Y561700D02*
Y566699D01*
G01X454919Y579810D02*
Y574592D01*
X454533Y572500D01*
G01X451573Y561700D02*
Y566699D01*
G01X474998Y561700D02*
Y566699D01*
G01X468305Y561700D02*
Y564295D01*
X466658Y565942D01*
Y567600D01*
X467390Y568332D01*
Y569303D01*
X466398Y570295D01*
X465578D01*
X464833Y569550D01*
X464758D01*
G01X468305Y579810D02*
X468304D01*
Y575605D01*
X466800Y574101D01*
Y572401D01*
X468101Y571100D01*
X468983D01*
X469832Y571949D01*
G01X464958Y561700D02*
Y564152D01*
X463241Y565869D01*
X462908Y566592D01*
Y569813D01*
X463229Y570696D01*
X464732Y572199D01*
G01X471651Y579810D02*
Y575849D01*
X471800Y575700D01*
Y570300D01*
X470840Y569340D01*
X469832D01*
G01X428147Y579810D02*
Y574759D01*
X428149Y574757D01*
G01X421455Y561700D02*
Y566821D01*
X421456Y566822D01*
G01X434840Y579810D02*
Y574759D01*
X434842Y574757D01*
G01X424801Y561700D02*
Y566807D01*
G01X438187Y561700D02*
Y566820D01*
X438189Y566822D01*
G01X438187Y617610D02*
Y609864D01*
G01X431494Y599500D02*
Y604499D01*
G01X444880Y599500D02*
Y604614D01*
G01Y617610D02*
Y609864D01*
G01X461612Y617610D02*
Y617633D01*
X460912Y610300D01*
G01X458266Y599500D02*
Y604499D01*
G01X454919Y617610D02*
Y612392D01*
X454533Y610300D01*
G01X451573Y599500D02*
Y604499D01*
G01X474998Y599500D02*
Y604499D01*
G01X468305Y599500D02*
Y602095D01*
X466658Y603742D01*
Y605400D01*
X467390Y606132D01*
Y607103D01*
X466398Y608095D01*
X465578D01*
X464833Y607350D01*
X464758D01*
G01X468305Y617610D02*
X468304D01*
Y613405D01*
X466800Y611901D01*
Y610201D01*
X468101Y608900D01*
X468983D01*
X469832Y609749D01*
G01X464958Y599500D02*
Y601952D01*
X463241Y603669D01*
X462908Y604392D01*
Y607613D01*
X463229Y608496D01*
X464732Y609999D01*
G01X471651Y617610D02*
Y613649D01*
X471800Y613500D01*
Y608100D01*
X470840Y607140D01*
X469833D01*
G01X428147Y617610D02*
Y612657D01*
G01X421455Y599500D02*
Y607291D01*
X421454Y607292D01*
G01X434840Y617610D02*
Y612657D01*
G01X424801Y599500D02*
Y604614D01*
G01X438187Y599500D02*
Y604614D01*
G01X481691Y22923D02*
Y27899D01*
G01X495077Y22923D02*
Y27899D01*
G01X518502Y22923D02*
Y27899D01*
G01X488384Y22923D02*
Y27899D01*
G01X511809Y22923D02*
Y27899D01*
G01X531888Y22923D02*
Y27899D01*
G01X525195Y22923D02*
Y27899D01*
G01X505116Y22923D02*
X505115D01*
Y25496D01*
X503469Y27142D01*
Y28800D01*
X504201Y29532D01*
Y30503D01*
X503209Y31495D01*
X502389D01*
X501644Y30750D01*
X501569D01*
G01X541927Y22923D02*
Y25496D01*
X540281Y27142D01*
Y28800D01*
X541013Y29532D01*
Y30503D01*
X540021Y31495D01*
X539201D01*
X538456Y30750D01*
X538381D01*
G01X505116Y41033D02*
X505115Y41032D01*
Y36805D01*
X503593Y35283D01*
Y33619D01*
X504912Y32300D01*
X505794D01*
X506643Y33149D01*
G01X501770Y22923D02*
Y25351D01*
X500053Y27068D01*
X499720Y27792D01*
Y31013D01*
X500041Y31896D01*
Y31897D01*
X501543Y33399D01*
G01X538581Y22923D02*
Y25351D01*
X536864Y27068D01*
X536531Y27792D01*
Y31013D01*
X536852Y31896D01*
X538355Y33399D01*
G01X508462Y41033D02*
Y37049D01*
X508611Y36900D01*
Y31500D01*
X507651Y30540D01*
X506643D01*
G01X485037Y3233D02*
Y-692D01*
X485555Y-1210D01*
Y-2090D01*
X485037Y-2608D01*
Y-3700D01*
G01X481691Y-14877D02*
Y-9901D01*
G01X478344Y3233D02*
X478345Y3232D01*
Y-600D01*
X478865Y-1120D01*
Y-1980D01*
X478345Y-2500D01*
Y-3699D01*
X478344Y-3700D01*
G01X498423Y3233D02*
X497723Y-4100D01*
G01X495077Y-14877D02*
Y-9901D01*
G01X521848Y3233D02*
Y-692D01*
X522366Y-1210D01*
Y-2090D01*
X521848Y-2608D01*
Y-3700D01*
G01X518502Y-14877D02*
Y-9901D01*
G01X491730Y3233D02*
Y-2008D01*
X491344Y-4100D01*
G01X488384Y-14877D02*
Y-9901D01*
G01X515155Y3233D02*
X515156Y3232D01*
Y-600D01*
X515676Y-1120D01*
Y-1980D01*
X515156Y-2500D01*
Y-3699D01*
X515155Y-3700D01*
G01X511809Y-14877D02*
Y-9901D01*
G01X535234Y3233D02*
X534534Y-4100D01*
G01X531888Y-14877D02*
Y-9901D01*
G01X528541Y3233D02*
Y-2008D01*
X528155Y-4100D01*
G01X525195Y-14877D02*
Y-9901D01*
G01X505116Y-14877D02*
Y-11560D01*
X503470Y-9914D01*
Y-9000D01*
X504202Y-8268D01*
Y-7297D01*
X503210Y-6305D01*
X502390D01*
X501645Y-7050D01*
X501570D01*
G01X541927Y-14877D02*
Y-11560D01*
X540281Y-9914D01*
Y-9000D01*
X541013Y-8268D01*
Y-7297D01*
X540021Y-6305D01*
X539201D01*
X538456Y-7050D01*
X538381D01*
G01X505116Y3233D02*
Y-755D01*
X504070Y-1801D01*
Y-4686D01*
X506644Y-7260D01*
G01X501770Y-14877D02*
Y-12449D01*
X500053Y-10732D01*
X499720Y-10008D01*
Y-6787D01*
X500041Y-5904D01*
X501544Y-4401D01*
G01X538581Y-14877D02*
Y-12449D01*
X536864Y-10732D01*
X536531Y-10008D01*
Y-6787D01*
X536852Y-5904D01*
X538355Y-4401D01*
G01X508462Y3233D02*
Y-1092D01*
X509335Y-1965D01*
Y-4887D01*
X508493Y-5729D01*
X507722D01*
X506644Y-4651D01*
G01X485037Y78833D02*
Y74908D01*
X485555Y74390D01*
Y73510D01*
X485037Y72992D01*
Y71900D01*
G01X481691Y104000D02*
Y97201D01*
X484192Y94700D01*
Y92801D01*
X483492Y92101D01*
Y91490D01*
X483178Y91176D01*
Y90234D01*
X482292Y89348D01*
X481584D01*
X480592Y90340D01*
Y91658D01*
X481691Y92757D01*
G01X481792Y112900D02*
X484492Y110200D01*
Y101700D01*
X490738Y95454D01*
Y92546D01*
X487961Y89769D01*
X487092D01*
X485037Y87714D01*
G01X481691Y60723D02*
Y65699D01*
G01X478344Y78833D02*
X478345Y78832D01*
Y75000D01*
X478865Y74480D01*
Y73620D01*
X478345Y73100D01*
Y71901D01*
X478344Y71900D01*
G01X498423Y78833D02*
X498105Y75500D01*
X497723Y71500D01*
G01X495077Y60723D02*
Y65699D01*
G01X521848Y78833D02*
Y74908D01*
X522366Y74390D01*
Y73510D01*
X521848Y72992D01*
Y71900D01*
G01X518502Y60723D02*
Y65699D01*
G01X491730Y78833D02*
Y73592D01*
X491344Y71500D01*
G01X488384Y60723D02*
Y65699D01*
G01X515155Y78833D02*
X515156Y78832D01*
Y75000D01*
X515676Y74480D01*
Y73620D01*
X515156Y73100D01*
Y71901D01*
X515155Y71900D01*
G01X511809Y60723D02*
Y65699D01*
G01X535234Y78833D02*
X534916Y75500D01*
X534534Y71500D01*
G01X531888Y60723D02*
Y65699D01*
G01X528541Y78833D02*
Y73592D01*
X528155Y71500D01*
G01X525195Y60723D02*
Y65699D01*
G01X505116Y60723D02*
Y63296D01*
X503470Y64942D01*
Y66600D01*
X504202Y67332D01*
Y68303D01*
X503210Y69295D01*
X502390D01*
X501645Y68550D01*
X501570D01*
G01X541927Y60723D02*
Y63296D01*
X540281Y64942D01*
Y66600D01*
X541013Y67332D01*
Y68303D01*
X540021Y69295D01*
X539201D01*
X538456Y68550D01*
X538381D01*
G01X505116Y78833D02*
Y74605D01*
X503612Y73101D01*
Y71401D01*
X504913Y70100D01*
X505795D01*
X506644Y70949D01*
G01X501770Y60723D02*
Y63151D01*
X500053Y64868D01*
X499720Y65592D01*
Y68813D01*
X500041Y69696D01*
X501544Y71199D01*
G01X538581Y60723D02*
Y63151D01*
X536864Y64868D01*
X536531Y65592D01*
Y68813D01*
X536852Y69696D01*
X538355Y71199D01*
G01X508462Y78833D02*
X508463Y78832D01*
Y74849D01*
X508612Y74700D01*
Y69300D01*
X507652Y68340D01*
X506644D01*
G01X485037Y41033D02*
Y37108D01*
X485555Y36590D01*
Y35710D01*
X485037Y35192D01*
Y34100D01*
G01X478344Y41033D02*
X478345Y41032D01*
Y37200D01*
X478865Y36680D01*
Y35820D01*
X478345Y35300D01*
Y34101D01*
X478344Y34100D01*
G01X498423Y41033D02*
X497847Y35000D01*
X497799Y34500D01*
X497723Y33700D01*
G01X521848Y41033D02*
Y37108D01*
X522366Y36590D01*
Y35710D01*
X521848Y35192D01*
Y34100D01*
G01X491730Y41033D02*
Y35792D01*
X491584Y35000D01*
X491492Y34500D01*
X491344Y33700D01*
G01X515155Y41033D02*
X515156Y41032D01*
Y37200D01*
X515676Y36680D01*
Y35820D01*
X515156Y35300D01*
Y34101D01*
X515155Y34100D01*
G01X535234Y41033D02*
X534658Y35000D01*
X534610Y34500D01*
X534534Y33700D01*
G01X528541Y41033D02*
Y35792D01*
X528395Y35000D01*
X528303Y34500D01*
X528155Y33700D01*
G01X496902Y116000D02*
Y111434D01*
X494692Y109224D01*
Y106800D01*
X493092Y105200D01*
Y103300D01*
X494892Y101500D01*
X497073D01*
X497723Y102150D01*
Y106964D01*
G01X516442Y130500D02*
Y128823D01*
X515792Y128173D01*
X514842D01*
X514192Y127523D01*
Y126150D01*
X514842Y125500D01*
X517667D01*
X518317Y124850D01*
Y122549D01*
X517667Y121899D01*
X515142D01*
X514492Y121249D01*
Y119899D01*
X515142Y119249D01*
X517667D01*
X518317Y118599D01*
Y112357D01*
G01X521052Y117000D02*
Y112360D01*
X523092Y110320D01*
Y108943D01*
X521113Y106964D01*
G01X488242Y116350D02*
X490992Y113600D01*
Y111800D01*
X489592Y110400D01*
X488244D01*
X487594Y109750D01*
Y107614D01*
X489008Y106200D01*
X490666D01*
X491430Y106964D01*
G01X508892Y122500D02*
Y117800D01*
X512024Y114668D01*
Y112357D01*
G01X511492Y133000D02*
Y119299D01*
X514681Y116110D01*
Y112337D01*
X512692Y110348D01*
Y107600D01*
X513328Y106964D01*
X514820D01*
G01X533203Y119500D02*
Y113689D01*
X533692Y113200D01*
Y111500D01*
X531692Y109500D01*
Y107600D01*
X529492Y105400D01*
Y102850D01*
X530142Y102200D01*
X532642D01*
X534534Y104092D01*
Y106964D01*
G01X524392Y132500D02*
Y113099D01*
X525134Y112357D01*
G01X526911Y125000D02*
Y115781D01*
X527973Y114719D01*
Y112281D01*
X526266Y110574D01*
Y109289D01*
X528241Y107314D01*
G01X540992Y141000D02*
Y139023D01*
X538661Y136692D01*
Y133458D01*
X540992Y131127D01*
Y129275D01*
X539617Y127900D01*
X537574D01*
X536872Y127198D01*
Y125452D01*
X537574Y124750D01*
X539717D01*
X541092Y123375D01*
Y120918D01*
X539717Y119543D01*
X537372D01*
X536872Y119043D01*
Y115820D01*
X537692Y115000D01*
X539691D01*
X540148Y114543D01*
Y112307D01*
X538355Y110514D01*
G01X537511Y135500D02*
Y132981D01*
X539842Y130650D01*
Y129752D01*
X539140Y129050D01*
X537097D01*
X535722Y127675D01*
Y124975D01*
X537097Y123600D01*
X539240D01*
X539942Y122898D01*
Y121395D01*
X539240Y120693D01*
X536895D01*
X535722Y119520D01*
Y115343D01*
X536392Y114673D01*
Y109854D01*
X538381Y107865D01*
G01X485682Y216196D02*
X483432D01*
G01X485682Y227896D02*
X483432D01*
G01X485682Y220096D02*
X483432D01*
G01X489062Y381947D02*
X491312D01*
G01X481172Y360496D02*
X478922D01*
G01X492442Y356596D02*
X494692D01*
G01X482302Y381947D02*
X484552D01*
G01X482302Y389747D02*
X484552D01*
G01X492442Y395597D02*
X494692D01*
G01X492442Y399496D02*
X494692D01*
G01X481172Y383896D02*
X478922D01*
G01X481172Y387796D02*
X478922D01*
G01X489062Y401447D02*
X491312D01*
G01X489062Y393647D02*
X491312D01*
G01X485682Y379996D02*
X487932D01*
G01X485682Y391696D02*
X487932D01*
G01X485682Y383896D02*
X487932D01*
G01X485682Y387796D02*
X487932D01*
G01X554792Y498487D02*
X554913D01*
X556792Y496608D01*
Y492426D01*
X558180Y491038D01*
Y472988D01*
X553353Y468161D01*
Y441461D01*
X538542Y426650D01*
X537342D01*
G01X538392Y423900D02*
X541392D01*
X556010Y438518D01*
Y466800D01*
X560837Y471627D01*
Y489068D01*
X562546Y490777D01*
Y494277D01*
X560679Y496144D01*
X558659D01*
G01X482302Y374146D02*
X484552D01*
G01X478922Y368296D02*
X481172D01*
G01Y376096D02*
X478922D01*
G01X533242Y427082D02*
X535560Y429400D01*
X537092D01*
X538217Y430525D01*
Y432225D01*
X539241Y433249D01*
X540941D01*
X541965Y434273D01*
Y435973D01*
X542989Y436997D01*
X544689D01*
X545713Y438021D01*
Y439721D01*
X546737Y440745D01*
X548437D01*
X550696Y443004D01*
Y471904D01*
X551520Y472728D01*
X554120D01*
X555651Y474259D01*
Y475834D01*
X554873Y476612D01*
X554108D01*
X553458Y477262D01*
Y479202D01*
X554108Y479852D01*
X554873D01*
X555523Y480502D01*
Y488019D01*
X555022Y488520D01*
X554892D01*
X554392Y489020D01*
Y492844D01*
X553892Y493344D01*
X551366D01*
G01X481691Y523900D02*
Y528899D01*
G01X495077Y523900D02*
Y528899D01*
G01X518502Y523900D02*
Y528899D01*
G01X488384Y523900D02*
Y528899D01*
G01X511809Y523900D02*
Y528899D01*
G01X531888Y523900D02*
Y528899D01*
G01X525195Y523900D02*
Y528899D01*
G01X505116Y523900D02*
Y526496D01*
X503470Y528142D01*
Y529800D01*
X504202Y530532D01*
Y531503D01*
X503210Y532495D01*
X502390D01*
X501645Y531750D01*
X501570D01*
G01X501770Y523900D02*
Y526351D01*
X500053Y528068D01*
X499804Y528610D01*
X499720Y528792D01*
Y532013D01*
X500041Y532896D01*
X501544Y534399D01*
G01X538581Y523900D02*
Y526351D01*
X536864Y528068D01*
X536615Y528610D01*
X536531Y528792D01*
Y532013D01*
X536852Y532896D01*
X538355Y534399D01*
G01X485037Y542010D02*
Y538108D01*
X485555Y537590D01*
Y536710D01*
X485037Y536192D01*
Y535100D01*
G01X478344Y542010D02*
X478345D01*
Y538200D01*
X478865Y537680D01*
Y536820D01*
X478345Y536300D01*
Y535101D01*
X478344Y535100D01*
G01X498423Y542010D02*
Y542033D01*
X497723Y534700D01*
G01X521848Y542010D02*
Y538108D01*
X522366Y537590D01*
Y536710D01*
X521848Y536192D01*
Y535100D01*
G01X491730Y542010D02*
Y536792D01*
X491344Y534700D01*
G01X515155Y542010D02*
X515156D01*
Y538200D01*
X515676Y537680D01*
Y536820D01*
X515156Y536300D01*
Y535101D01*
X515155Y535100D01*
G01X535234Y542010D02*
Y542033D01*
X534534Y534700D01*
G01X528541Y542010D02*
Y536792D01*
X528155Y534700D01*
G01X541927Y523900D02*
Y526496D01*
X540281Y528142D01*
Y529800D01*
X541013Y530532D01*
Y531503D01*
X540021Y532495D01*
X539201D01*
X538456Y531750D01*
X538381D01*
G01X505116Y542010D02*
Y537805D01*
X503612Y536301D01*
Y534601D01*
X504913Y533300D01*
X505795D01*
X506644Y534149D01*
G01X508462Y542010D02*
X508463D01*
Y538049D01*
X508612Y537900D01*
Y532500D01*
X507652Y531540D01*
X506644D01*
G01X485037Y579810D02*
Y575908D01*
X485555Y575390D01*
Y574510D01*
X485037Y573992D01*
Y572900D01*
G01X481691Y561700D02*
Y566699D01*
G01X478344Y579810D02*
X478345D01*
Y576000D01*
X478865Y575480D01*
Y574620D01*
X478345Y574100D01*
Y572901D01*
X478344Y572900D01*
G01X498423Y579810D02*
Y579833D01*
X497723Y572500D01*
G01X495077Y561700D02*
Y566699D01*
G01X521848Y579810D02*
Y575908D01*
X522366Y575390D01*
Y574510D01*
X521848Y573992D01*
Y572900D01*
G01X518502Y561700D02*
Y566699D01*
G01X491730Y579810D02*
Y574592D01*
X491344Y572500D01*
G01X488384Y561700D02*
Y566699D01*
G01X515155Y579810D02*
X515156D01*
Y576000D01*
X515676Y575480D01*
Y574620D01*
X515156Y574100D01*
Y572901D01*
X515155Y572900D01*
G01X511809Y561700D02*
Y566699D01*
G01X535234Y579810D02*
Y579833D01*
X534534Y572500D01*
G01X531888Y561700D02*
Y566699D01*
G01X528541Y579810D02*
Y574592D01*
X528155Y572500D01*
G01X525195Y561700D02*
Y566699D01*
G01X505116Y561700D02*
Y564296D01*
X503470Y565942D01*
Y567600D01*
X504202Y568332D01*
Y569303D01*
X503210Y570295D01*
X502390D01*
X501645Y569550D01*
X501570D01*
G01X541927Y561700D02*
Y564296D01*
X540281Y565942D01*
Y567600D01*
X541013Y568332D01*
Y569303D01*
X540021Y570295D01*
X539201D01*
X538456Y569550D01*
X538381D01*
G01X505116Y579810D02*
Y575605D01*
X503612Y574101D01*
Y572401D01*
X504913Y571100D01*
X505795D01*
X506644Y571949D01*
G01X501770Y561700D02*
Y564151D01*
X500053Y565868D01*
X499720Y566592D01*
Y569813D01*
X500041Y570696D01*
X501544Y572199D01*
G01X538581Y561700D02*
Y564151D01*
X536864Y565868D01*
X536531Y566592D01*
Y569813D01*
X536852Y570696D01*
X538355Y572199D01*
G01X508462Y579810D02*
X508463D01*
Y575849D01*
X508612Y575700D01*
Y570300D01*
X507652Y569340D01*
X506644D01*
G01X485037Y617610D02*
Y613708D01*
X485555Y613190D01*
Y612310D01*
X485037Y611792D01*
Y610700D01*
G01X481691Y599500D02*
Y604499D01*
G01X478344Y617610D02*
X478345D01*
Y613800D01*
X478865Y613280D01*
Y612420D01*
X478345Y611900D01*
Y610701D01*
X478344Y610700D01*
G01X498423Y617610D02*
Y617633D01*
X497838Y611507D01*
X498092Y611200D01*
G01X495077Y599500D02*
Y604499D01*
G01X521848Y617610D02*
Y613708D01*
X522366Y613190D01*
Y612310D01*
X521848Y611792D01*
Y610700D01*
G01X518502Y599500D02*
Y604499D01*
G01X491730Y617610D02*
Y611674D01*
X491724Y611668D01*
G01X488384Y599500D02*
Y604499D01*
G01X515155Y617610D02*
X515156D01*
Y613800D01*
X515676Y613280D01*
Y612420D01*
X515156Y611900D01*
Y610701D01*
X515155Y610700D01*
G01X511809Y599500D02*
Y604499D01*
G01X535234Y617610D02*
Y617633D01*
X534534Y610300D01*
G01X531888Y599500D02*
Y604499D01*
G01X528541Y617610D02*
Y612392D01*
X528155Y610300D01*
G01X525195Y599500D02*
Y604499D01*
G01X505116Y599500D02*
Y602096D01*
X503470Y603742D01*
Y605400D01*
X504202Y606132D01*
Y607103D01*
X503210Y608095D01*
X502390D01*
X501645Y607350D01*
X501570D01*
G01X541927Y599500D02*
Y602096D01*
X540281Y603742D01*
Y605400D01*
X541013Y606132D01*
Y607103D01*
X540021Y608095D01*
X539201D01*
X538456Y607350D01*
X538381D01*
G01X505116Y617610D02*
Y613405D01*
X503612Y611901D01*
Y610201D01*
X504913Y608900D01*
X505795D01*
X506644Y609749D01*
G01X501770Y599500D02*
Y601951D01*
X500053Y603668D01*
X499720Y604392D01*
Y607613D01*
X500041Y608496D01*
X501544Y609999D01*
G01X538581Y599500D02*
Y601951D01*
X536864Y603668D01*
X536531Y604392D01*
Y607613D01*
X536852Y608496D01*
X538355Y609999D01*
G01X508462Y617610D02*
X508463D01*
Y613649D01*
X508612Y613500D01*
Y608100D01*
X507652Y607140D01*
X506644D01*
G01X555313Y22923D02*
Y27899D01*
G01X548620Y22923D02*
Y27899D01*
G01X568699Y22923D02*
Y27899D01*
G01X592124Y22923D02*
Y27899D01*
G01X562006Y22923D02*
Y27899D01*
G01X585431Y22923D02*
Y27899D01*
G01X578738Y22923D02*
Y26240D01*
X577092Y27886D01*
Y28800D01*
X577824Y29532D01*
Y30503D01*
X576832Y31495D01*
X576012D01*
X575267Y30750D01*
X575192D01*
G01X541927Y41033D02*
Y36805D01*
X540423Y35301D01*
Y33601D01*
X541724Y32300D01*
X542606D01*
X543455Y33149D01*
G01X578738Y41033D02*
Y37045D01*
X577692Y35999D01*
Y33114D01*
X580266Y30540D01*
G01X575392Y22923D02*
Y25351D01*
X573675Y27068D01*
X573342Y27792D01*
Y31013D01*
X573663Y31896D01*
X575166Y33399D01*
G01X545273Y41033D02*
X545274Y41032D01*
Y37049D01*
X545423Y36900D01*
Y31500D01*
X544463Y30540D01*
X543455D01*
G01X582084Y41033D02*
Y36708D01*
X582957Y35835D01*
Y32913D01*
X582115Y32071D01*
X581344D01*
X580266Y33149D01*
G01X558659Y3233D02*
Y-692D01*
X559177Y-1210D01*
Y-2090D01*
X558659Y-2608D01*
Y-3700D01*
G01X555313Y-14877D02*
Y-9901D01*
G01X551966Y3233D02*
X551967Y3232D01*
Y-600D01*
X552487Y-1120D01*
Y-1980D01*
X551967Y-2500D01*
Y-3699D01*
X551966Y-3700D01*
G01X548620Y-14877D02*
Y-9901D01*
G01X572045Y3233D02*
X571345Y-4100D01*
G01X568699Y-14877D02*
Y-9901D01*
G01X595470Y3233D02*
Y-692D01*
X595988Y-1210D01*
Y-2090D01*
X595470Y-2608D01*
Y-3700D01*
G01X592124Y-14877D02*
Y-9901D01*
G01X565352Y3233D02*
Y-2008D01*
X564966Y-4100D01*
G01X562006Y-14877D02*
Y-9901D01*
G01X588777Y3233D02*
X588778Y3232D01*
Y-600D01*
X589298Y-1120D01*
Y-1980D01*
X588778Y-2500D01*
Y-3699D01*
X588777Y-3700D01*
G01X585431Y-14877D02*
Y-9901D01*
G01X578738Y-14877D02*
Y-11560D01*
X577092Y-9914D01*
Y-9000D01*
X577824Y-8268D01*
Y-7297D01*
X576832Y-6305D01*
X576012D01*
X575267Y-7050D01*
X575192D01*
G01X541927Y3233D02*
Y-755D01*
X540881Y-1801D01*
Y-4686D01*
X543455Y-7260D01*
G01X578738Y3233D02*
Y-755D01*
X577692Y-1801D01*
Y-4686D01*
X580266Y-7260D01*
G01X575392Y-14877D02*
Y-12449D01*
X573675Y-10732D01*
X573342Y-10008D01*
Y-6787D01*
X573663Y-5904D01*
X575166Y-4401D01*
G01X545273Y3233D02*
Y-1092D01*
X546146Y-1965D01*
Y-4887D01*
X545304Y-5729D01*
X544533D01*
X543455Y-4651D01*
G01X582084Y3233D02*
Y-1092D01*
X582957Y-1965D01*
Y-4887D01*
X582115Y-5729D01*
X581344D01*
X580266Y-4651D01*
G01X558659Y78833D02*
Y74908D01*
X559177Y74390D01*
Y73510D01*
X558659Y72992D01*
Y71900D01*
G01X555313Y60723D02*
Y65699D01*
G01X551966Y78833D02*
X551967Y78832D01*
Y75000D01*
X552487Y74480D01*
Y73620D01*
X551967Y73100D01*
Y71901D01*
X551966Y71900D01*
G01X548620Y60723D02*
Y65699D01*
G01X572045Y78833D02*
X571727Y75500D01*
X571345Y71500D01*
G01X568699Y60723D02*
Y65699D01*
G01X595470Y78833D02*
Y74908D01*
X595988Y74390D01*
Y73510D01*
X595470Y72992D01*
Y71900D01*
G01X592124Y60723D02*
Y65699D01*
G01X565352Y78833D02*
Y73592D01*
X564966Y71500D01*
G01X562006Y60723D02*
Y65699D01*
G01X588777Y78833D02*
X588778Y78832D01*
Y75000D01*
X589298Y74480D01*
Y73620D01*
X588778Y73100D01*
Y71901D01*
X588777Y71900D01*
G01X585431Y60723D02*
Y65699D01*
G01X578738Y60723D02*
Y63296D01*
X577092Y64942D01*
Y66600D01*
X577824Y67332D01*
Y68303D01*
X576832Y69295D01*
X576012D01*
X575267Y68550D01*
X575192D01*
G01X541927Y78833D02*
Y74605D01*
X540423Y73101D01*
Y71401D01*
X541724Y70100D01*
X542606D01*
X543455Y70949D01*
G01X578738Y78833D02*
Y74605D01*
X577234Y73101D01*
Y71401D01*
X578535Y70100D01*
X579417D01*
X580266Y70949D01*
G01X575392Y60723D02*
Y63151D01*
X573675Y64868D01*
X573342Y65592D01*
Y68813D01*
X573663Y69696D01*
X575166Y71199D01*
G01X545273Y78833D02*
X545274Y78832D01*
Y74849D01*
X545423Y74700D01*
Y69300D01*
X544463Y68340D01*
X543455D01*
G01X582084Y78833D02*
X582085Y78832D01*
Y74849D01*
X582234Y74700D01*
Y69300D01*
X581274Y68340D01*
X580266D01*
G01X558659Y41033D02*
Y37108D01*
X559177Y36590D01*
Y35710D01*
X558659Y35192D01*
Y34100D01*
G01X551966Y41033D02*
X551967Y41032D01*
Y37200D01*
X552487Y36680D01*
Y35820D01*
X551967Y35300D01*
Y34101D01*
X551966Y34100D01*
G01X572045Y41033D02*
X571469Y35000D01*
X571421Y34500D01*
X571345Y33700D01*
G01X595470Y41033D02*
Y37108D01*
X595988Y36590D01*
Y35710D01*
X595470Y35192D01*
Y34100D01*
G01X565352Y41033D02*
Y35792D01*
X565206Y35000D01*
X565114Y34500D01*
X564966Y33700D01*
G01X588777Y41033D02*
X588778Y41032D01*
Y37200D01*
X589298Y36680D01*
Y35820D01*
X588778Y35300D01*
Y34101D01*
X588777Y34100D01*
G01X557692Y133500D02*
Y130399D01*
X558691Y129400D01*
Y122900D01*
X558191Y122400D01*
X556651D01*
X556151Y122900D01*
Y126200D01*
X555651Y126700D01*
X554249D01*
X553611Y126062D01*
Y114059D01*
X555313Y112357D01*
G01X560211Y140500D02*
Y131443D01*
X561210Y130444D01*
Y120201D01*
X557392Y116383D01*
Y111701D01*
X555892Y110201D01*
Y108442D01*
X557020Y107314D01*
X558659D01*
G01X547328Y120500D02*
Y115265D01*
X548620Y113973D01*
Y112357D01*
G01X555147Y139000D02*
Y131355D01*
X551092Y127300D01*
Y111800D01*
X550171Y110879D01*
Y109109D01*
X551966Y107314D01*
G01X543659Y126500D02*
Y119922D01*
X541706Y117969D01*
Y109404D01*
X543455Y107655D01*
G01X544809Y135000D02*
Y119445D01*
X542856Y117492D01*
Y116036D01*
X545292Y113600D01*
Y111061D01*
X544495Y110264D01*
X543481D01*
G01X555313Y523900D02*
Y528899D01*
G01X548620Y523900D02*
Y528899D01*
G01X568699Y523900D02*
Y528899D01*
G01X592124Y523900D02*
Y528899D01*
G01X562006Y523900D02*
Y528899D01*
G01X585431Y523900D02*
Y528899D01*
G01X578738Y523900D02*
Y526496D01*
X577092Y528142D01*
Y529800D01*
X577824Y530532D01*
Y531503D01*
X576832Y532495D01*
X576012D01*
X575267Y531750D01*
X575192D01*
G01X575392Y523900D02*
Y526351D01*
X573675Y528068D01*
X573426Y528610D01*
X573342Y528792D01*
Y532013D01*
X573663Y532896D01*
X575166Y534399D01*
G01X558659Y542010D02*
Y538108D01*
X559177Y537590D01*
Y536710D01*
X558659Y536192D01*
Y535100D01*
G01X551966D02*
X551967Y535101D01*
Y536300D01*
X552487Y536820D01*
Y537680D01*
X551967Y538200D01*
Y542010D01*
X551966D01*
G01X572045D02*
Y542033D01*
X571345Y534700D01*
G01X595470Y542010D02*
Y538108D01*
X595988Y537590D01*
Y536710D01*
X595470Y536192D01*
Y535100D01*
G01X565352Y542010D02*
Y536792D01*
X564966Y534700D01*
G01X588777Y542010D02*
X588778D01*
Y538200D01*
X589298Y537680D01*
Y536820D01*
X588778Y536300D01*
Y535101D01*
X588777Y535100D01*
G01X541927Y542010D02*
Y537805D01*
X540423Y536301D01*
Y534601D01*
X541724Y533300D01*
X542606D01*
X543455Y534149D01*
G01X578738Y542010D02*
Y537805D01*
X577234Y536301D01*
Y534601D01*
X578535Y533300D01*
X579417D01*
X580266Y534149D01*
G01X545273Y542010D02*
X545274D01*
Y538049D01*
X545423Y537900D01*
Y532500D01*
X544463Y531540D01*
X543455D01*
G01X582084Y542010D02*
X582085D01*
Y538049D01*
X582234Y537900D01*
Y532500D01*
X581274Y531540D01*
X580266D01*
G01X558659Y579810D02*
Y575908D01*
X559177Y575390D01*
Y574510D01*
X558659Y573992D01*
Y572900D01*
G01X555313Y561700D02*
Y566699D01*
G01X551966Y579810D02*
X551967D01*
Y576000D01*
X552487Y575480D01*
Y574620D01*
X551967Y574100D01*
Y572901D01*
X551966Y572900D01*
G01X548620Y561700D02*
Y566699D01*
G01X572045Y579810D02*
Y579833D01*
X571345Y572500D01*
G01X568699Y561700D02*
Y566699D01*
G01X595470Y579810D02*
Y575908D01*
X595988Y575390D01*
Y574510D01*
X595470Y573992D01*
Y572900D01*
G01X592124Y561700D02*
Y566699D01*
G01X565352Y579810D02*
Y574592D01*
X564966Y572500D01*
G01X562006Y561700D02*
Y566699D01*
G01X588777Y579810D02*
X588778D01*
Y576000D01*
X589298Y575480D01*
Y574620D01*
X588778Y574100D01*
Y572901D01*
X588777Y572900D01*
G01X585431Y561700D02*
Y566699D01*
G01X578738Y561700D02*
Y564296D01*
X577092Y565942D01*
Y567600D01*
X577824Y568332D01*
Y569303D01*
X576832Y570295D01*
X576012D01*
X575267Y569550D01*
X575192D01*
G01X541927Y579810D02*
Y575605D01*
X540423Y574101D01*
Y572401D01*
X541724Y571100D01*
X542606D01*
X543455Y571949D01*
G01X578738Y579810D02*
Y575605D01*
X577234Y574101D01*
Y572401D01*
X578535Y571100D01*
X579417D01*
X580266Y571949D01*
G01X575392Y561700D02*
Y564151D01*
X573675Y565868D01*
X573342Y566592D01*
Y569813D01*
X573663Y570696D01*
X575166Y572199D01*
G01X545273Y579810D02*
X545274D01*
Y575849D01*
X545423Y575700D01*
Y570300D01*
X544463Y569340D01*
X543455D01*
G01X582084Y579810D02*
X582085D01*
Y575849D01*
X582234Y575700D01*
Y570300D01*
X581274Y569340D01*
X580266D01*
G01X558659Y617610D02*
Y613708D01*
X559177Y613190D01*
Y612310D01*
X558659Y611792D01*
Y610700D01*
G01X555313Y599500D02*
Y604499D01*
G01X551966Y610700D02*
X551967Y610701D01*
Y611900D01*
X552487Y612420D01*
Y613280D01*
X551967Y613800D01*
Y617610D01*
X551966D01*
G01X548620Y599500D02*
Y604499D01*
G01X572045Y617610D02*
Y617633D01*
X571345Y610300D01*
G01X568699Y599500D02*
Y604499D01*
G01X595470Y617610D02*
Y613708D01*
X595988Y613190D01*
Y612310D01*
X595470Y611792D01*
Y610700D01*
G01X592124Y599500D02*
Y604499D01*
G01X565352Y617610D02*
Y612392D01*
X564966Y610300D01*
G01X562006Y599500D02*
Y604499D01*
G01X588777Y617610D02*
X588778D01*
Y613800D01*
X589298Y613280D01*
Y612420D01*
X588778Y611900D01*
Y610701D01*
X588777Y610700D01*
G01X585431Y599500D02*
Y604499D01*
G01X578738Y599500D02*
Y602096D01*
X577092Y603742D01*
Y605400D01*
X577824Y606132D01*
Y607103D01*
X576832Y608095D01*
X576012D01*
X575267Y607350D01*
X575192D01*
G01X541927Y617610D02*
Y613405D01*
X540423Y611901D01*
Y610201D01*
X541724Y608900D01*
X542606D01*
X543455Y609749D01*
G01X578738Y617610D02*
Y613405D01*
X577234Y611901D01*
Y610201D01*
X578535Y608900D01*
X579417D01*
X580266Y609749D01*
G01X575392Y599500D02*
Y601951D01*
X573675Y603668D01*
X573342Y604392D01*
Y607613D01*
X573663Y608496D01*
X575166Y609999D01*
G01X545273Y617610D02*
X545274D01*
Y613649D01*
X545423Y613500D01*
Y608100D01*
X544463Y607140D01*
X543455D01*
G01X582084Y617610D02*
X582085D01*
Y613649D01*
X582234Y613500D01*
Y608100D01*
X581274Y607140D01*
X580266D01*
G01X608856Y528899D02*
Y523923D01*
G01X612203Y523900D02*
Y528899D01*
G01X608856Y579833D02*
Y579810D01*
G01D02*
Y574857D01*
G01X602163Y579833D02*
Y579810D01*
G01D02*
Y574857D01*
G01X612203Y579833D02*
Y579810D01*
G01D02*
Y574857D01*
G01X615549Y579833D02*
Y579810D01*
G01D02*
Y574857D01*
G01X608856Y542033D02*
Y542010D01*
G01X612203Y542033D02*
Y542010D01*
G01X615549Y542033D02*
Y542010D01*
G01X612203D02*
Y537057D01*
G01X608856Y542010D02*
Y537057D01*
G01X615549Y542010D02*
Y537057D01*
G01X602163Y617633D02*
Y617610D01*
G01X608856Y617633D02*
Y617610D01*
G01X612203Y617633D02*
Y617610D01*
G01X615549D02*
Y617633D01*
G01X612203Y617610D02*
Y612657D01*
G01X608856Y617610D02*
Y612657D01*
G01X602163Y617610D02*
Y612657D01*
G01X615549D02*
Y617610D01*
G01X779923Y22923D02*
X779921D01*
Y27899D01*
G01X773230Y22923D02*
X773228D01*
Y27899D01*
G01X789962Y22923D02*
X789960D01*
Y26240D01*
X788314Y27886D01*
Y28800D01*
X789046Y29532D01*
Y30503D01*
X788054Y31495D01*
X787159D01*
X786414Y30750D01*
G01X786616Y22923D02*
X786614D01*
Y25351D01*
X784897Y27068D01*
X784564Y27792D01*
Y31013D01*
X784885Y31896D01*
X786388Y33399D01*
G01X783269Y3233D02*
X783267D01*
X782567Y-4100D01*
G01X779923Y-14877D02*
X779921D01*
Y-9901D01*
G01X776576Y3233D02*
X776574D01*
Y-2008D01*
X776188Y-4100D01*
G01X773230Y-14877D02*
X773228D01*
Y-9901D01*
G01X789962Y-14877D02*
X789960D01*
Y-11560D01*
X788314Y-9914D01*
Y-9000D01*
X789046Y-8268D01*
Y-7297D01*
X788054Y-6305D01*
X787234D01*
X786489Y-7050D01*
X786414D01*
G01X786616Y-14877D02*
X786614D01*
Y-12449D01*
X784897Y-10732D01*
X784564Y-10008D01*
Y-6787D01*
X784885Y-5904D01*
X786388Y-4401D01*
G01X783269Y78833D02*
X783267D01*
X782949Y75500D01*
X782567Y71500D01*
G01X779923Y60723D02*
X779921D01*
Y65699D01*
G01X776576Y78833D02*
X776574D01*
Y73592D01*
X776188Y71500D01*
G01X773230Y60723D02*
X773228D01*
Y65699D01*
G01X789962Y60723D02*
X789960D01*
Y63296D01*
X788314Y64942D01*
Y66600D01*
X789046Y67332D01*
Y68303D01*
X788054Y69295D01*
X787234D01*
X786489Y68550D01*
X786414D01*
G01X786616Y60723D02*
X786614D01*
Y63151D01*
X784897Y64868D01*
X784564Y65592D01*
Y68813D01*
X784885Y69696D01*
X786388Y71199D01*
G01X783269Y41033D02*
X783267D01*
X782643Y34500D01*
X782567Y33700D01*
G01X776576Y41033D02*
X776574D01*
Y35792D01*
X776336Y34500D01*
X776188Y33700D01*
G01X779923Y523900D02*
X779921Y523923D01*
Y528899D01*
G01X773230Y523900D02*
X773228Y523923D01*
Y528899D01*
G01X786616Y523900D02*
X786614Y523923D01*
Y526351D01*
X784897Y528068D01*
X784648Y528610D01*
X784564Y528792D01*
Y532013D01*
X784885Y532896D01*
X786388Y534399D01*
G01X783269Y542010D02*
X783267Y542033D01*
X782567Y534700D01*
G01X776576Y542010D02*
X776574D01*
Y536792D01*
X776188Y534700D01*
G01X789962Y523900D02*
X789960Y523923D01*
Y526496D01*
X788314Y528142D01*
Y529800D01*
X789046Y530532D01*
Y531503D01*
X788054Y532495D01*
X787234D01*
X786489Y531750D01*
X786414D01*
G01X783269Y579810D02*
X783267Y579833D01*
X782567Y572500D01*
G01X779923Y561700D02*
X779921Y561723D01*
Y566699D01*
G01X776576Y579810D02*
X776574D01*
Y574592D01*
X776188Y572500D01*
G01X773230Y561700D02*
X773228Y561723D01*
Y566699D01*
G01X789962Y561700D02*
X789960Y561723D01*
Y564296D01*
X788314Y565942D01*
Y567600D01*
X789046Y568332D01*
Y569303D01*
X788054Y570295D01*
X787234D01*
X786489Y569550D01*
X786414D01*
G01X786616Y561700D02*
X786614Y561723D01*
Y564151D01*
X784897Y565868D01*
X784564Y566592D01*
Y569813D01*
X784885Y570696D01*
X786388Y572199D01*
G01X783269Y617610D02*
X783267Y617633D01*
X782567Y610300D01*
G01X779923Y599500D02*
X779921Y599523D01*
Y604499D01*
G01X776576Y617610D02*
X776574D01*
Y612392D01*
X776188Y610300D01*
G01X773230Y599500D02*
X773228Y599523D01*
Y604499D01*
G01X789962Y599500D02*
X789960Y599523D01*
Y602096D01*
X788314Y603742D01*
Y605400D01*
X789046Y606132D01*
Y607103D01*
X788054Y608095D01*
X787234D01*
X786489Y607350D01*
X786414D01*
G01X786616Y599500D02*
X786614Y599523D01*
Y601951D01*
X784897Y603668D01*
X784564Y604392D01*
Y607613D01*
X784885Y608496D01*
X786388Y609999D01*
G01X840159Y22923D02*
X840157D01*
Y27899D01*
G01X810041Y22923D02*
X810039D01*
Y27899D01*
G01X833466Y22923D02*
X833464D01*
Y27899D01*
G01X846852Y22923D02*
X846850D01*
Y27899D01*
G01X803348Y22923D02*
X803346D01*
Y27899D01*
G01X796655Y22923D02*
X796653D01*
Y27899D01*
G01X816734Y22923D02*
X816732D01*
Y27899D01*
G01X789962Y41033D02*
X789960D01*
Y37045D01*
X788914Y35999D01*
Y33114D01*
X791488Y30540D01*
G01X826773Y22923D02*
X826771D01*
Y26240D01*
X825125Y27886D01*
Y28800D01*
X825857Y29532D01*
Y30503D01*
X824865Y31495D01*
X823970D01*
X823225Y30750D01*
G01X826773Y41033D02*
X826771D01*
Y37045D01*
X825725Y35999D01*
Y33114D01*
X828299Y30540D01*
G01X791488Y33149D02*
X792566Y32071D01*
X793337D01*
X794179Y32913D01*
Y35835D01*
X793309Y36705D01*
Y41033D01*
G01X823427Y22923D02*
X823425D01*
Y25351D01*
X821708Y27068D01*
X821375Y27792D01*
Y31013D01*
X821696Y31896D01*
X823199Y33399D01*
G01X830120Y41033D02*
Y36705D01*
X830990Y35835D01*
Y32913D01*
X830148Y32071D01*
X829377D01*
X828299Y33149D01*
G01X843506Y3233D02*
Y-695D01*
X844021Y-1210D01*
Y-2090D01*
X843503Y-2608D01*
Y-3700D01*
G01X840159Y-14877D02*
X840157D01*
Y-9901D01*
G01X813387Y3233D02*
X813385D01*
Y-2008D01*
X812999Y-4100D01*
G01X810041Y-14877D02*
X810039D01*
Y-9901D01*
G01X836813Y3233D02*
X836811D01*
Y-600D01*
X837331Y-1120D01*
Y-1980D01*
X836811Y-2500D01*
Y-3699D01*
X836810Y-3700D01*
G01X833466Y-14877D02*
X833464D01*
Y-9901D01*
G01X846852Y-14877D02*
X846850D01*
Y-9901D01*
G01X806694Y3233D02*
X806692D01*
Y-692D01*
X807210Y-1210D01*
Y-2090D01*
X806692Y-2608D01*
Y-3700D01*
G01X803348Y-14877D02*
X803346D01*
Y-9901D01*
G01X800002Y3233D02*
X800000D01*
Y-600D01*
X800520Y-1120D01*
Y-1980D01*
X800000Y-2500D01*
Y-3699D01*
X799999Y-3700D01*
G01X796655Y-14877D02*
X796653D01*
Y-9901D01*
G01X820080Y3233D02*
X820078D01*
X819378Y-4100D01*
G01X816734Y-14877D02*
X816732D01*
Y-9901D01*
G01X789962Y3233D02*
X789960D01*
Y-755D01*
X788914Y-1801D01*
Y-4686D01*
X791488Y-7260D01*
G01X826773Y-14877D02*
X826771D01*
Y-11560D01*
X825125Y-9914D01*
Y-9000D01*
X825857Y-8268D01*
Y-7297D01*
X824865Y-6305D01*
X824045D01*
X823300Y-7050D01*
X823225D01*
G01X826773Y3233D02*
X826771D01*
Y-755D01*
X825725Y-1801D01*
Y-4686D01*
X828299Y-7260D01*
G01X793309Y3233D02*
X793307D01*
Y-1093D01*
X794179Y-1965D01*
Y-4887D01*
X793337Y-5729D01*
X792566D01*
X791488Y-4651D01*
G01X823427Y-14877D02*
X823425D01*
Y-12449D01*
X821708Y-10732D01*
X821375Y-10008D01*
Y-6787D01*
X821696Y-5904D01*
X823199Y-4401D01*
G01X830120Y3233D02*
X830118D01*
Y-1093D01*
X830990Y-1965D01*
Y-4887D01*
X830148Y-5729D01*
X829377D01*
X828299Y-4651D01*
G01X843506Y78833D02*
Y74905D01*
X844021Y74390D01*
Y73510D01*
X843503Y72992D01*
Y71900D01*
G01X840157Y92757D02*
X845020Y97620D01*
X845940D01*
X848768Y94792D01*
X849688D01*
X864338Y109442D01*
Y110362D01*
X863384Y111316D01*
X862464D01*
X849688Y98540D01*
X848768D01*
X847814Y99494D01*
Y100414D01*
X861026Y113626D01*
Y141000D01*
G01X858337Y125500D02*
Y118315D01*
X857788Y117766D01*
X856053D01*
X855553Y118266D01*
Y131633D01*
X854903Y132283D01*
X853513D01*
X852863Y131633D01*
Y111063D01*
X838292Y96492D01*
Y91956D01*
X840042Y90206D01*
X841011D01*
X843503Y87714D01*
G01X840159Y60723D02*
X840157D01*
Y65699D01*
G01X813387Y78833D02*
X813385D01*
Y73592D01*
X812999Y71500D01*
G01X913700Y235706D02*
X900431D01*
X818763Y154038D01*
Y123763D01*
X809800Y114800D01*
Y101125D01*
X809150Y100475D01*
X807350D01*
X806700Y99825D01*
Y98475D01*
X807350Y97825D01*
X809150D01*
X809800Y97175D01*
Y92996D01*
X810039Y92757D01*
G01X810041Y60723D02*
X810039D01*
Y65699D01*
G01X813085Y87714D02*
X811240Y89559D01*
Y90720D01*
X812500Y93800D01*
Y112954D01*
X821400Y121854D01*
Y152917D01*
X841741Y173258D01*
G01X847304Y138000D02*
Y131685D01*
X846654Y131035D01*
X845450D01*
X844800Y130385D01*
Y129035D01*
X845450Y128385D01*
X846654D01*
X847304Y127735D01*
Y126385D01*
X846654Y125735D01*
X844046D01*
X843396Y125085D01*
Y123735D01*
X844046Y123085D01*
X846654D01*
X847304Y122435D01*
Y114054D01*
X844729Y111479D01*
X843809D01*
X841056Y114232D01*
X840136D01*
X839182Y113278D01*
Y112358D01*
X841935Y109605D01*
Y108685D01*
X840981Y107731D01*
X840061D01*
X837308Y110484D01*
X836388D01*
X835434Y109530D01*
Y108610D01*
X838187Y105857D01*
Y104937D01*
X837233Y103983D01*
X836313D01*
X833560Y106736D01*
X832640D01*
X831686Y105782D01*
Y104862D01*
X834439Y102109D01*
Y101189D01*
X832500Y99250D01*
Y93721D01*
X833464Y92757D01*
G01X836813Y78833D02*
X836811D01*
Y75000D01*
X837331Y74480D01*
Y73620D01*
X836811Y73100D01*
Y71901D01*
X836810Y71900D01*
G01Y87714D02*
X834774Y89750D01*
Y91174D01*
X835500Y91900D01*
Y98200D01*
X850036Y112736D01*
Y128500D01*
G01X833466Y60723D02*
X833464D01*
Y65699D01*
G01X846852Y60723D02*
X846850D01*
Y65699D01*
G01X806694Y78833D02*
X806692D01*
Y74908D01*
X807210Y74390D01*
Y73510D01*
X806692Y72992D01*
Y71900D01*
G01X803348Y60723D02*
X803346D01*
Y65699D01*
G01X800002Y78833D02*
X800000D01*
Y75000D01*
X800520Y74480D01*
Y73620D01*
X800000Y73100D01*
Y71901D01*
X799999Y71900D01*
G01X796655Y60723D02*
X796653D01*
Y65699D01*
G01X820080Y78833D02*
X820078D01*
X819760Y75500D01*
X819378Y71500D01*
G01X816732Y92757D02*
X815192Y94297D01*
Y111688D01*
X824320Y120816D01*
Y133724D01*
X829219Y138623D01*
Y140976D01*
X828569Y141626D01*
X824924D01*
X824274Y142276D01*
Y143626D01*
X824924Y144276D01*
X828569D01*
X829219Y144926D01*
Y146276D01*
X828569Y146926D01*
X826650D01*
X826000Y147576D01*
Y148926D01*
X826650Y149576D01*
X828569D01*
X829219Y150226D01*
Y156978D01*
X832370Y160129D01*
G01X912391Y227856D02*
X903855D01*
X831951Y155952D01*
Y137491D01*
X827147Y132687D01*
Y126505D01*
X828200Y125452D01*
Y123608D01*
X827147Y122555D01*
Y119876D01*
X817915Y110644D01*
Y94233D01*
X818574Y93574D01*
Y92074D01*
X817374Y90874D01*
Y89718D01*
X819378Y87714D01*
G01X816734Y60723D02*
X816732D01*
Y65699D01*
G01X789962Y78833D02*
X789960D01*
Y74605D01*
X788456Y73101D01*
Y71401D01*
X789757Y70100D01*
X790639D01*
X791488Y70949D01*
G01X912120Y224141D02*
X905553D01*
X835624Y154212D01*
Y132748D01*
X834301Y131425D01*
X831977D01*
X831327Y130775D01*
Y129425D01*
X831977Y128775D01*
X834301D01*
X835624Y127452D01*
Y122324D01*
X824204Y110904D01*
Y110196D01*
X823496Y109489D01*
X822789D01*
X821742Y108442D01*
Y107158D01*
X822275Y106625D01*
Y105691D01*
X821742Y105158D01*
Y104158D01*
X822275Y103625D01*
Y102691D01*
X821742Y102158D01*
Y101158D01*
X822275Y100625D01*
Y99691D01*
X821742Y99158D01*
Y98158D01*
X822275Y97625D01*
Y96691D01*
X821742Y96158D01*
Y95158D01*
X822500Y94400D01*
X824000D01*
X824970Y93430D01*
Y90969D01*
X823901Y89900D01*
X823199D01*
G01X826773Y60723D02*
X826771D01*
Y63296D01*
X825125Y64942D01*
Y66600D01*
X825857Y67332D01*
Y68303D01*
X824865Y69295D01*
X824045D01*
X823300Y68550D01*
X823225D01*
G01X826773Y78833D02*
X826771D01*
Y74605D01*
X825200Y73034D01*
Y71468D01*
X826568Y70100D01*
X827450D01*
X828299Y70949D01*
G01X912752Y221066D02*
X906386D01*
X838750Y153430D01*
Y149552D01*
X840073Y148229D01*
X842972D01*
X843472Y147729D01*
Y146079D01*
X842972Y145579D01*
X840073D01*
X838750Y144256D01*
Y139567D01*
X840073Y138244D01*
X842124D01*
X842624Y137744D01*
Y136094D01*
X842124Y135594D01*
X840073D01*
X838750Y134271D01*
Y119937D01*
X825174Y106361D01*
Y96799D01*
X826504Y95469D01*
Y89309D01*
X828299Y87514D01*
G01X793309Y78833D02*
X793307D01*
Y74849D01*
X793456Y74700D01*
Y69300D01*
X792496Y68340D01*
X791488D01*
G01X823199Y87300D02*
X821350Y89149D01*
Y93923D01*
X820592Y94681D01*
Y108919D01*
X831125Y119452D01*
G01X823427Y60723D02*
X823425D01*
Y63151D01*
X821708Y64868D01*
X821375Y65592D01*
Y68813D01*
X821696Y69696D01*
X823199Y71199D01*
G01X828299Y90114D02*
X829715D01*
X830200Y90599D01*
Y94000D01*
X829700Y94500D01*
X828200D01*
X827800Y94900D01*
Y95800D01*
X826324Y97276D01*
Y105884D01*
X829466Y109026D01*
G01X830120Y78833D02*
X830118D01*
Y74849D01*
X830267Y74700D01*
Y69300D01*
X829307Y68340D01*
X828299D01*
G01X843506Y41033D02*
X843504D01*
Y37109D01*
X843503Y37108D01*
X844021Y36590D01*
Y35710D01*
X843503Y35192D01*
Y34100D01*
G01X813387Y41033D02*
X813385D01*
Y35792D01*
X813147Y34500D01*
X812999Y33700D01*
G01X836813Y41033D02*
X836811D01*
Y37200D01*
X837331Y36680D01*
Y35820D01*
X836811Y35300D01*
Y34101D01*
X836810Y34100D01*
G01X806694Y41033D02*
X806692D01*
Y37108D01*
X807210Y36590D01*
Y35710D01*
X806692Y35192D01*
Y34100D01*
G01X800002Y41033D02*
X800000D01*
Y37200D01*
X800520Y36680D01*
Y35820D01*
X800000Y35300D01*
Y34101D01*
X799999Y34100D01*
G01X820080Y41033D02*
X820078D01*
X819454Y34500D01*
X819378Y33700D01*
G01X907733Y217000D02*
X847304Y156571D01*
Y138000D01*
G01X831125Y119452D02*
X834474Y122801D01*
Y126975D01*
X833824Y127625D01*
X831500D01*
X830177Y128948D01*
Y131252D01*
X831500Y132575D01*
X833824D01*
X834474Y133225D01*
Y154689D01*
X905076Y225291D01*
X912120D01*
G01X829466Y109026D02*
X839900Y119460D01*
Y121794D01*
X840400Y122294D01*
Y123294D01*
X839900Y123794D01*
Y124794D01*
X840400Y125294D01*
Y126294D01*
X839900Y126794D01*
Y127794D01*
X840400Y128294D01*
Y129294D01*
X839900Y129794D01*
Y130794D01*
X840400Y131294D01*
Y132294D01*
X839900Y132794D01*
Y133794D01*
X840550Y134444D01*
X842601D01*
X843774Y135617D01*
Y138221D01*
X842601Y139394D01*
X840550D01*
X839900Y140044D01*
Y143779D01*
X840550Y144429D01*
X843449D01*
X844622Y145602D01*
Y148206D01*
X843449Y149379D01*
X840550D01*
X839900Y150029D01*
Y152953D01*
X906863Y219916D01*
X912752D01*
G01X841741Y173258D02*
X901639Y233156D01*
X913644D01*
G01X832370Y160129D02*
X902800Y230559D01*
X912600D01*
G01X916092Y385393D02*
X912479D01*
X847332Y450540D01*
Y498710D01*
X846642Y499400D01*
X845332D01*
X844642Y498710D01*
Y487690D01*
X843952Y487000D01*
X842642D01*
X841952Y487690D01*
Y511374D01*
X840157Y513169D01*
Y518157D01*
G01X915103Y357309D02*
X906920D01*
X814600Y449629D01*
Y497800D01*
X811874Y500526D01*
Y511452D01*
X810039Y513287D01*
Y518157D01*
G01X915128Y360500D02*
X907487D01*
X817300Y450687D01*
Y498999D01*
X814523Y501776D01*
Y511676D01*
X813085Y513114D01*
G01X916273Y378760D02*
X911498D01*
X841980Y448278D01*
Y463610D01*
X841290Y464300D01*
X839980D01*
X839290Y463610D01*
Y453990D01*
X838600Y453300D01*
X837290D01*
X836600Y453990D01*
Y506000D01*
X835600Y507000D01*
Y510800D01*
X833464Y512936D01*
Y518157D01*
G01X916133Y382843D02*
X911222D01*
X844637Y449428D01*
Y483810D01*
X844047Y484400D01*
X842737D01*
X841947Y483610D01*
Y467647D01*
X841257Y466957D01*
X839947D01*
X839257Y467647D01*
Y507043D01*
X838300Y508000D01*
Y511624D01*
X836810Y513114D01*
G01X915213Y363160D02*
X908585D01*
X820000Y451745D01*
Y500600D01*
X817100Y503500D01*
Y507300D01*
X818654Y508854D01*
Y510672D01*
X816732Y512594D01*
Y518157D01*
G01X915308Y366500D02*
X909003D01*
X822697Y452806D01*
Y459159D01*
X823447Y459909D01*
X825050D01*
X825700Y460559D01*
Y461909D01*
X825050Y462559D01*
X823447D01*
X822797Y463209D01*
Y464559D01*
X823447Y465209D01*
X825050D01*
X825700Y465859D01*
Y467209D01*
X825050Y467859D01*
X823447D01*
X822697Y468609D01*
Y502204D01*
X819900Y505001D01*
Y506100D01*
X821374Y507574D01*
Y512426D01*
X820686Y513114D01*
X819378D01*
G01X915500Y371555D02*
X909361D01*
X826737Y454179D01*
Y456187D01*
X827426Y456876D01*
X828705D01*
X830080Y458251D01*
Y469591D01*
X828505Y471166D01*
X827226D01*
X826524Y471868D01*
Y511975D01*
X823199Y515300D01*
G01X914980Y374281D02*
X910543D01*
X832630Y452194D01*
Y471003D01*
X829530Y474103D01*
Y476797D01*
X832630Y479897D01*
Y481983D01*
X831928Y482685D01*
X830695D01*
X829320Y484060D01*
Y487100D01*
X830695Y488475D01*
X831928D01*
X832630Y489177D01*
Y491263D01*
X831928Y491965D01*
X830695D01*
X829320Y493340D01*
Y496380D01*
X830695Y497755D01*
X831928D01*
X832630Y498457D01*
Y499851D01*
X828963Y503518D01*
Y504974D01*
X829253Y505264D01*
Y506264D01*
X828753Y506764D01*
Y507764D01*
X829253Y508264D01*
Y509264D01*
X828753Y509764D01*
Y510764D01*
X829253Y511264D01*
Y511961D01*
X828300Y512914D01*
X828299D01*
G01X915500Y370405D02*
X908884D01*
X825587Y453702D01*
Y456664D01*
X826949Y458026D01*
X828228D01*
X828930Y458728D01*
Y469114D01*
X828028Y470016D01*
X826749D01*
X825374Y471391D01*
Y504413D01*
X825000Y504787D01*
Y505787D01*
X825374Y506161D01*
Y507451D01*
X825012Y507813D01*
Y508813D01*
X825374Y509175D01*
Y511498D01*
X824172Y512700D01*
X823199D01*
G01X915000Y375431D02*
X911020D01*
X833780Y452671D01*
Y471480D01*
X830680Y474580D01*
Y476320D01*
X833780Y479420D01*
Y482460D01*
X832405Y483835D01*
X831172D01*
X830470Y484537D01*
Y486623D01*
X831172Y487325D01*
X832405D01*
X833780Y488700D01*
Y491740D01*
X832405Y493115D01*
X831172D01*
X830470Y493817D01*
Y495903D01*
X831172Y496605D01*
X832405D01*
X833780Y497980D01*
Y500328D01*
X830403Y503705D01*
Y513411D01*
X828300Y515514D01*
X828299D01*
G01X840159Y523900D02*
X840157Y523923D01*
Y528899D01*
G01X915642Y387943D02*
X913757D01*
X850000Y451700D01*
Y487878D01*
X850650Y488528D01*
X852000D01*
X852650Y487878D01*
Y475250D01*
X853300Y474600D01*
X854650D01*
X855300Y475250D01*
Y501428D01*
X854350Y502378D01*
X846522D01*
X844620Y504280D01*
Y511997D01*
X843503Y513114D01*
G01X810041Y523900D02*
X810039Y523923D01*
Y528899D01*
G01X833466Y523900D02*
X833464Y523923D01*
Y528899D01*
G01X846852Y523900D02*
X846850Y523923D01*
Y528899D01*
G01X803348Y523900D02*
X803346Y523923D01*
Y528899D01*
G01X796655Y523900D02*
X796653Y523923D01*
Y528899D01*
G01X816734Y523900D02*
X816732Y523923D01*
Y528899D01*
G01X826773Y523900D02*
X826771Y523923D01*
Y526496D01*
X825125Y528142D01*
Y529800D01*
X825857Y530532D01*
Y531503D01*
X824865Y532495D01*
X824045D01*
X823300Y531750D01*
X823225D01*
G01X823427Y523900D02*
X823425Y523923D01*
Y526351D01*
X821708Y528068D01*
X821459Y528610D01*
X821375Y528792D01*
Y532013D01*
X821696Y532896D01*
X823199Y534399D01*
G01X843506Y542010D02*
X843503D01*
Y538108D01*
X844021Y537590D01*
Y536710D01*
X843503Y536192D01*
Y535100D01*
G01X812999Y534700D02*
X813385Y536792D01*
Y542010D01*
X813387D01*
G01X836810Y535100D02*
X836811Y535101D01*
Y536300D01*
X837331Y536820D01*
Y537680D01*
X836811Y538200D01*
Y542010D01*
X836813D01*
G01X806694D02*
X806692D01*
Y538108D01*
X807210Y537590D01*
Y536710D01*
X806692Y536192D01*
Y535100D01*
G01X800002Y542010D02*
X800000D01*
Y538200D01*
X800520Y537680D01*
Y536820D01*
X800000Y536300D01*
Y535101D01*
X799999Y535100D01*
G01X820080Y542010D02*
X820078Y542033D01*
X819378Y534700D01*
G01X789962Y542010D02*
X789960D01*
Y537805D01*
X788456Y536301D01*
Y534601D01*
X789757Y533300D01*
X790639D01*
X791488Y534149D01*
G01X828299D02*
X827450Y533300D01*
X826568D01*
X825200Y534668D01*
Y536234D01*
X826771Y537805D01*
Y542010D01*
X826773D01*
G01X793309D02*
X793307D01*
Y538049D01*
X793456Y537900D01*
Y532500D01*
X792496Y531540D01*
X791488D01*
G01X830120Y542010D02*
X830118D01*
Y538049D01*
X830267Y537900D01*
Y532500D01*
X829307Y531540D01*
X828299D01*
G01X843506Y579810D02*
X843503D01*
Y575908D01*
X844021Y575390D01*
Y574510D01*
X843503Y573992D01*
Y572900D01*
G01X840159Y561700D02*
X840157Y561723D01*
Y566699D01*
G01X813387Y579810D02*
X813385D01*
Y574592D01*
X812999Y572500D01*
G01X810041Y561700D02*
X810039Y561723D01*
Y566699D01*
G01X836813Y579810D02*
X836811D01*
Y576000D01*
X837331Y575480D01*
Y574620D01*
X836811Y574100D01*
Y572901D01*
X836810Y572900D01*
G01X833466Y561700D02*
X833464Y561723D01*
Y566699D01*
G01X846852Y561700D02*
X846850Y561723D01*
Y566699D01*
G01X806694Y579810D02*
X806692D01*
Y575908D01*
X807210Y575390D01*
Y574510D01*
X806692Y573992D01*
Y572900D01*
G01X803348Y561700D02*
X803346Y561723D01*
Y566699D01*
G01X800002Y579810D02*
X800000D01*
Y576000D01*
X800520Y575480D01*
Y574620D01*
X800000Y574100D01*
Y572901D01*
X799999Y572900D01*
G01X796655Y561700D02*
X796653Y561723D01*
Y566699D01*
G01X820080Y579810D02*
X820078Y579833D01*
X819378Y572500D01*
G01X816734Y561700D02*
X816732Y561723D01*
Y566699D01*
G01X789962Y579810D02*
X789960D01*
Y575605D01*
X788456Y574101D01*
Y572401D01*
X789757Y571100D01*
X790639D01*
X791488Y571949D01*
G01X826773Y561700D02*
X826771Y561723D01*
Y564296D01*
X825125Y565942D01*
Y567600D01*
X825857Y568332D01*
Y569303D01*
X824865Y570295D01*
X824045D01*
X823300Y569550D01*
X823225D01*
G01X826773Y579810D02*
X826771D01*
Y575605D01*
X825200Y574034D01*
Y572468D01*
X826568Y571100D01*
X827450D01*
X828299Y571949D01*
G01X793309Y579810D02*
X793307D01*
Y575849D01*
X793456Y575700D01*
Y570300D01*
X792496Y569340D01*
X791488D01*
G01X823427Y561700D02*
X823425Y561723D01*
Y564151D01*
X821708Y565868D01*
X821375Y566592D01*
Y569813D01*
X821696Y570696D01*
X823199Y572199D01*
G01X830120Y579810D02*
X830118D01*
Y575849D01*
X830267Y575700D01*
Y570300D01*
X829307Y569340D01*
X828299D01*
G01X843506Y617610D02*
X843503D01*
Y613708D01*
X844021Y613190D01*
Y612310D01*
X843503Y611792D01*
Y610700D01*
G01X840159Y599500D02*
X840157Y599523D01*
Y604499D01*
G01X813387Y617610D02*
X813385D01*
Y612392D01*
X812999Y610300D01*
G01X810041Y599500D02*
X810039Y599523D01*
Y604499D01*
G01X836813Y617610D02*
X836811D01*
Y613800D01*
X837331Y613280D01*
Y612420D01*
X836811Y611900D01*
Y610701D01*
X836810Y610700D01*
G01X833466Y599500D02*
X833464Y599523D01*
Y604499D01*
G01X846852Y599500D02*
X846850Y599523D01*
Y604499D01*
G01X806694Y617610D02*
X806692D01*
Y613708D01*
X807210Y613190D01*
Y612310D01*
X806692Y611792D01*
Y610700D01*
G01X803348Y599500D02*
X803346Y599523D01*
Y604499D01*
G01X800002Y617610D02*
X800000D01*
Y613800D01*
X800520Y613280D01*
Y612420D01*
X800000Y611900D01*
Y610701D01*
X799999Y610700D01*
G01X796655Y599500D02*
X796653Y599523D01*
Y604499D01*
G01X820080Y617610D02*
X820078Y617633D01*
X819378Y610300D01*
G01X816734Y599500D02*
X816732Y599523D01*
Y604499D01*
G01X789962Y617610D02*
X789960D01*
Y613405D01*
X788456Y611901D01*
Y610201D01*
X789757Y608900D01*
X790639D01*
X791488Y609749D01*
G01X826773Y599500D02*
X826771Y599523D01*
Y602096D01*
X825125Y603742D01*
Y605400D01*
X825857Y606132D01*
Y607103D01*
X824865Y608095D01*
X824045D01*
X823300Y607350D01*
X823225D01*
G01X826773Y617610D02*
X826771D01*
Y613405D01*
X825200Y611834D01*
Y610268D01*
X826568Y608900D01*
X827450D01*
X828299Y609749D01*
G01X793309Y617610D02*
X793307D01*
Y613649D01*
X793456Y613500D01*
Y608100D01*
X792496Y607140D01*
X791488D01*
G01X823427Y599500D02*
X823425Y599523D01*
Y601951D01*
X821708Y603668D01*
X821375Y604392D01*
Y607613D01*
X821696Y608496D01*
X823199Y609999D01*
G01X830120Y617610D02*
X830118D01*
Y613649D01*
X830267Y613500D01*
Y608100D01*
X829307Y607140D01*
X828299D01*
G01X853545Y22923D02*
X853543D01*
Y27899D01*
G01X876970Y22923D02*
X876968D01*
Y27899D01*
G01X870277Y22923D02*
X870275D01*
Y27899D01*
G01X890356Y22923D02*
X890354D01*
Y27899D01*
G01X883663Y22923D02*
X883661D01*
Y27899D01*
G01X907088Y22923D02*
X907086D01*
Y27899D01*
G01X863584Y22923D02*
X863582D01*
Y26240D01*
X861936Y27886D01*
Y28800D01*
X862668Y29532D01*
Y30503D01*
X861676Y31495D01*
X860781D01*
X860036Y30750D01*
G01X900395Y22923D02*
X900393D01*
Y26240D01*
X898747Y27886D01*
Y28800D01*
X899479Y29532D01*
Y30503D01*
X898487Y31495D01*
X897592D01*
X896847Y30750D01*
G01X863584Y41033D02*
X863582D01*
Y37045D01*
X862536Y35999D01*
Y33114D01*
X865110Y30540D01*
G01X900395Y41033D02*
X900393D01*
Y36805D01*
X898822Y35234D01*
Y33668D01*
X900190Y32300D01*
X901072D01*
X901921Y33149D01*
G01X860238Y22923D02*
X860236D01*
Y25351D01*
X858519Y27068D01*
X858186Y27792D01*
Y31013D01*
X858507Y31896D01*
X860010Y33399D01*
G01X897049Y22923D02*
X897047D01*
Y25351D01*
X895330Y27068D01*
X894997Y27792D01*
Y31013D01*
X895318Y31896D01*
X896821Y33399D01*
G01X866931Y41033D02*
Y36711D01*
X866928Y36708D01*
X867801Y35835D01*
Y32913D01*
X866959Y32071D01*
X866188D01*
X865110Y33149D01*
G01X903742Y41033D02*
X903740D01*
Y37049D01*
X903889Y36900D01*
Y31500D01*
X902929Y30540D01*
X901921D01*
G01X856891Y3233D02*
X856889D01*
X856189Y-4100D01*
G01X853545Y-14877D02*
X853543D01*
Y-9901D01*
G01X880317Y3233D02*
Y-695D01*
X880832Y-1210D01*
Y-2090D01*
X880314Y-2608D01*
Y-3700D01*
G01X876970Y-14877D02*
X876968D01*
Y-9901D01*
G01X850198Y3233D02*
X850196D01*
Y-2008D01*
X849810Y-4100D01*
G01X873624Y3233D02*
X873622D01*
Y-600D01*
X874142Y-1120D01*
Y-1980D01*
X873622Y-2500D01*
Y-3699D01*
X873621Y-3700D01*
G01X870277Y-14877D02*
X870275D01*
Y-9901D01*
G01X893702Y3233D02*
X893700D01*
X893000Y-4100D01*
G01X890356Y-14877D02*
X890354D01*
Y-9901D01*
G01X887009Y3233D02*
X887007D01*
Y-2008D01*
X886621Y-4100D01*
G01X883663Y-14877D02*
X883661D01*
Y-9901D01*
G01X907088Y-14877D02*
X907086D01*
Y-9901D01*
G01X863584Y-14877D02*
X863582D01*
Y-11560D01*
X861936Y-9914D01*
Y-9000D01*
X862668Y-8268D01*
Y-7297D01*
X861676Y-6305D01*
X860856D01*
X860111Y-7050D01*
X860036D01*
G01X900395Y-14877D02*
X900393D01*
Y-11560D01*
X898747Y-9914D01*
Y-9000D01*
X899479Y-8268D01*
Y-7297D01*
X898487Y-6305D01*
X897667D01*
X896922Y-7050D01*
X896847D01*
G01X863584Y3233D02*
X863582D01*
Y-755D01*
X862536Y-1801D01*
Y-4686D01*
X865110Y-7260D01*
G01X900395Y3233D02*
X900393D01*
Y-755D01*
X899347Y-1801D01*
Y-4686D01*
X901921Y-7260D01*
G01X860238Y-14877D02*
X860236D01*
Y-12449D01*
X858519Y-10732D01*
X858186Y-10008D01*
Y-6787D01*
X858507Y-5904D01*
X860010Y-4401D01*
G01X897049Y-14877D02*
X897047D01*
Y-12449D01*
X895330Y-10732D01*
X894997Y-10008D01*
Y-6787D01*
X895318Y-5904D01*
X896821Y-4401D01*
G01X866931Y3233D02*
X866929D01*
Y-1093D01*
X867801Y-1965D01*
Y-4887D01*
X866959Y-5729D01*
X866188D01*
X865110Y-4651D01*
G01X903742Y3233D02*
X903740D01*
Y-1093D01*
X904612Y-1965D01*
Y-4887D01*
X903770Y-5729D01*
X902999D01*
X901921Y-4651D01*
G01X856891Y78833D02*
X856889D01*
X856571Y75500D01*
X856189Y71500D01*
G01X853545Y60723D02*
X853543D01*
Y65699D01*
G01X880317Y78833D02*
Y71903D01*
X880314Y71900D01*
G01X876970Y60723D02*
X876968D01*
Y65699D01*
G01X850198Y78833D02*
X850196D01*
Y73592D01*
X849810Y71500D01*
G01X873624Y78833D02*
X873622D01*
Y75000D01*
X874142Y74480D01*
Y73620D01*
X873622Y73100D01*
Y71901D01*
X873621Y71900D01*
G01X870277Y60723D02*
X870275D01*
Y65699D01*
G01X893702Y78833D02*
X893700D01*
X893382Y75500D01*
X893000Y71500D01*
G01X890356Y60723D02*
X890354D01*
Y65699D01*
G01X887009Y78833D02*
X887007D01*
Y73592D01*
X886621Y71500D01*
G01X883663Y60723D02*
X883661D01*
Y65699D01*
G01X907088Y60723D02*
X907086D01*
Y65699D01*
G01X863584Y60723D02*
X863582D01*
Y63296D01*
X861936Y64942D01*
Y66600D01*
X862668Y67332D01*
Y68303D01*
X861676Y69295D01*
X860856D01*
X860111Y68550D01*
X860036D01*
G01X900395Y60723D02*
X900393D01*
Y63296D01*
X898747Y64942D01*
Y66600D01*
X899479Y67332D01*
Y68303D01*
X898487Y69295D01*
X897667D01*
X896922Y68550D01*
X896847D01*
G01X863584Y78833D02*
X863582D01*
Y74605D01*
X862078Y73101D01*
Y71401D01*
X863379Y70100D01*
X864261D01*
X865110Y70949D01*
G01X900395Y78833D02*
X900393D01*
Y74605D01*
X898889Y73101D01*
Y71401D01*
X900190Y70100D01*
X901072D01*
X901921Y70949D01*
G01X860238Y60723D02*
X860236D01*
Y63151D01*
X858519Y64868D01*
X858186Y65592D01*
Y68813D01*
X858507Y69696D01*
X860010Y71199D01*
G01X897049Y60723D02*
X897047D01*
Y63151D01*
X895330Y64868D01*
X894997Y65592D01*
Y68813D01*
X895318Y69696D01*
X896821Y71199D01*
G01X866931Y78833D02*
X866929D01*
Y74849D01*
X867078Y74700D01*
Y69300D01*
X866118Y68340D01*
X865110D01*
G01X903742Y78833D02*
X903740D01*
Y74849D01*
X903889Y74700D01*
Y69300D01*
X902929Y68340D01*
X901921D01*
G01X856891Y41033D02*
X856889D01*
X856265Y34500D01*
X856189Y33700D01*
G01X880317Y41033D02*
Y37105D01*
X880832Y36590D01*
Y35710D01*
X880314Y35192D01*
Y34100D01*
G01X850198Y41033D02*
X850196D01*
Y35792D01*
X849958Y34500D01*
X849810Y33700D01*
G01X873624Y41033D02*
X873622D01*
Y37200D01*
X874142Y36680D01*
Y35820D01*
X873622Y35300D01*
Y34101D01*
X873621Y34100D01*
G01X893702Y41033D02*
X893700D01*
X893076Y34500D01*
X893000Y33700D01*
G01X887009Y41033D02*
X887007D01*
Y35792D01*
X886769Y34500D01*
X886621Y33700D01*
G01X861026Y141000D02*
Y159018D01*
X912552Y210544D01*
G01X910608Y212359D02*
X858337Y160088D01*
Y125500D01*
G01X850036Y128500D02*
Y148882D01*
X850686Y149532D01*
X852036D01*
X852686Y148882D01*
Y139259D01*
X853336Y138609D01*
X854686D01*
X855336Y139259D01*
Y151532D01*
X854686Y152182D01*
X850686D01*
X850036Y152832D01*
Y155545D01*
X908991Y214500D01*
G01X889500Y135000D02*
Y149951D01*
X888810Y150641D01*
Y166834D01*
X908237Y186261D01*
X908238D01*
G01X890354Y112327D02*
X889500Y113181D01*
Y118141D01*
X888850Y118791D01*
X887450D01*
X886800Y119441D01*
Y120791D01*
X887450Y121441D01*
X888850D01*
X889500Y122091D01*
Y123441D01*
X888850Y124091D01*
X887450D01*
X886800Y124741D01*
Y126091D01*
X887450Y126741D01*
X888850D01*
X889500Y127391D01*
Y128741D01*
X888850Y129391D01*
X887450D01*
X886800Y130041D01*
Y131391D01*
X887450Y132041D01*
X888850D01*
X889500Y132691D01*
Y135000D01*
G01X892200Y142000D02*
Y148101D01*
X895350Y151251D01*
Y152678D01*
X894700Y153328D01*
X893850D01*
X893200Y153978D01*
Y155328D01*
X893850Y155978D01*
X894700D01*
X895350Y156628D01*
Y157978D01*
X894700Y158628D01*
X892250D01*
X891600Y159278D01*
Y160628D01*
X892250Y161278D01*
X894700D01*
X895350Y161928D01*
Y169757D01*
X910046Y184453D01*
G01X893000Y106934D02*
X890024D01*
X889374Y107584D01*
Y108674D01*
X892200Y111500D01*
Y142000D01*
G01X883661Y112327D02*
X881100Y114888D01*
Y140500D01*
G01D02*
Y147750D01*
X883200Y149850D01*
Y152712D01*
X882550Y153362D01*
X881050D01*
X880400Y154012D01*
Y155362D01*
X881050Y156012D01*
X882550D01*
X883200Y156662D01*
Y158012D01*
X882550Y158662D01*
X881050D01*
X880400Y159312D01*
Y160662D01*
X881050Y161312D01*
X882550D01*
X883200Y161962D01*
Y168449D01*
X904624Y189873D01*
X904626D01*
G01X886707Y107284D02*
X886675D01*
X884800Y109159D01*
Y110800D01*
X885486Y111486D01*
Y114364D01*
X883800Y116050D01*
Y134000D01*
G01D02*
Y137800D01*
X886100Y140100D01*
Y167700D01*
X906400Y188000D01*
G01X907086Y112327D02*
X906100Y113313D01*
Y117446D01*
X905410Y118136D01*
X905390D01*
X904700Y118826D01*
Y120136D01*
X905390Y120826D01*
X905410D01*
X906100Y121516D01*
Y122826D01*
X905410Y123516D01*
X905390D01*
X904700Y124206D01*
Y125516D01*
X905390Y126206D01*
X905410D01*
X906100Y126896D01*
Y130000D01*
G01D02*
Y163350D01*
X906600Y163850D01*
X908290D01*
X908790Y163350D01*
Y155600D01*
X909290Y155100D01*
X910980D01*
X911480Y155600D01*
Y171787D01*
X917095Y177402D01*
G01X910432Y107284D02*
X908600Y109116D01*
Y111143D01*
X909300Y111843D01*
Y113557D01*
X908757Y114100D01*
Y140500D01*
G01D02*
Y146860D01*
X909447Y147550D01*
X910757D01*
X911447Y146860D01*
Y144650D01*
X912097Y144000D01*
X913487D01*
X914137Y144650D01*
Y170836D01*
X918899Y175598D01*
G01X896821Y110514D02*
X897853D01*
X898616Y111277D01*
Y114337D01*
X897853Y115100D01*
X896500D01*
X896050Y115550D01*
Y116510D01*
X896570Y117030D01*
Y118030D01*
X896050Y118550D01*
Y119510D01*
X896570Y120030D01*
Y121030D01*
X896050Y121550D01*
Y122510D01*
X896570Y123030D01*
Y124030D01*
X896050Y124550D01*
Y125510D01*
X896570Y126030D01*
Y127030D01*
X896050Y127550D01*
Y128763D01*
X896752Y129465D01*
X898227D01*
X899550Y130788D01*
Y133932D01*
X898227Y135255D01*
X896752D01*
X896050Y135957D01*
Y138043D01*
X896752Y138745D01*
X898105D01*
X899480Y140120D01*
Y141500D01*
G01D02*
Y143160D01*
X898105Y144535D01*
X897000D01*
X896350Y145185D01*
Y146608D01*
X899450Y149708D01*
Y168615D01*
X912651Y181816D01*
G01X901921Y107655D02*
X900152Y109424D01*
Y114428D01*
X900100Y114480D01*
Y127356D01*
X902220Y129476D01*
Y135500D01*
G01D02*
Y167770D01*
X914464Y180014D01*
G01X896847Y107865D02*
X894900Y109812D01*
Y125500D01*
G01D02*
Y129240D01*
X896275Y130615D01*
X897750D01*
X898400Y131265D01*
Y133455D01*
X897750Y134105D01*
X896275D01*
X894900Y135480D01*
Y138520D01*
X896275Y139895D01*
X897628D01*
X898330Y140597D01*
Y142683D01*
X897628Y143385D01*
X896523D01*
X895200Y144708D01*
Y147085D01*
X898300Y150185D01*
Y169092D01*
X911838Y182630D01*
G01X901947Y110264D02*
X903027D01*
X903800Y111037D01*
Y113900D01*
X902900Y114800D01*
X901800D01*
X901250Y115350D01*
Y116310D01*
X901770Y116830D01*
Y117830D01*
X901250Y118350D01*
Y119310D01*
X901770Y119830D01*
Y120830D01*
X901250Y121350D01*
Y123500D01*
G01D02*
Y126879D01*
X903370Y128999D01*
Y167293D01*
X915277Y179200D01*
G01X930843Y407449D02*
X919396D01*
X890517Y436328D01*
X888300Y441679D01*
Y446703D01*
X888950Y447353D01*
X889450D01*
X890100Y448003D01*
Y449303D01*
X889450Y449953D01*
X888950D01*
X888300Y450603D01*
Y451903D01*
X888950Y452553D01*
X889450D01*
X890100Y453203D01*
Y454503D01*
X889450Y455153D01*
X888950D01*
X888300Y455803D01*
Y457103D01*
X888950Y457753D01*
X889450D01*
X890100Y458403D01*
Y459703D01*
X889450Y460353D01*
X888950D01*
X888300Y461003D01*
Y462303D01*
X888950Y462953D01*
X889676D01*
X890352Y463629D01*
Y464929D01*
X889728Y465553D01*
X888950D01*
X888300Y466203D01*
Y495000D01*
X889200Y495900D01*
G01X930843Y409999D02*
X920410D01*
X892900Y437509D01*
Y441158D01*
X892250Y441808D01*
X891472D01*
X890822Y442458D01*
Y443808D01*
X891472Y444458D01*
X892250D01*
X892900Y445108D01*
Y455248D01*
X892184Y455964D01*
Y456970D01*
X892900Y457686D01*
Y467406D01*
X892250Y468056D01*
X891474D01*
X890824Y468706D01*
Y470006D01*
X891474Y470656D01*
X892426D01*
X893076Y471306D01*
Y472606D01*
X892426Y473256D01*
X891474D01*
X890824Y473906D01*
Y475206D01*
X891474Y475856D01*
X892427D01*
X893077Y476506D01*
Y477806D01*
X892427Y478456D01*
X891473D01*
X890823Y479106D01*
Y480406D01*
X891473Y481056D01*
X892451D01*
X893051Y481656D01*
Y482956D01*
X892351Y483656D01*
X891473D01*
X890900Y484229D01*
Y485600D01*
X891500Y486200D01*
X892540D01*
X893040Y486700D01*
Y488110D01*
X892400Y488750D01*
X891400D01*
X890900Y489250D01*
Y490472D01*
X891719Y491291D01*
X894500D01*
X895000Y491791D01*
Y495116D01*
X894422Y495694D01*
X893000D01*
G01X930264Y402349D02*
X915412D01*
X887417Y430344D01*
X881100Y445593D01*
Y497100D01*
X882500Y498500D01*
X882900D01*
G01X929782Y404899D02*
X917279D01*
X889097Y433081D01*
X883700Y446111D01*
Y448400D01*
X885600Y450300D01*
Y453000D01*
X883700Y454900D01*
Y456500D01*
X885779Y458579D01*
Y460021D01*
X883700Y462100D01*
Y463700D01*
X885779Y465779D01*
Y467121D01*
X883700Y469200D01*
Y470700D01*
X885779Y472779D01*
Y473921D01*
X883700Y476000D01*
Y477600D01*
X885400Y479300D01*
Y480601D01*
X883700Y482301D01*
Y484001D01*
X885100Y485401D01*
Y489400D01*
X886500Y490800D01*
G01X935849Y419949D02*
X928400D01*
X907640Y440709D01*
Y444112D01*
X906846Y444906D01*
X905460D01*
X904783Y445583D01*
Y446893D01*
X905486Y447596D01*
X906846D01*
X907536Y448286D01*
Y451462D01*
X907036Y451962D01*
X906312D01*
X905812Y452462D01*
Y454101D01*
X906363Y454652D01*
X907036D01*
X907666Y455282D01*
Y461370D01*
X906837Y462199D01*
X905653D01*
X903203Y464649D01*
Y473250D01*
X905500Y475547D01*
Y486100D01*
X908600Y489200D01*
Y494700D01*
X909000Y495100D01*
Y496573D01*
X907086Y498487D01*
G01X934756Y422499D02*
X929452D01*
X910193Y441758D01*
Y445139D01*
X909468Y445864D01*
Y446634D01*
X910193Y447359D01*
Y453586D01*
X910994Y454387D01*
Y455458D01*
X910193Y456259D01*
Y464166D01*
X909503Y464856D01*
X906564D01*
X905849Y465571D01*
Y466881D01*
X906514Y467546D01*
X909793D01*
X910395Y468148D01*
Y469596D01*
X909755Y470236D01*
X906437D01*
X905773Y470900D01*
Y472210D01*
X906489Y472926D01*
X909652D01*
X910393Y473667D01*
Y474977D01*
X909754Y475616D01*
X908790D01*
X908100Y476306D01*
Y477616D01*
X908790Y478306D01*
X909679D01*
X910395Y479022D01*
Y480332D01*
X909731Y480996D01*
X908790D01*
X908100Y481686D01*
Y482996D01*
X908790Y483686D01*
X909503D01*
X910193Y484376D01*
Y487193D01*
X912300Y489300D01*
Y493244D01*
X911800Y493744D01*
X910432D01*
G01X936256Y413699D02*
X936255Y413700D01*
X923276D01*
X896770Y440206D01*
Y476401D01*
X897400Y477031D01*
Y482368D01*
X896770Y482998D01*
Y486171D01*
X899874Y489275D01*
Y492871D01*
X896836Y495909D01*
G01X936256Y416259D02*
X926491D01*
X925714Y417036D01*
X925007D01*
X924228Y417815D01*
Y418522D01*
X923451Y419299D01*
X922744D01*
X921965Y420078D01*
Y420785D01*
X921188Y421562D01*
X920481D01*
X919702Y422341D01*
Y423048D01*
X918925Y423825D01*
X918218D01*
X917439Y424604D01*
Y425311D01*
X916593Y426157D01*
X915886D01*
X915107Y426936D01*
Y427643D01*
X914330Y428420D01*
X913623D01*
X912844Y429199D01*
Y429906D01*
X912067Y430683D01*
X911360D01*
X910581Y431462D01*
Y432169D01*
X909804Y432946D01*
X909097D01*
X908318Y433725D01*
Y434432D01*
X907541Y435209D01*
X906834D01*
X906055Y435988D01*
Y436695D01*
X905278Y437472D01*
X904571D01*
X903792Y438251D01*
Y438958D01*
X903015Y439735D01*
X902308D01*
X901529Y440514D01*
Y441221D01*
X899900Y442850D01*
Y444550D01*
X899400Y445050D01*
Y446150D01*
X899900Y446650D01*
Y447750D01*
X901113Y448963D01*
X901628D01*
X902330Y449665D01*
Y450991D01*
X901628Y451693D01*
X900905D01*
X899530Y453068D01*
Y455348D01*
X900905Y456723D01*
X903217D01*
X903709Y457215D01*
Y458936D01*
X903192Y459453D01*
X900905D01*
X899530Y460828D01*
Y474786D01*
X901650Y476906D01*
Y477750D01*
X901130Y478270D01*
Y479330D01*
X901650Y479850D01*
Y481050D01*
X901100Y481600D01*
Y482600D01*
X901650Y483150D01*
Y484150D01*
X901004Y484796D01*
Y485704D01*
X901650Y486350D01*
Y487450D01*
X903824Y489624D01*
Y492284D01*
X902894Y493214D01*
X901921D01*
G01X936256Y412549D02*
X935779D01*
X935778Y412550D01*
X922799D01*
X921892Y413457D01*
X921185D01*
X920407Y414235D01*
Y414942D01*
X919630Y415719D01*
X918923D01*
X918144Y416498D01*
Y417205D01*
X895620Y439729D01*
Y476878D01*
X896250Y477508D01*
Y481891D01*
X895620Y482521D01*
Y486648D01*
X896258Y487286D01*
Y487804D01*
X896966Y488512D01*
X897484D01*
X898724Y489752D01*
Y492394D01*
X897909Y493209D01*
X896836D01*
G01X936256Y417399D02*
Y417409D01*
X926968D01*
X901050Y443327D01*
Y447273D01*
X901590Y447813D01*
X902105D01*
X903480Y449188D01*
Y451468D01*
X902105Y452843D01*
X901382D01*
X900680Y453545D01*
Y454871D01*
X901382Y455573D01*
X903694D01*
X904859Y456738D01*
Y459413D01*
X903669Y460603D01*
X901382D01*
X900680Y461305D01*
Y474309D01*
X902800Y476429D01*
Y486973D01*
X904974Y489147D01*
Y492761D01*
X901921Y495814D01*
G01X853545Y523900D02*
X853543Y523923D01*
Y528899D01*
G01X876970Y523900D02*
X876968Y523923D01*
Y528899D01*
G01X870277Y523900D02*
X870275Y523923D01*
Y528899D01*
G01X890356Y523900D02*
X890354Y523923D01*
Y528899D01*
G01X883663Y523900D02*
X883661Y523923D01*
Y528899D01*
G01X907088Y523900D02*
X907086Y523923D01*
Y528899D01*
G01X863584Y523900D02*
X863582Y523923D01*
Y526496D01*
X861936Y528142D01*
Y529800D01*
X862668Y530532D01*
Y531503D01*
X861676Y532495D01*
X860856D01*
X860111Y531750D01*
X860036D01*
G01X900395Y523900D02*
X900393Y523923D01*
Y526496D01*
X898747Y528142D01*
Y529800D01*
X899479Y530532D01*
Y531503D01*
X898487Y532495D01*
X897667D01*
X896922Y531750D01*
X896847D01*
G01X860238Y523900D02*
X860236Y523923D01*
Y526351D01*
X858519Y528068D01*
X858270Y528610D01*
X858186Y528792D01*
Y532013D01*
X858507Y532896D01*
X860010Y534399D01*
G01X897049Y523900D02*
X897047Y523923D01*
Y526351D01*
X895330Y528068D01*
X895081Y528610D01*
X894997Y528792D01*
Y532013D01*
X895318Y532896D01*
X896821Y534399D01*
G01X856891Y542010D02*
X856889Y542033D01*
X856189Y534700D01*
G01X880317Y542010D02*
X880314D01*
Y538108D01*
X880832Y537590D01*
Y536710D01*
X880314Y536192D01*
Y535100D01*
G01X850198Y542010D02*
X850196D01*
Y536792D01*
X849810Y534700D01*
G01X873624Y542010D02*
X873622D01*
Y538200D01*
X874142Y537680D01*
Y536820D01*
X873622Y536300D01*
Y535101D01*
X873621Y535100D01*
G01X893702Y542010D02*
X893700Y542033D01*
X893000Y534700D01*
G01X887009Y542010D02*
X887007D01*
Y536792D01*
X886621Y534700D01*
G01X865110Y534149D02*
X864261Y533300D01*
X863379D01*
X862078Y534601D01*
Y536301D01*
X863582Y537805D01*
Y542010D01*
X863584D01*
G01X900395D02*
X900393D01*
Y537805D01*
X898889Y536301D01*
Y534601D01*
X900190Y533300D01*
X901072D01*
X901921Y534149D01*
G01X866931Y542010D02*
X866929D01*
Y538049D01*
X867078Y537900D01*
Y532500D01*
X866118Y531540D01*
X865110D01*
G01X903742Y542010D02*
X903740D01*
Y538049D01*
X903889Y537900D01*
Y532500D01*
X902929Y531540D01*
X901921D01*
G01X856891Y579810D02*
X856889Y579833D01*
X856189Y572500D01*
G01X853545Y561700D02*
X853543Y561723D01*
Y566699D01*
G01X880317Y579810D02*
X880314D01*
Y575908D01*
X880832Y575390D01*
Y574510D01*
X880314Y573992D01*
Y572900D01*
G01X876970Y561700D02*
X876968Y561723D01*
Y566699D01*
G01X850198Y579810D02*
X850196D01*
Y574592D01*
X849810Y572500D01*
G01X873624Y579810D02*
X873622D01*
Y576000D01*
X874142Y575480D01*
Y574620D01*
X873622Y574100D01*
Y572901D01*
X873621Y572900D01*
G01X870277Y561700D02*
X870275Y561723D01*
Y566699D01*
G01X893702Y579810D02*
X893700Y579833D01*
X893000Y572500D01*
G01X890356Y561700D02*
X890354Y561723D01*
Y566699D01*
G01X887009Y579810D02*
X887007D01*
Y574592D01*
X886621Y572500D01*
G01X883663Y561700D02*
X883661Y561723D01*
Y566699D01*
G01X907088Y561700D02*
X907086Y561723D01*
Y566699D01*
G01X863584Y561700D02*
X863582Y561723D01*
Y564296D01*
X861936Y565942D01*
Y567600D01*
X862668Y568332D01*
Y569303D01*
X861676Y570295D01*
X860856D01*
X860111Y569550D01*
X860036D01*
G01X900395Y561700D02*
X900393Y561723D01*
Y564296D01*
X898747Y565942D01*
Y567600D01*
X899479Y568332D01*
Y569303D01*
X898487Y570295D01*
X897667D01*
X896922Y569550D01*
X896847D01*
G01X863584Y579810D02*
X863582D01*
Y575605D01*
X862078Y574101D01*
Y572401D01*
X863379Y571100D01*
X864261D01*
X865110Y571949D01*
G01X900395Y579810D02*
X900393D01*
Y575605D01*
X898889Y574101D01*
Y572401D01*
X900190Y571100D01*
X901072D01*
X901921Y571949D01*
G01X860238Y561700D02*
X860236Y561723D01*
Y564151D01*
X858519Y565868D01*
X858186Y566592D01*
Y569813D01*
X858507Y570696D01*
X860010Y572199D01*
G01X897049Y561700D02*
X897047Y561723D01*
Y564151D01*
X895330Y565868D01*
X894997Y566592D01*
Y569813D01*
X895318Y570696D01*
X896821Y572199D01*
G01X866931Y579810D02*
X866929D01*
Y575849D01*
X867078Y575700D01*
Y570300D01*
X866118Y569340D01*
X865110D01*
G01X903742Y579810D02*
X903740D01*
Y575849D01*
X903889Y575700D01*
Y570300D01*
X902929Y569340D01*
X901921D01*
G01X856891Y617610D02*
X856889Y617633D01*
X856189Y610300D01*
G01X853545Y599500D02*
X853543Y599523D01*
Y604499D01*
G01X880314Y610700D02*
Y611792D01*
X880832Y612310D01*
Y613190D01*
X880314Y613708D01*
Y617610D01*
X880317D01*
G01X876970Y599500D02*
X876968Y599523D01*
Y604499D01*
G01X850198Y617610D02*
X850196D01*
Y612392D01*
X849810Y610300D01*
G01X873621Y610700D02*
X873622Y610701D01*
Y611900D01*
X874142Y612420D01*
Y613280D01*
X873622Y613800D01*
Y617610D01*
X873624D01*
G01X870277Y599500D02*
X870275Y599523D01*
Y604499D01*
G01X893702Y617610D02*
X893700Y617633D01*
X893000Y610300D01*
G01X890356Y599500D02*
X890354Y599523D01*
Y604499D01*
G01X886621Y610300D02*
X887007Y612392D01*
Y617610D01*
X887009D01*
G01X883663Y599500D02*
X883661Y599523D01*
Y604499D01*
G01X907088Y599500D02*
X907086Y599523D01*
Y604499D01*
G01X863584Y599500D02*
X863582Y599523D01*
Y602096D01*
X861936Y603742D01*
Y605400D01*
X862668Y606132D01*
Y607103D01*
X861676Y608095D01*
X860856D01*
X860111Y607350D01*
X860036D01*
G01X900395Y599500D02*
X900393Y599523D01*
Y602096D01*
X898747Y603742D01*
Y605400D01*
X899479Y606132D01*
Y607103D01*
X898487Y608095D01*
X897667D01*
X896922Y607350D01*
X896847D01*
G01X863584Y617610D02*
X863582D01*
Y613405D01*
X862078Y611901D01*
Y610201D01*
X863379Y608900D01*
X864261D01*
X865110Y609749D01*
G01X900395Y617610D02*
X900393D01*
Y613405D01*
X898889Y611901D01*
Y610201D01*
X900190Y608900D01*
X901072D01*
X901921Y609749D01*
G01X860238Y599500D02*
X860236Y599523D01*
Y601951D01*
X858519Y603668D01*
X858186Y604392D01*
Y607613D01*
X858507Y608496D01*
X860010Y609999D01*
G01X897049Y599500D02*
X897047Y599523D01*
Y601951D01*
X895330Y603668D01*
X894997Y604392D01*
Y607613D01*
X895318Y608496D01*
X896821Y609999D01*
G01X865110Y607140D02*
X866118D01*
X867078Y608100D01*
Y613500D01*
X866929Y613649D01*
Y617610D01*
X866931D01*
G01X903742D02*
X903740D01*
Y613649D01*
X903889Y613500D01*
Y608100D01*
X902929Y607140D01*
X901921D01*
G01X970671Y22923D02*
X970669D01*
Y28014D01*
G01X963978Y22923D02*
X963976D01*
Y28014D01*
G01X913781Y22923D02*
X913779D01*
Y27899D01*
G01X937206Y22923D02*
X937204D01*
Y26240D01*
X935558Y27886D01*
Y28800D01*
X936290Y29532D01*
Y30503D01*
X935298Y31495D01*
X934403D01*
X933658Y30750D01*
G01X937206Y41033D02*
X937204D01*
Y36805D01*
X935633Y35234D01*
Y33668D01*
X937001Y32300D01*
X937883D01*
X938732Y33149D01*
G01X933860Y22923D02*
X933858D01*
Y25351D01*
X932141Y27068D01*
X931808Y27792D01*
Y31013D01*
X932129Y31896D01*
X933632Y33399D01*
G01X940553Y41033D02*
X940551D01*
Y37049D01*
X940700Y36900D01*
Y31500D01*
X939740Y30540D01*
X938732D01*
G01X927167Y22923D02*
X927165D01*
Y27899D01*
G01X950592Y22923D02*
Y27897D01*
X950590Y27899D01*
G01X920474Y22923D02*
X920472D01*
Y27899D01*
G01X943899Y22923D02*
X943897D01*
Y27899D01*
G01X970671Y-14877D02*
X970669D01*
Y-7108D01*
G01X963978Y-14877D02*
X963976D01*
Y-7108D01*
G01X960631Y3233D02*
X960629D01*
Y-4536D01*
G01X917128Y3233D02*
X917125Y3230D01*
Y-692D01*
X917643Y-1210D01*
Y-2090D01*
X917125Y-2608D01*
Y-3700D01*
G01X913781Y-14877D02*
X913779D01*
Y-9901D01*
G01X910435Y3233D02*
X910433D01*
Y-600D01*
X910953Y-1120D01*
Y-1980D01*
X910433Y-2500D01*
Y-3699D01*
X910432Y-3700D01*
G01X937206Y-14877D02*
X937204D01*
Y-11560D01*
X935558Y-9914D01*
Y-9000D01*
X936290Y-8268D01*
Y-7297D01*
X935298Y-6305D01*
X934478D01*
X933733Y-7050D01*
X933658D01*
G01X937206Y3233D02*
X937204D01*
Y-755D01*
X936158Y-1801D01*
Y-4686D01*
X938732Y-7260D01*
G01X933860Y-14877D02*
X933858D01*
Y-12449D01*
X932141Y-10732D01*
X931808Y-10008D01*
Y-6787D01*
X932129Y-5904D01*
X933632Y-4401D01*
G01X940553Y3233D02*
X940550Y3230D01*
Y-1092D01*
X941423Y-1965D01*
Y-4887D01*
X940581Y-5729D01*
X939810D01*
X938732Y-4651D01*
G01X930513Y3233D02*
X930511D01*
X929811Y-4100D01*
G01X927167Y-14877D02*
X927165D01*
Y-9901D01*
G01X953939Y3233D02*
X953936Y3230D01*
Y-692D01*
X954454Y-1210D01*
Y-2090D01*
X953936Y-2608D01*
Y-3700D01*
G01X950592Y-14877D02*
X950590D01*
Y-9901D01*
G01X923820Y3233D02*
X923818D01*
Y-2008D01*
X923432Y-4100D01*
G01X920474Y-14877D02*
X920472D01*
Y-9901D01*
G01X947246Y3233D02*
X947244D01*
Y-600D01*
X947764Y-1120D01*
Y-1980D01*
X947244Y-2500D01*
Y-3699D01*
X947243Y-3700D01*
G01X943899Y-14877D02*
X943897D01*
Y-9901D01*
G01X970671Y60723D02*
X970669D01*
Y65814D01*
G01X981200Y115148D02*
Y104700D01*
X975500Y99000D01*
X973400D01*
X970669Y96269D01*
Y92757D01*
G01X963978Y60723D02*
X963976D01*
Y65814D01*
G01X960631Y78833D02*
X960629D01*
Y81771D01*
X958300Y84100D01*
Y85300D01*
X959600Y86600D01*
Y88400D01*
X958600Y89400D01*
Y90700D01*
X959800Y91900D01*
Y99500D01*
X965500Y105200D01*
Y106500D01*
X967478Y108478D01*
G01X963976Y92657D02*
Y97176D01*
X969650Y102850D01*
Y104150D01*
X972825Y107325D01*
G01X960629Y84714D02*
X961900Y85985D01*
Y88500D01*
X962600Y89200D01*
Y90700D01*
X961800Y91500D01*
Y98599D01*
X967500Y104299D01*
Y105500D01*
X974300Y112300D01*
Y115182D01*
G01X917128Y78833D02*
X917125Y78830D01*
Y74908D01*
X917643Y74390D01*
Y73510D01*
X917125Y72992D01*
Y71900D01*
G01X913781Y60723D02*
X913779D01*
Y65699D01*
G01X910435Y78833D02*
X910433D01*
Y75000D01*
X910953Y74480D01*
Y73620D01*
X910433Y73100D01*
Y71901D01*
X910432Y71900D01*
G01X937206Y60723D02*
X937204D01*
Y63296D01*
X935558Y64942D01*
Y66600D01*
X936290Y67332D01*
Y68303D01*
X935298Y69295D01*
X934478D01*
X933733Y68550D01*
X933658D01*
G01X937206Y78833D02*
X937204D01*
Y74605D01*
X935700Y73101D01*
Y71401D01*
X937001Y70100D01*
X937883D01*
X938732Y70949D01*
G01X933860Y60723D02*
X933858D01*
Y63151D01*
X932141Y64868D01*
X931808Y65592D01*
Y68813D01*
X932129Y69696D01*
X933632Y71199D01*
G01X940553Y78833D02*
X940551D01*
Y74849D01*
X940700Y74700D01*
Y69300D01*
X939740Y68340D01*
X938732D01*
G01X930513Y78833D02*
X930511D01*
X930193Y75500D01*
X929811Y71500D01*
G01X927167Y60723D02*
X927165D01*
Y65699D01*
G01X953939Y78833D02*
Y74911D01*
X953936Y74908D01*
X954454Y74390D01*
Y73510D01*
X953936Y72992D01*
Y71900D01*
G01X950592Y60723D02*
X950590D01*
Y65699D01*
G01X923820Y78833D02*
X923818D01*
Y73592D01*
X923432Y71500D01*
G01X920474Y60723D02*
X920472D01*
Y65699D01*
G01X947246Y78833D02*
X947244D01*
Y75000D01*
X947764Y74480D01*
Y73620D01*
X947244Y73100D01*
Y71901D01*
X947243Y71900D01*
G01X943899Y60723D02*
X943897D01*
Y65699D01*
G01X960631Y41033D02*
X960629D01*
Y35957D01*
G01X917128Y41033D02*
X917125Y41030D01*
Y37108D01*
X917643Y36590D01*
Y35710D01*
X917125Y35192D01*
Y34100D01*
G01X910435Y41033D02*
X910433D01*
Y37200D01*
X910953Y36680D01*
Y35820D01*
X910433Y35300D01*
Y34101D01*
X910432Y34100D01*
G01X930513Y41033D02*
X930511D01*
X929887Y34500D01*
X929811Y33700D01*
G01X953939Y41033D02*
Y37105D01*
X954454Y36590D01*
Y35710D01*
X953936Y35192D01*
Y34100D01*
G01X923820Y41033D02*
X923818D01*
Y35792D01*
X923580Y34500D01*
X923432Y33700D01*
G01X947246Y41033D02*
X947244D01*
Y37200D01*
X947764Y36680D01*
Y35820D01*
X947244Y35300D01*
Y34101D01*
X947243Y34100D01*
G01X967478Y108478D02*
X972300Y113300D01*
Y122000D01*
X984315Y134015D01*
Y134724D01*
X982639Y136400D01*
Y137295D01*
X983593Y138249D01*
X984538D01*
X985811Y136976D01*
X986520D01*
X987700Y138156D01*
Y182563D01*
G01X916794Y141000D02*
Y169877D01*
X920707Y173790D01*
G01X913779Y112327D02*
X911500Y114606D01*
Y116689D01*
X912190Y117379D01*
Y120069D01*
X911500Y120759D01*
Y135450D01*
X912150Y136100D01*
X913540D01*
X914190Y135450D01*
Y128490D01*
X914780Y127900D01*
X916090D01*
X916794Y128604D01*
Y141000D01*
G01X917125Y107284D02*
X914800Y109609D01*
Y110200D01*
X915600Y111000D01*
Y121601D01*
X920112Y126113D01*
Y136000D01*
G01D02*
Y140900D01*
X920091Y140921D01*
Y141655D01*
X920741Y142305D01*
X922150D01*
X922800Y142955D01*
Y144305D01*
X922150Y144955D01*
X920741D01*
X920091Y145605D01*
Y146955D01*
X920741Y147605D01*
X922150D01*
X922800Y148255D01*
Y149605D01*
X922150Y150255D01*
X920741D01*
X920091Y150905D01*
Y152255D01*
X920741Y152905D01*
X922150D01*
X922800Y153555D01*
Y154905D01*
X922150Y155555D01*
X920741D01*
X920091Y156205D01*
Y157555D01*
X920741Y158205D01*
X920850D01*
X921500Y158855D01*
Y160205D01*
X920850Y160855D01*
X920741D01*
X920091Y161505D01*
Y169566D01*
X922511Y171986D01*
G01X945300Y140000D02*
Y141911D01*
X943911Y143300D01*
X941666D01*
X940600Y144366D01*
Y145900D01*
X941100Y146400D01*
Y147400D01*
X940600Y147900D01*
Y149000D01*
X941100Y149500D01*
Y150500D01*
X940600Y151000D01*
Y152400D01*
X941100Y152900D01*
Y153900D01*
X940600Y154400D01*
Y155400D01*
X941100Y155900D01*
Y156900D01*
X940600Y157400D01*
Y158755D01*
X941100Y159255D01*
Y160255D01*
X940600Y160755D01*
Y161755D01*
X941307Y162462D01*
X942014D01*
X942722Y163169D01*
Y163877D01*
X943429Y164584D01*
X944136D01*
X944844Y165291D01*
Y165999D01*
X948457Y169612D01*
G01X933632Y110514D02*
X934864D01*
X935427Y111077D01*
Y113973D01*
X934400Y115000D01*
X934030D01*
X933229Y115801D01*
Y117251D01*
X933936Y117958D01*
X934643D01*
X935351Y118665D01*
Y119373D01*
X936058Y120080D01*
X936765D01*
X937473Y120787D01*
Y121495D01*
X938180Y122202D01*
X938887D01*
X939595Y122909D01*
Y123617D01*
X940302Y124324D01*
X941009D01*
X941717Y125031D01*
Y125739D01*
X942424Y126446D01*
X943131D01*
X943839Y127153D01*
Y127861D01*
X945300Y129322D01*
Y132667D01*
X943977Y133990D01*
X942050D01*
X941550Y134490D01*
Y136140D01*
X942050Y136640D01*
X943977D01*
X945300Y137963D01*
Y140000D01*
G01X938732Y107655D02*
X936963Y109424D01*
Y116463D01*
X941963Y121463D01*
X942695D01*
X944980Y123748D01*
Y124480D01*
X948000Y127500D01*
Y130500D01*
G01D02*
Y143100D01*
X947400Y143700D01*
Y147086D01*
X945500Y148986D01*
Y160194D01*
X947400Y162094D01*
Y164894D01*
X950184Y167678D01*
G01X942425Y128074D02*
X944150Y129799D01*
Y132190D01*
X943500Y132840D01*
X941573D01*
X940400Y134013D01*
Y136617D01*
X941573Y137790D01*
X943500D01*
X944150Y138440D01*
Y141434D01*
X943434Y142150D01*
X941189D01*
X939450Y143889D01*
Y162232D01*
X947644Y170426D01*
G01X933658Y107865D02*
X931800Y109723D01*
Y113901D01*
X932191Y114292D01*
Y115212D01*
X932079Y115324D01*
Y117728D01*
X942425Y128074D01*
G01X938758Y110264D02*
X940964D01*
X941600Y110900D01*
Y112700D01*
X939500Y114800D01*
Y117373D01*
X942440Y120313D01*
X943172D01*
X946130Y123271D01*
Y124003D01*
X949150Y127023D01*
Y131739D01*
X949549Y132138D01*
Y133138D01*
X949150Y133537D01*
Y134577D01*
X949650Y135077D01*
Y136077D01*
X949150Y136577D01*
Y137577D01*
X949650Y138077D01*
Y139077D01*
X949150Y139577D01*
Y140577D01*
X949650Y141077D01*
Y142077D01*
X949150Y142577D01*
Y143577D01*
X948550Y144177D01*
Y147563D01*
X946650Y149463D01*
Y150717D01*
X947150Y151217D01*
Y152217D01*
X946650Y152717D01*
Y153717D01*
X947150Y154217D01*
Y155217D01*
X946650Y155717D01*
Y156717D01*
X947150Y157217D01*
Y158217D01*
X946650Y158717D01*
Y159717D01*
X948550Y161617D01*
Y164417D01*
X950998Y166865D01*
G01X944226Y174222D02*
X934200Y164196D01*
Y153893D01*
X933550Y153243D01*
X932350D01*
X931700Y152593D01*
Y151243D01*
X932350Y150593D01*
X933550D01*
X934200Y149943D01*
Y148593D01*
X933550Y147943D01*
X932350D01*
X931700Y147293D01*
Y145943D01*
X932350Y145293D01*
X933550D01*
X934200Y144643D01*
Y143293D01*
X933550Y142643D01*
X932350D01*
X931700Y141993D01*
Y140643D01*
X932350Y139993D01*
X933550D01*
X934200Y139343D01*
Y137993D01*
X933550Y137343D01*
X932350D01*
X931700Y136693D01*
Y135343D01*
X932350Y134693D01*
X933550D01*
X934200Y134043D01*
Y132693D01*
X933550Y132043D01*
X932350D01*
X931700Y131393D01*
Y130043D01*
X932350Y129393D01*
X933550D01*
X934200Y128743D01*
Y127549D01*
X926400Y119749D01*
Y113092D01*
X927165Y112327D01*
G01X929811Y106934D02*
Y102951D01*
X929160Y102300D01*
X925600D01*
X924900Y103000D01*
Y105800D01*
X925500Y106400D01*
Y109000D01*
X926800Y110300D01*
X927900D01*
X929100Y111500D01*
Y118551D01*
X938450Y127901D01*
Y129400D01*
X936900Y130950D01*
Y135000D01*
G01D02*
Y138200D01*
X937850Y139150D01*
Y141300D01*
X936900Y142250D01*
Y163289D01*
X945934Y172323D01*
G01X950590Y109700D02*
X953050D01*
X955425Y112075D01*
G01D02*
X960600Y117250D01*
Y129650D01*
X964950Y134000D01*
Y141600D01*
X965600Y142250D01*
X966950D01*
X967600Y141600D01*
Y137750D01*
X968250Y137100D01*
X969600D01*
X970250Y137750D01*
Y145727D01*
X969600Y146377D01*
X965600D01*
X961477Y150500D01*
X959250D01*
X957300Y152450D01*
Y160497D01*
X957576Y160773D01*
G01X953786Y107684D02*
X955434D01*
X962875Y115125D01*
G01D02*
X964100Y116350D01*
Y124050D01*
X972800Y132750D01*
Y148000D01*
X965800Y155000D01*
Y160050D01*
X965300Y160550D01*
X963300D01*
X962800Y160050D01*
Y156700D01*
X961800Y155700D01*
X960700D01*
X959996Y156404D01*
Y160796D01*
G01X920472Y112327D02*
Y121621D01*
X926300Y127449D01*
Y130963D01*
X925524Y131739D01*
X924426D01*
X923650Y132515D01*
Y133613D01*
X924426Y134389D01*
X925524D01*
X926300Y135165D01*
Y136263D01*
X925524Y137039D01*
X924426D01*
X923650Y137815D01*
Y138913D01*
X924426Y139689D01*
X925524D01*
X926300Y140465D01*
Y142500D01*
G01D02*
Y163709D01*
X928519Y165928D01*
Y167026D01*
X927247Y168298D01*
Y169396D01*
X928023Y170172D01*
X929121D01*
X930393Y168900D01*
X931491D01*
X940583Y177992D01*
G01X923518Y107284D02*
X921277D01*
X920627Y107934D01*
Y109627D01*
X923700Y112700D01*
Y120951D01*
X929100Y126351D01*
Y137500D01*
G01D02*
Y162902D01*
X942431Y176233D01*
G01X952866Y165111D02*
X951550Y163795D01*
Y148251D01*
X955301Y144500D01*
X959150D01*
X959650Y144000D01*
Y136350D01*
X959000Y135700D01*
X957650D01*
X957000Y136350D01*
Y140800D01*
X956500Y141300D01*
X954850D01*
X954350Y140800D01*
Y126000D01*
X951175Y122825D01*
G01D02*
X944497Y116147D01*
Y110927D01*
G01X947243Y105084D02*
X944554D01*
X944080Y105558D01*
Y107480D01*
X947200Y110600D01*
Y115050D01*
X949115Y116965D01*
X950865D01*
X951909Y118009D01*
Y119759D01*
X952863Y120713D01*
X953783D01*
X954738Y119758D01*
X955658D01*
X956612Y120712D01*
Y121632D01*
X955657Y122587D01*
Y123507D01*
X957350Y125200D01*
Y130150D01*
X962350Y135150D01*
Y145150D01*
X960200Y147300D01*
X956600D01*
X954200Y149700D01*
Y162854D01*
X954966Y163620D01*
G01X923097Y261760D02*
X920847D01*
G01X923097Y335860D02*
X920847D01*
G01X916337D02*
X913787D01*
G01X923097Y331960D02*
X920847D01*
G01X916337D02*
X913787D01*
G01X923097Y339760D02*
X920847D01*
G01X919717Y337809D02*
X917467D01*
G01X939997Y333909D02*
X937747D01*
G01X933237Y330009D02*
X930987D01*
G01X929857Y339760D02*
X927607D01*
G01X939997Y330009D02*
X937747D01*
G01X936617Y328060D02*
X934367D01*
G01X936617Y339760D02*
X934367D01*
G01X929857Y335860D02*
X927607D01*
G01X929857Y331960D02*
X927607D01*
G01X936617Y335860D02*
X934367D01*
G01X933237Y333909D02*
X930987D01*
G01X939997Y337809D02*
X937747D01*
G01X956897Y339760D02*
X954647D01*
G01X950137Y335860D02*
X947887D01*
G01X956897D02*
X954647D01*
G01X953517Y333909D02*
X951267D01*
G01X946757Y337809D02*
X944507D01*
G01X970416Y328060D02*
X968166D01*
G01X970416Y335860D02*
X968166D01*
G01X950137Y339760D02*
X947887D01*
G01X970416Y324160D02*
X968166D01*
G01X970416Y331960D02*
X968166D01*
G01X967036Y326110D02*
X964786D01*
G01X967036Y333909D02*
X964786D01*
G01X963656Y328060D02*
X961406D01*
G01X963656Y331960D02*
X961406D01*
G01X973796Y326110D02*
X971546D01*
G01X973796Y333909D02*
X971546D01*
G01X939997Y372909D02*
X937747D01*
G01X933237Y369010D02*
X930987D01*
G01X933237Y380709D02*
X930987D01*
G01X929857Y378760D02*
X927607D01*
G01X939997Y369010D02*
X937747D01*
G01X936617Y367060D02*
X934367D01*
G01X936617Y378760D02*
X934367D01*
G01X929857Y374860D02*
X927607D01*
G01X950137D02*
X947887D01*
G01X950137Y382660D02*
X947887D01*
G01X960276Y376809D02*
X958026D01*
G01X960276Y380709D02*
X958026D01*
G01X946757Y376809D02*
X944507D01*
G01X946757Y380709D02*
X944507D01*
G01X916337Y351460D02*
X913787D01*
G01X956897Y374860D02*
X954647D01*
G01X956897Y382660D02*
X954647D01*
G01X923097Y351460D02*
X920847D01*
G01X916337Y347560D02*
X913787D01*
G01X923097D02*
X920847D01*
G01X923097Y343660D02*
X920847D01*
G01X936617Y374860D02*
X934367D01*
G01X953517Y376809D02*
X951267D01*
G01X929857Y370959D02*
X927607D01*
G01X953517Y384609D02*
X951267D01*
G01X919717Y345609D02*
X917467D01*
G01X939997Y376809D02*
X937747D01*
G01X953517Y372909D02*
X951267D01*
G01X933237D02*
X930987D01*
G01X953517Y380709D02*
X951267D01*
G01X973796Y353409D02*
X971546D01*
G01X973796Y357309D02*
X971546D01*
G01X936617Y359260D02*
X934367D01*
G01X933237Y361209D02*
X930987D01*
G01X939997Y349509D02*
X937747D01*
G01X936617Y347560D02*
X934367D01*
G01X929857Y355360D02*
X927607D01*
G01X929857Y359260D02*
X927607D01*
G01X936617Y386560D02*
X934367D01*
G01X936617Y394359D02*
X934367D01*
G01X946757Y388509D02*
X944507D01*
G01X946757Y392410D02*
X944507D01*
G01X933237Y388509D02*
X930987D01*
G01X933237Y392410D02*
X930987D01*
G01X943377Y386560D02*
X941127D01*
G01X943377Y394359D02*
X941127D01*
G01X933237Y341709D02*
X930987D01*
G01X939997Y353409D02*
X937747D01*
G01X933237Y349509D02*
X930987D01*
G01X936617Y355360D02*
X934367D01*
G01X939997Y388509D02*
X937747D01*
G01X929857Y351460D02*
X927607D01*
G01X939997Y396309D02*
X937747D01*
G01X939997Y357309D02*
X937747D01*
G01X939997Y384609D02*
X937747D01*
G01X933237Y353409D02*
X930987D01*
G01X939997Y392410D02*
X937747D01*
G01X948931Y418666D02*
X922424Y445173D01*
Y489776D01*
X921700Y490500D01*
Y494401D01*
X922500Y495201D01*
Y497599D01*
X921455Y498644D01*
X920700D01*
G01X953517Y365109D02*
X951267D01*
G01X950137Y367060D02*
X947887D01*
G01X956897Y355360D02*
X954647D01*
G01X953517Y353409D02*
X951267D01*
G01X946757Y361209D02*
X944507D01*
G01X946757Y365109D02*
X944507D01*
G01X970416Y363160D02*
X968166D01*
G01X963656Y367060D02*
X961406D01*
G01X973796Y372909D02*
X971546D01*
G01X970416Y374860D02*
X968166D01*
G01X967036Y361209D02*
X964786D01*
G01X963656Y363160D02*
X961406D01*
G01X973796Y369010D02*
X971546D01*
G01X967036Y372909D02*
X964786D01*
G01X950137Y347560D02*
X947887D01*
G01X946757Y345609D02*
X944507D01*
G01X953517D02*
X951267D01*
G01X946757Y341709D02*
X944507D01*
G01X956897Y359260D02*
X954647D01*
G01X950137Y355360D02*
X947887D01*
G01X953517Y361209D02*
X951267D01*
G01X970416Y367060D02*
X968166D01*
G01X946757Y357309D02*
X944507D01*
G01X963656Y370959D02*
X961406D01*
G01X953517Y341709D02*
X951267D01*
G01X956897Y363160D02*
X954647D01*
G01X973796Y365109D02*
X971546D01*
G01X950137Y359260D02*
X947887D01*
G01X967036Y369010D02*
X964786D01*
G01X956897Y343660D02*
X954647D01*
G01X934156Y425049D02*
X930702D01*
X913061Y442690D01*
Y447614D01*
X913850Y448403D01*
X915150D01*
X915800Y449053D01*
Y450353D01*
X915150Y451003D01*
X913750D01*
X913100Y451653D01*
Y452953D01*
X913750Y453603D01*
X915550D01*
X916200Y454253D01*
Y455553D01*
X915550Y456203D01*
X913750D01*
X913100Y456853D01*
Y458153D01*
X913750Y458803D01*
X915550D01*
X916200Y459453D01*
Y460753D01*
X915550Y461403D01*
X913750D01*
X912935Y462218D01*
Y486343D01*
X914900Y488308D01*
Y492700D01*
X915300Y493100D01*
Y494800D01*
X917000Y496500D01*
Y498500D01*
X916100Y499400D01*
X914692D01*
X913779Y498487D01*
G01X917192Y493919D02*
X917473Y494200D01*
X918600D01*
X919100Y493700D01*
Y488380D01*
X918600Y487880D01*
X917900D01*
X917100Y487080D01*
Y485691D01*
X917861Y484930D01*
X918500D01*
X919100Y484330D01*
Y483030D01*
X918400Y482330D01*
X916030D01*
X915500Y481800D01*
Y480431D01*
X916150Y479781D01*
X918450D01*
X919100Y479131D01*
Y477781D01*
X918450Y477131D01*
X916150D01*
X915500Y476481D01*
Y475131D01*
X916150Y474481D01*
X918450D01*
X919100Y473831D01*
Y472481D01*
X918450Y471831D01*
X916150D01*
X915500Y471181D01*
Y469831D01*
X916150Y469181D01*
X918450D01*
X919100Y468531D01*
Y467181D01*
X918450Y466531D01*
X916150D01*
X915500Y465881D01*
Y464400D01*
X916000Y463900D01*
X918299D01*
X919100Y463099D01*
Y459000D01*
X918500Y458400D01*
Y456800D01*
X919100Y456200D01*
Y452939D01*
X918400Y452239D01*
Y449699D01*
X919100Y448999D01*
Y446268D01*
X918450Y445618D01*
X916510D01*
X915860Y444968D01*
Y443618D01*
X916510Y442968D01*
X918450D01*
X919100Y442318D01*
Y440350D01*
X931851Y427599D01*
X933456D01*
G01X956577Y427165D02*
X936874Y446868D01*
Y492848D01*
X933778Y495944D01*
X933647D01*
G01X958454Y429663D02*
X956658Y431459D01*
X955893D01*
X955186Y432166D01*
Y432931D01*
X954261Y433856D01*
X953497D01*
X952790Y434563D01*
Y435327D01*
X952083Y436034D01*
X951319D01*
X950612Y436741D01*
Y437505D01*
X949905Y438212D01*
X949141D01*
X948434Y438919D01*
Y439683D01*
X947727Y440390D01*
X946963D01*
X946256Y441097D01*
Y441861D01*
X945549Y442568D01*
X944785D01*
X944078Y443275D01*
Y444039D01*
X943371Y444746D01*
Y445677D01*
X942940Y446108D01*
Y447108D01*
X943371Y447539D01*
Y448615D01*
X942751Y449235D01*
Y450235D01*
X943371Y450855D01*
Y451855D01*
X942751Y452475D01*
Y453475D01*
X943371Y454095D01*
Y455095D01*
X942751Y455715D01*
Y456715D01*
X943371Y457335D01*
Y458335D01*
X942751Y458955D01*
Y459955D01*
X943371Y460575D01*
Y461583D01*
X942716Y462238D01*
X940989D01*
X939608Y463619D01*
Y466062D01*
X940975Y467429D01*
X942800D01*
X943450Y468079D01*
Y469379D01*
X942800Y470029D01*
X940862D01*
X939539Y471352D01*
Y473606D01*
X940724Y474791D01*
Y478361D01*
X940350Y478735D01*
Y479959D01*
X940724Y480333D01*
Y481400D01*
X940224Y481900D01*
Y482900D01*
X940724Y483400D01*
Y484400D01*
X940224Y484900D01*
Y485900D01*
X940724Y486400D01*
Y487400D01*
X940224Y487900D01*
Y488900D01*
X940724Y489400D01*
Y492325D01*
X939705Y493344D01*
X938732D01*
G01X955800Y426314D02*
X935724Y446390D01*
Y478550D01*
X935274Y479000D01*
Y480000D01*
X935724Y480450D01*
Y481500D01*
X935224Y482000D01*
Y483000D01*
X935724Y483500D01*
Y484500D01*
X935224Y485000D01*
Y486000D01*
X935724Y486500D01*
Y487460D01*
X935204Y487980D01*
Y488980D01*
X935724Y489500D01*
Y492370D01*
X934719Y493375D01*
X933678D01*
X933647Y493344D01*
G01X959267Y430477D02*
X944521Y445223D01*
Y462060D01*
X943193Y463388D01*
X941466D01*
X940758Y464096D01*
Y465585D01*
X941452Y466279D01*
X943277D01*
X944600Y467602D01*
Y469856D01*
X943277Y471179D01*
X941339D01*
X940689Y471829D01*
Y473129D01*
X941874Y474314D01*
Y492802D01*
X938732Y495944D01*
G01X951600Y423258D02*
X930484Y444374D01*
Y445822D01*
X929834Y446472D01*
X928700D01*
X928200Y446972D01*
Y448622D01*
X928700Y449122D01*
X929834D01*
X930484Y449772D01*
Y459557D01*
X927700Y462341D01*
Y487300D01*
X927974Y487574D01*
Y493974D01*
X929000Y495000D01*
Y496809D01*
X927165Y498644D01*
G01X954196Y424312D02*
X933100Y445408D01*
Y461445D01*
X932450Y462095D01*
X931700D01*
X931200Y462595D01*
Y464245D01*
X931700Y464745D01*
X932600D01*
X933175Y465320D01*
Y466670D01*
X932450Y467395D01*
X931084D01*
X930434Y468045D01*
Y469395D01*
X931084Y470045D01*
X932576D01*
X933201Y470670D01*
Y472020D01*
X932526Y472695D01*
X931084D01*
X930434Y473345D01*
Y474695D01*
X931084Y475345D01*
X932450D01*
X933100Y475995D01*
Y477716D01*
X932174Y478642D01*
X931110D01*
X930460Y479292D01*
Y480642D01*
X931110Y481292D01*
X931978D01*
X932628Y481942D01*
Y483292D01*
X931978Y483942D01*
X931110D01*
X930460Y484592D01*
Y485942D01*
X931110Y486592D01*
X931978D01*
X932628Y487242D01*
Y488804D01*
X931774Y489658D01*
Y491281D01*
X929811Y493244D01*
G01X963690Y436813D02*
X957767Y442736D01*
Y464200D01*
X957267Y464700D01*
X955617D01*
X955117Y464200D01*
Y461517D01*
X954467Y460867D01*
X953117D01*
X952500Y461484D01*
Y491500D01*
X950700Y493300D01*
G01X965229Y438843D02*
X960337Y443735D01*
Y479500D01*
X959837Y480000D01*
X958187D01*
X957687Y479500D01*
Y469888D01*
X957037Y469238D01*
X955687D01*
X955037Y469888D01*
Y492463D01*
X954000Y493500D01*
Y494700D01*
G01X950355Y420939D02*
X925174Y446120D01*
Y450658D01*
X925849Y451333D01*
X927187D01*
X927837Y451983D01*
Y453333D01*
X927187Y453983D01*
X926200D01*
X925700Y454483D01*
Y456133D01*
X926200Y456633D01*
X927187D01*
X927837Y457283D01*
Y458633D01*
X927187Y459283D01*
X925849D01*
X925174Y459958D01*
Y488374D01*
X925400Y488600D01*
Y492644D01*
X924300Y493744D01*
X923600D01*
G01X960779Y432548D02*
X947300Y446027D01*
Y476403D01*
X946650Y477053D01*
X945128D01*
X944478Y477703D01*
Y479053D01*
X945128Y479703D01*
X946650D01*
X947300Y480353D01*
Y481703D01*
X946650Y482353D01*
X945128D01*
X944478Y483003D01*
Y484353D01*
X945128Y485003D01*
X946650D01*
X947300Y485653D01*
Y487000D01*
X946142Y488158D01*
Y490958D01*
X944000Y493100D01*
G01X962091Y434807D02*
X955148Y441750D01*
Y455300D01*
X954648Y455800D01*
X952998D01*
X952498Y455300D01*
Y447016D01*
X951898Y446416D01*
X950548D01*
X949848Y447116D01*
Y488152D01*
X948674Y489326D01*
Y493713D01*
X947443Y494944D01*
G01X970671Y523900D02*
X970669Y523923D01*
Y529014D01*
G01X999182Y406130D02*
Y451922D01*
X981438Y469666D01*
Y503162D01*
X976350Y508250D01*
Y510344D01*
X970669Y516025D01*
Y518157D01*
G01X979338Y490843D02*
Y502062D01*
X976500Y504900D01*
X974800D01*
X969900Y509800D01*
Y510300D01*
X968150Y512050D01*
X967750D01*
X965200Y514600D01*
Y516542D01*
X965900Y517242D01*
Y518699D01*
X963976Y520623D01*
Y523900D01*
X963978D01*
G01X992699Y402909D02*
Y449049D01*
X974392Y467356D01*
Y494890D01*
X962600Y506682D01*
Y510900D01*
X961700Y511800D01*
Y513200D01*
X962800Y514300D01*
Y516881D01*
X963976Y518057D01*
G01X990604Y402882D02*
Y447473D01*
X972294Y465783D01*
Y493948D01*
X960629Y505613D01*
Y510114D01*
G01X913781Y523900D02*
X913779Y523923D01*
Y528899D01*
G01X937206Y523900D02*
X937204Y523923D01*
Y526496D01*
X935558Y528142D01*
Y529800D01*
X936290Y530532D01*
Y531503D01*
X935298Y532495D01*
X934478D01*
X933733Y531750D01*
X933658D01*
G01X933860Y523900D02*
X933858Y523923D01*
Y526351D01*
X932141Y528068D01*
X931892Y528610D01*
X931808Y528792D01*
Y532013D01*
X932129Y532896D01*
X933632Y534399D01*
G01X927167Y523900D02*
X927165Y523923D01*
Y528899D01*
G01X950592Y523900D02*
X950590Y523923D01*
Y528899D01*
G01X920474Y523900D02*
X920472Y523923D01*
Y528899D01*
G01X943899Y523900D02*
X943897Y523923D01*
Y528899D01*
G01X960631Y542010D02*
X960629D01*
Y536957D01*
G01X917128Y542010D02*
X917125D01*
Y538108D01*
X917643Y537590D01*
Y536710D01*
X917125Y536192D01*
Y535100D01*
G01X910435Y542010D02*
X910433D01*
Y538200D01*
X910953Y537680D01*
Y536820D01*
X910433Y536300D01*
Y535101D01*
X910432Y535100D01*
G01X937206Y542010D02*
X937204D01*
Y537805D01*
X935700Y536301D01*
Y534601D01*
X937001Y533300D01*
X937883D01*
X938732Y534149D01*
G01Y531540D02*
X939740D01*
X940700Y532500D01*
Y537900D01*
X940551Y538049D01*
Y542010D01*
X940553D01*
G01X930513D02*
X930511Y542033D01*
X929811Y534700D01*
G01X953936Y535100D02*
Y536192D01*
X954454Y536710D01*
Y537590D01*
X953936Y538108D01*
Y542010D01*
X953939D01*
G01X923820D02*
X923818D01*
Y536792D01*
X923432Y534700D01*
G01X947246Y542010D02*
X947244D01*
Y538200D01*
X947764Y537680D01*
Y536820D01*
X947244Y536300D01*
Y535101D01*
X947243Y535100D01*
G01X970671Y561700D02*
X970669Y561723D01*
Y566814D01*
G01X963978Y561700D02*
X963976Y561723D01*
Y566814D01*
G01X960631Y579810D02*
X960629D01*
Y574757D01*
G01X917128Y579810D02*
X917125D01*
Y575908D01*
X917643Y575390D01*
Y574510D01*
X917125Y573992D01*
Y572900D01*
G01X913781Y561700D02*
X913779Y561723D01*
Y566699D01*
G01X910432Y572900D02*
X910433Y572901D01*
Y574100D01*
X910953Y574620D01*
Y575480D01*
X910433Y576000D01*
Y579810D01*
X910435D01*
G01X937206Y561700D02*
X937204Y561723D01*
Y564296D01*
X935558Y565942D01*
Y567600D01*
X936290Y568332D01*
Y569303D01*
X935298Y570295D01*
X934478D01*
X933733Y569550D01*
X933658D01*
G01X937206Y579810D02*
X937204D01*
Y575605D01*
X935700Y574101D01*
Y572401D01*
X937001Y571100D01*
X937883D01*
X938732Y571949D01*
G01X933860Y561700D02*
X933858Y561723D01*
Y564151D01*
X932141Y565868D01*
X931808Y566592D01*
Y569813D01*
X932129Y570696D01*
X933632Y572199D01*
G01X940553Y579810D02*
X940551D01*
Y575849D01*
X940700Y575700D01*
Y570300D01*
X939740Y569340D01*
X938732D01*
G01X930513Y579810D02*
X930511Y579833D01*
X929811Y572500D01*
G01X927167Y561700D02*
X927165Y561723D01*
Y566699D01*
G01X953939Y579810D02*
X953936D01*
Y575908D01*
X954454Y575390D01*
Y574510D01*
X953936Y573992D01*
Y572900D01*
G01X950592Y561700D02*
X950590Y561723D01*
Y566699D01*
G01X923820Y579810D02*
X923818D01*
Y574592D01*
X923432Y572500D01*
G01X920474Y561700D02*
X920472Y561723D01*
Y566699D01*
G01X947246Y579810D02*
X947244D01*
Y576000D01*
X947764Y575480D01*
Y574620D01*
X947244Y574100D01*
Y572901D01*
X947243Y572900D01*
G01X943899Y561700D02*
X943897Y561723D01*
Y566699D01*
G01X970671Y599500D02*
X970669Y599523D01*
Y607292D01*
G01X963978Y599500D02*
X963976Y599523D01*
Y607292D01*
G01X960629Y609864D02*
Y617610D01*
X960631D01*
G01X917125Y610700D02*
Y611792D01*
X917643Y612310D01*
Y613190D01*
X917125Y613708D01*
Y617610D01*
X917128D01*
G01X913781Y599500D02*
X913779Y599523D01*
Y604499D01*
G01X910435Y617610D02*
X910433D01*
Y613800D01*
X910953Y613280D01*
Y612420D01*
X910433Y611900D01*
Y610701D01*
X910432Y610700D01*
G01X937206Y599500D02*
X937204Y599523D01*
Y602096D01*
X935558Y603742D01*
Y605400D01*
X936290Y606132D01*
Y607103D01*
X935298Y608095D01*
X934478D01*
X933733Y607350D01*
X933658D01*
G01X937206Y617610D02*
X937204D01*
Y613405D01*
X935700Y611901D01*
Y610201D01*
X937001Y608900D01*
X937883D01*
X938732Y609749D01*
G01X933860Y599500D02*
X933858Y599523D01*
Y601951D01*
X932141Y603668D01*
X931808Y604392D01*
Y607613D01*
X932129Y608496D01*
X933632Y609999D01*
G01X938732Y607140D02*
X939740D01*
X940700Y608100D01*
Y613500D01*
X940551Y613649D01*
Y617610D01*
X940553D01*
G01X930513D02*
X930511Y617633D01*
X929811Y610300D01*
G01X927167Y599500D02*
X927165Y599523D01*
Y604499D01*
G01X953939Y617610D02*
X953936D01*
Y613708D01*
X954454Y613190D01*
Y612310D01*
X953936Y611792D01*
Y610700D01*
G01X950592Y599500D02*
X950590Y599523D01*
Y604499D01*
G01X923820Y617610D02*
X923818D01*
Y612392D01*
X923432Y610300D01*
G01X920474Y599500D02*
X920472Y599523D01*
Y604499D01*
G01X947246Y617610D02*
X947244D01*
Y613400D01*
X947764Y612880D01*
Y612020D01*
X947244Y611500D01*
Y610701D01*
X947243Y610700D01*
G01X943899Y599500D02*
X943897Y599523D01*
Y604499D01*
G01X974017Y22923D02*
X974015D01*
Y28014D01*
G01X1014175Y22923D02*
X1014173D01*
Y28014D01*
G01X1010828Y22923D02*
X1010826D01*
Y28014D01*
G01X980710Y22923D02*
X980708D01*
Y28014D01*
G01X1004135Y22923D02*
X1004133D01*
Y28022D01*
G01X1000789Y22923D02*
X1000787D01*
Y28022D01*
G01X994096Y22923D02*
X994094D01*
Y28022D01*
G01X990750Y22923D02*
X990748D01*
Y28022D01*
G01X984057Y22923D02*
X984055D01*
Y28013D01*
X984054Y28014D01*
G01X977364Y3233D02*
X977362D01*
Y-1743D01*
G01X974017Y-14877D02*
X974015D01*
Y-9901D01*
G01X974017Y3233D02*
X974015D01*
Y-4536D01*
G01X1014175Y-14877D02*
X1014173D01*
Y-9786D01*
G01X1014175Y3233D02*
X1014173D01*
Y-1858D01*
G01X1010828Y-14877D02*
X1010826D01*
Y-9786D01*
G01X1010828Y3233D02*
X1010826D01*
Y-1858D01*
G01X984057Y3233D02*
X984055D01*
Y-1743D01*
G01X980710Y-14877D02*
X980708D01*
Y-9786D01*
G01X1004134Y-7108D02*
Y-14876D01*
X1004135Y-14877D01*
G01Y3233D02*
X1004133D01*
Y-1742D01*
G01X1000789Y-14877D02*
X1000787D01*
Y-9901D01*
G01X997443Y3233D02*
X997441D01*
Y-1743D01*
G01X994096Y3233D02*
X994094D01*
Y-4536D01*
G01X994096Y-14877D02*
X994094D01*
Y-9786D01*
G01X987403Y3233D02*
X987401D01*
Y-4536D01*
G01X990750Y-14877D02*
X990748D01*
Y-7108D01*
G01X984057Y-14877D02*
X984055D01*
Y-7108D01*
G01X977362Y87392D02*
Y89804D01*
X985400Y97842D01*
Y104069D01*
G01X977364Y78833D02*
X977362D01*
Y73757D01*
G01X983300Y110390D02*
Y103904D01*
X981854Y102458D01*
Y101538D01*
X982878Y100514D01*
Y99806D01*
X981747Y98675D01*
X981039D01*
X980015Y99699D01*
X979095D01*
X978176Y98780D01*
Y97860D01*
X979051Y96985D01*
Y96277D01*
X977920Y95146D01*
X977212D01*
X976366Y95992D01*
X975025D01*
X974015Y94982D01*
Y89964D01*
G01X974017Y60723D02*
X974015D01*
Y65814D01*
G01X974017Y78833D02*
X974015D01*
Y73757D01*
G01X1028030Y115156D02*
Y100627D01*
X1026948Y99545D01*
Y90293D01*
X1028202Y87266D01*
X1028420Y86739D01*
Y76350D01*
X1026928Y72745D01*
X1025560Y71377D01*
X1019817Y69000D01*
X1015934D01*
X1013952Y68178D01*
X1013074Y67301D01*
Y66226D01*
X1014173Y65127D01*
Y60723D01*
X1014175D01*
G01X1015215Y92500D02*
X1013944Y93771D01*
Y109095D01*
X1019801Y114952D01*
G01X1014175Y78833D02*
X1014173D01*
Y81160D01*
X1013074Y82259D01*
Y83350D01*
X1013724Y84000D01*
X1020500D01*
X1022175Y85675D01*
Y88376D01*
X1023983Y90184D01*
Y94303D01*
X1022719Y95567D01*
X1017793D01*
X1017143Y96217D01*
Y99525D01*
X1017793Y100175D01*
X1019423D01*
X1019848Y99750D01*
X1022685D01*
X1024895Y101960D01*
Y103892D01*
X1023572Y105215D01*
X1017729D01*
X1017079Y105865D01*
Y107215D01*
X1017729Y107865D01*
X1023572D01*
X1024895Y109188D01*
Y111035D01*
G01X1014842Y87500D02*
X1014021Y88321D01*
Y89329D01*
X1012763Y90587D01*
X1011125D01*
X1010625Y91087D01*
Y94955D01*
X1010225Y95355D01*
Y103689D01*
G01X1010828Y60723D02*
X1010826D01*
Y65227D01*
X1011924Y66325D01*
Y67778D01*
X1013300Y69154D01*
X1015705Y70150D01*
X1019588D01*
X1024908Y72353D01*
X1025952Y73397D01*
X1027270Y76579D01*
Y78869D01*
X1026790Y79349D01*
Y81299D01*
X1027270Y81779D01*
Y86510D01*
X1026957Y87266D01*
X1025798Y90064D01*
Y95341D01*
X1025354Y95785D01*
Y97735D01*
X1025798Y98179D01*
Y100022D01*
X1026880Y101104D01*
Y103936D01*
G01X1012400Y92500D02*
X1012794Y92894D01*
Y96460D01*
X1012304Y96950D01*
Y98348D01*
X1012794Y98838D01*
Y100263D01*
X1012303Y100754D01*
Y102240D01*
X1012794Y102731D01*
Y108014D01*
G01X1010828Y78833D02*
X1010826D01*
Y81411D01*
X1011924Y82509D01*
Y83827D01*
X1013247Y85150D01*
X1020023D01*
X1021025Y86152D01*
Y88853D01*
X1022833Y90661D01*
Y93826D01*
X1022242Y94417D01*
X1017316D01*
X1015993Y95740D01*
Y100002D01*
X1017316Y101325D01*
X1019900D01*
X1020325Y100900D01*
X1022208D01*
X1023745Y102437D01*
Y103415D01*
X1023095Y104065D01*
X1019589D01*
G01X1012043Y87500D02*
X1012871Y88328D01*
Y88852D01*
X1012286Y89437D01*
X1010648D01*
X1009475Y90610D01*
Y94478D01*
X1009075Y94878D01*
Y111477D01*
X1011411Y113813D01*
G01X984057Y78833D02*
X984055D01*
Y73757D01*
G01X980710Y60723D02*
X980708D01*
Y65814D01*
G01X1003322Y103936D02*
Y96478D01*
X1004023Y94785D01*
Y92757D01*
G01X1004135Y60723D02*
X1004133D01*
Y65822D01*
G01X1004135Y78833D02*
X1004133D01*
Y73858D01*
X1004134Y73857D01*
Y73757D01*
G01X1015490Y188215D02*
Y120839D01*
X1005307Y110656D01*
Y109379D01*
X1005957Y108729D01*
X1006590D01*
X1007090Y108229D01*
Y106579D01*
X1006590Y106079D01*
X1005957D01*
X1005307Y105429D01*
Y104079D01*
X1005957Y103429D01*
X1006365D01*
X1007015Y102779D01*
Y101429D01*
X1006365Y100779D01*
X1005957D01*
X1005307Y100129D01*
Y98658D01*
X1006951Y97014D01*
Y95086D01*
X1005798Y93933D01*
Y91265D01*
X1005100Y90567D01*
Y89600D01*
X1005738Y88962D01*
Y88042D01*
X1005088Y87392D01*
X1004023D01*
G01X1000789Y60723D02*
X1000787D01*
Y65822D01*
G01Y89964D02*
X1001691D01*
X1002248Y90521D01*
Y93890D01*
X1001285Y94853D01*
Y112251D01*
X1004250Y115216D01*
G01X999300Y108743D02*
Y91600D01*
X998374Y90674D01*
Y88325D01*
X997441Y87392D01*
G01X997443Y78833D02*
X997441D01*
Y73757D01*
G01X994094Y84714D02*
Y86894D01*
X995919Y88719D01*
Y91749D01*
X995616Y92052D01*
Y93514D01*
X997200Y95098D01*
Y103793D01*
G01X994096Y78833D02*
X994094D01*
Y73757D01*
G01X995100Y112669D02*
Y95827D01*
X992900Y93627D01*
Y92382D01*
X991573Y91055D01*
Y89956D01*
X992369Y89160D01*
X993290D01*
X994094Y89964D01*
G01X994096Y60723D02*
X994094D01*
Y65822D01*
G01X987401Y84599D02*
Y87299D01*
X985400Y89300D01*
Y91000D01*
X987500Y93100D01*
Y113956D01*
G01X987403Y78833D02*
X987401D01*
Y73757D01*
G01X990750Y60723D02*
X990748D01*
Y65822D01*
G01X1003580Y138417D02*
Y129662D01*
X989838Y115920D01*
Y114164D01*
X990444Y113558D01*
X991461D01*
X992126Y112893D01*
Y111543D01*
X991491Y110908D01*
X990135D01*
X989485Y110258D01*
Y108822D01*
X989985Y108322D01*
X992275D01*
X992983Y107614D01*
Y106354D01*
X992333Y105704D01*
X990534D01*
X989809Y104979D01*
Y103679D01*
X990384Y103104D01*
X992394D01*
X993044Y102454D01*
Y101154D01*
X992394Y100504D01*
X990208D01*
X989511Y99807D01*
Y98429D01*
X990011Y97929D01*
X992046D01*
X992784Y97191D01*
Y96050D01*
X991952Y95218D01*
X991398D01*
X990748Y94568D01*
Y92757D01*
G01X984057Y60723D02*
X984055D01*
Y65813D01*
X984054Y65814D01*
G01X977364Y41033D02*
X977362D01*
Y35957D01*
G01X974017Y41033D02*
X974015D01*
Y35957D01*
G01X1014175Y41033D02*
X1014173D01*
Y35942D01*
G01X1010828Y41033D02*
X1010826D01*
Y35942D01*
G01X984057Y41033D02*
X984055D01*
Y35957D01*
G01X1004135Y41033D02*
X1004133D01*
Y36058D01*
X1004134Y36057D01*
Y35957D01*
G01X997443Y41033D02*
X997441D01*
Y35957D01*
G01X994096Y41033D02*
X994094D01*
Y35957D01*
G01X987403Y41033D02*
X987401D01*
Y35957D01*
G01X995640Y186625D02*
Y133419D01*
X981200Y118979D01*
Y115148D01*
G01X985400Y104069D02*
Y117253D01*
X999610Y131463D01*
Y186360D01*
G01X997625Y186310D02*
Y132441D01*
X983300Y118116D01*
Y110390D01*
G01X979181Y107022D02*
Y105502D01*
X976700Y103021D01*
G01X993655Y186736D02*
Y134397D01*
X979181Y119923D01*
Y107022D01*
G01X972825Y107325D02*
X976400Y110900D01*
Y120101D01*
X991670Y135371D01*
Y182619D01*
G01X974300Y115182D02*
Y121000D01*
X989685Y136385D01*
Y182436D01*
G01X1028030Y115156D02*
Y181266D01*
G01X1019801Y114952D02*
X1021760Y116911D01*
Y182706D01*
G01X1024895Y183105D02*
Y111035D01*
G01X1010225Y103689D02*
Y111000D01*
X1018625Y119400D01*
Y184533D01*
G01X1026880Y103936D02*
Y105839D01*
X1026472Y106247D01*
Y107609D01*
X1026880Y108017D01*
Y181268D01*
G01X1012794Y108014D02*
Y109572D01*
X1017255Y114033D01*
Y114726D01*
X1018431Y115902D01*
X1019124D01*
X1020610Y117388D01*
Y182686D01*
G01X1019589Y104065D02*
X1017252D01*
X1015929Y105388D01*
Y107692D01*
X1017252Y109015D01*
X1023095D01*
X1023745Y109665D01*
Y183105D01*
G01X1011411Y113813D02*
X1017475Y119877D01*
Y184533D01*
G01X1032000Y110422D02*
Y180801D01*
G01X1047637Y89964D02*
X1045797Y94404D01*
X1032000Y108201D01*
Y110422D01*
G01X1013505Y188142D02*
Y121662D01*
X1003322Y111479D01*
Y103936D01*
G01X1004250Y115216D02*
X1011520Y122486D01*
Y188639D01*
G01X1009535Y189913D02*
Y123310D01*
X999300Y113075D01*
Y108743D01*
G01X997200Y103793D02*
Y113784D01*
X1007550Y124134D01*
Y189634D01*
G01X1005565Y185958D02*
Y128568D01*
X1004365Y127368D01*
Y126449D01*
X1005252Y125562D01*
Y124644D01*
X1004331Y123723D01*
X1003414D01*
X1002392Y124745D01*
X1001472D01*
X1000634Y123907D01*
Y122825D01*
X1001574Y121885D01*
Y120966D01*
X1000653Y120045D01*
X999736D01*
X998848Y120933D01*
X997930D01*
X997009Y120012D01*
Y119093D01*
X997896Y118206D01*
Y117288D01*
X995100Y114492D01*
Y112669D01*
G01X987500Y113956D02*
Y116390D01*
X1001595Y130485D01*
Y186312D01*
G01X1003580Y186457D02*
Y138417D01*
G01X1033546Y103754D02*
X1030015Y107285D01*
Y181141D01*
G01X1044290Y87392D02*
Y93010D01*
X1033546Y103754D01*
G01X1033985Y115181D02*
Y180486D01*
G01X1037955Y179613D02*
Y119788D01*
X1042157Y113499D01*
X1045292Y108807D01*
X1048016Y106083D01*
G01X990696Y211060D02*
Y210239D01*
X991826Y209109D01*
G01X1038756Y112345D02*
X1035970Y115131D01*
Y180000D01*
G01X1025625Y213009D02*
X1027875D01*
G01X994076Y224709D02*
X991826D01*
G01X997456Y230559D02*
X995206D01*
G01X1031255Y234460D02*
X1029005D01*
G01X1027875Y228610D02*
X1025625D01*
G01X983936Y335860D02*
X981686D01*
G01X994076Y337809D02*
X991826D01*
G01X990696Y335860D02*
X988446D01*
G01X987316Y337809D02*
X985066D01*
G01X987316Y333909D02*
X985066D01*
G01X977176Y328060D02*
X974926D01*
G01X977176Y331960D02*
X974926D01*
G01X994076Y396309D02*
X991508D01*
X991500Y396301D01*
G01X1054330Y515364D02*
X1050354D01*
X1049100Y514110D01*
Y512000D01*
X1049600Y511500D01*
Y509256D01*
X1048218Y507874D01*
X1045442D01*
X1042758Y505190D01*
Y501046D01*
X1037575Y495863D01*
Y411056D01*
G01X1022245Y390460D02*
X1024495D01*
G01X1001277Y407377D02*
Y452727D01*
X983538Y470466D01*
Y472157D01*
X984188Y472807D01*
X985186D01*
X985820Y473441D01*
Y474791D01*
X985154Y475457D01*
X984188D01*
X983538Y476107D01*
Y490705D01*
X984188Y491355D01*
X985355D01*
X986021Y492021D01*
Y493371D01*
X985387Y494005D01*
X984188D01*
X983538Y494655D01*
Y503734D01*
X984447Y504643D01*
Y506814D01*
X982999Y508262D01*
X979838D01*
X978700Y509400D01*
Y511100D01*
X979254Y511654D01*
Y513470D01*
X977360Y515364D01*
X974015D01*
G01X997456Y386560D02*
X995206D01*
G01X997087Y405432D02*
Y451016D01*
X979338Y468765D01*
Y490843D01*
G01X994992Y403714D02*
Y450211D01*
X976530Y468673D01*
Y497170D01*
G01X1022389Y490150D02*
Y487879D01*
X1020659Y486149D01*
X1017384D01*
X1016734Y485499D01*
Y484149D01*
X1017384Y483499D01*
X1024128D01*
X1025451Y482176D01*
Y479872D01*
X1024128Y478549D01*
X1017384D01*
X1016734Y477899D01*
Y476549D01*
X1017384Y475899D01*
X1021477D01*
X1022800Y474576D01*
Y470467D01*
X1024232Y469035D01*
X1024688D01*
X1026068Y467655D01*
Y467199D01*
X1027907Y465360D01*
Y410053D01*
G01X1013873Y515152D02*
X1012957Y516068D01*
Y516792D01*
X1011511Y518238D01*
X1007087D01*
X1005680Y516831D01*
Y514014D01*
X1005959Y513735D01*
Y511925D01*
X1005575Y511541D01*
Y507693D01*
X1007050Y506218D01*
Y473830D01*
X1020031Y460849D01*
Y410490D01*
G01X1031108Y410133D02*
Y467698D01*
X1028769Y470037D01*
Y484578D01*
X1026800Y486547D01*
Y497824D01*
G01X1023618Y410158D02*
Y435094D01*
X1023218Y435494D01*
Y437444D01*
X1023618Y437844D01*
Y439794D01*
X1023218Y440194D01*
Y442144D01*
X1023618Y442544D01*
Y444494D01*
X1023218Y444894D01*
Y446844D01*
X1023618Y447244D01*
Y449194D01*
X1023218Y449594D01*
Y451544D01*
X1023618Y451944D01*
Y453894D01*
X1023218Y454294D01*
Y456244D01*
X1023618Y456644D01*
Y458594D01*
X1023218Y458994D01*
Y460944D01*
X1023618Y461344D01*
Y463294D01*
X1021416Y465496D01*
X1020965D01*
X1019585Y466876D01*
Y467327D01*
X1018313Y468599D01*
X1017716D01*
X1016337Y469978D01*
Y470575D01*
X1014878Y472034D01*
X1014209D01*
X1012830Y473413D01*
Y474082D01*
X1011425Y475487D01*
Y479255D01*
X1010927Y479753D01*
Y481703D01*
X1011425Y482201D01*
Y484151D01*
X1010927Y484649D01*
Y486599D01*
X1011425Y487097D01*
Y489047D01*
X1012748Y490370D01*
X1015896D01*
X1016546Y491020D01*
Y492370D01*
X1015896Y493020D01*
X1012748D01*
X1011425Y494343D01*
Y496647D01*
X1012748Y497970D01*
X1015896D01*
X1016546Y498620D01*
Y499970D01*
X1015896Y500620D01*
X1012748D01*
X1011425Y501943D01*
Y505246D01*
X1013184Y507005D01*
X1016750D01*
X1018338Y508593D01*
Y510826D01*
X1017014Y512150D01*
X1013618D01*
X1013095Y511627D01*
Y510892D01*
X1013873Y510114D01*
G01X1026757Y461106D02*
Y410073D01*
G01X1021181Y410262D02*
Y417083D01*
X1021631Y417533D01*
Y419483D01*
X1021181Y419933D01*
Y421883D01*
X1021631Y422333D01*
Y424283D01*
X1021181Y424733D01*
Y426683D01*
X1021631Y427133D01*
Y429083D01*
X1021181Y429533D01*
Y431483D01*
X1021631Y431933D01*
Y433883D01*
X1021181Y434333D01*
Y461326D01*
X1018496Y464011D01*
Y464554D01*
X1017116Y465934D01*
X1016573D01*
X1015053Y467454D01*
Y468043D01*
X1013673Y469423D01*
X1013084D01*
X1011662Y470845D01*
Y471549D01*
X1010283Y472929D01*
X1009578D01*
X1008200Y474307D01*
Y475483D01*
X1008508Y475791D01*
Y477091D01*
X1008200Y477399D01*
Y478842D01*
X1008698Y479340D01*
Y481290D01*
X1008200Y481788D01*
Y483738D01*
X1008698Y484236D01*
Y486186D01*
X1008200Y486684D01*
Y488634D01*
X1008698Y489132D01*
Y491082D01*
X1008200Y491580D01*
Y493530D01*
X1008698Y494028D01*
Y495978D01*
X1008200Y496476D01*
Y498426D01*
X1008698Y498924D01*
Y500874D01*
X1008200Y501372D01*
Y502951D01*
X1008764Y503515D01*
Y505421D01*
X1008200Y505985D01*
Y506695D01*
X1006725Y508170D01*
Y511064D01*
X1007109Y511448D01*
Y514212D01*
X1006830Y514491D01*
Y516354D01*
X1007564Y517088D01*
X1011034D01*
X1011807Y516315D01*
Y515757D01*
X1011250Y515200D01*
G01X1029958Y451876D02*
Y410133D01*
G01X1024768Y410161D02*
Y463771D01*
X1012575Y475964D01*
Y488570D01*
X1013225Y489220D01*
X1016373D01*
X1017696Y490543D01*
Y492847D01*
X1016373Y494170D01*
X1013225D01*
X1012575Y494820D01*
Y496170D01*
X1013225Y496820D01*
X1016373D01*
X1017696Y498143D01*
Y500447D01*
X1016373Y501770D01*
X1013225D01*
X1012575Y502420D01*
Y504769D01*
X1013661Y505855D01*
X1017227D01*
X1019488Y508116D01*
Y511303D01*
X1017491Y513300D01*
X1013141D01*
X1011945Y512104D01*
Y510933D01*
X1011126Y510114D01*
G01X980556Y353409D02*
X978306D01*
G01X980556Y361209D02*
X978306D01*
G01X980556Y349509D02*
X978306D01*
G01X980556Y357309D02*
X978306D01*
G01X977176Y351460D02*
X974926D01*
G01X977176Y359260D02*
X974926D01*
G01X987316Y353409D02*
X985066D01*
G01X987316Y357309D02*
X985066D01*
G01X983936Y351460D02*
X981686D01*
G01X983936Y359260D02*
X981686D01*
G01X1047637Y515364D02*
X1046500Y514227D01*
Y511404D01*
X1040358Y505262D01*
Y501697D01*
X1035475Y496814D01*
Y410585D01*
G01X1022245Y386560D02*
X1024495D01*
G01X1000836Y392410D02*
X998586Y388509D01*
G01X994076Y380709D02*
X991826D01*
G01X1064369Y512792D02*
X1060592D01*
X1049624Y501824D01*
X1048640D01*
X1046737Y499921D01*
Y499001D01*
X1047565Y498173D01*
Y496837D01*
X1045368Y494640D01*
X1043992D01*
X1042028Y492676D01*
Y491191D01*
X1043155Y490064D01*
Y488800D01*
X1041775Y487420D01*
Y411853D01*
G01X1057676Y518157D02*
Y516076D01*
X1052500Y510900D01*
Y508334D01*
X1044204Y500038D01*
Y499386D01*
X1039675Y494857D01*
Y410927D01*
G01X1015942Y410519D02*
Y458934D01*
X1001273Y473603D01*
Y499745D01*
X1002700Y501172D01*
Y503465D01*
X1001303Y504862D01*
Y507365D01*
X1002265Y508327D01*
Y511535D01*
X1001830Y511970D01*
Y513654D01*
X1002782Y514606D01*
Y516805D01*
X1004134Y518157D01*
G01X1018037Y410774D02*
Y459994D01*
X1004981Y473050D01*
Y482639D01*
X1003347Y484273D01*
Y487913D01*
X1004602Y489168D01*
Y493288D01*
X1003347Y494543D01*
Y498701D01*
X1004416Y499770D01*
Y506265D01*
X1003915Y506766D01*
Y512792D01*
G01X1000787Y515364D02*
X999654Y514231D01*
Y512294D01*
X998635Y511275D01*
Y508934D01*
X998872Y508697D01*
Y473069D01*
X1013847Y458094D01*
Y410143D01*
G01X1011752Y410009D02*
Y457319D01*
X996887Y472184D01*
Y512238D01*
X997441Y512792D01*
G01X1009657Y409566D02*
Y456451D01*
X994734Y471374D01*
Y509474D01*
X994094Y510114D01*
G01X1007562Y408976D02*
Y455549D01*
X992664Y470447D01*
Y496811D01*
X991834Y497641D01*
Y499574D01*
X992664Y500404D01*
Y502111D01*
X991721Y503054D01*
Y504761D01*
X992664Y505704D01*
Y507834D01*
X991964Y508534D01*
Y510864D01*
X994555Y513455D01*
Y514903D01*
X994094Y515364D01*
G01X1003372Y408372D02*
Y453532D01*
X988049Y468855D01*
Y474232D01*
X988621Y474804D01*
Y476154D01*
X987971Y476804D01*
X987246D01*
X986596Y477454D01*
Y478804D01*
X987246Y479454D01*
X987971D01*
X988621Y480104D01*
Y481529D01*
X987971Y482179D01*
X986775D01*
X986124Y482830D01*
Y484179D01*
X986774Y484829D01*
X987971D01*
X988621Y485479D01*
Y486829D01*
X987971Y487479D01*
X987021D01*
X986371Y488129D01*
Y489479D01*
X987021Y490129D01*
X987585D01*
X988591Y491135D01*
Y494140D01*
X987401Y495330D01*
Y509999D01*
G01X1005467Y408774D02*
Y454367D01*
X990629Y469205D01*
Y495571D01*
X989800Y496400D01*
Y510500D01*
X988900Y511400D01*
Y513679D01*
X990748Y515527D01*
Y518157D01*
G01X1000836Y400209D02*
Y402764D01*
X1000800Y402800D01*
G01X1033375Y410585D02*
Y497821D01*
X1038618Y503064D01*
Y505890D01*
X1044290Y511562D01*
Y512792D01*
G01X997456Y378760D02*
X995206D01*
G01X1000836Y380709D02*
X998586D01*
G01X1025625Y384609D02*
X1027875D01*
G01X997456Y355360D02*
X995206D01*
G01X1000836Y357309D02*
X998586D01*
G01X983936Y343660D02*
X981686D01*
G01X994076Y341709D02*
X991826D01*
G01X980556D02*
X978306D01*
G01X990696Y343660D02*
X988446D01*
G01X987316Y345609D02*
X985066D01*
G01X987316Y341709D02*
X985066D01*
G01X1027875Y369010D02*
X1025625D01*
G01X1026757Y461106D02*
Y464883D01*
X1021650Y469990D01*
Y474099D01*
X1021000Y474749D01*
X1016907D01*
X1015584Y476072D01*
Y478376D01*
X1016907Y479699D01*
X1023651D01*
X1024301Y480349D01*
Y481699D01*
X1023651Y482349D01*
X1016907D01*
X1015584Y483672D01*
Y485976D01*
X1016907Y487299D01*
X1020182D01*
X1021239Y488356D01*
Y512987D01*
X1015945Y518281D01*
X1014147D01*
X1013023Y519405D01*
X1012697D01*
X1010826Y521276D01*
Y523900D01*
X1010828D01*
G01Y542010D02*
X1010826D01*
Y537529D01*
X1011924Y536431D01*
Y534406D01*
X1013826Y532504D01*
X1018668D01*
X1020153Y531019D01*
Y530556D01*
X1021533Y529176D01*
X1021996D01*
X1024259Y526913D01*
Y526438D01*
X1025639Y525058D01*
X1026114D01*
X1027600Y523572D01*
Y515200D01*
X1025650Y513250D01*
Y511300D01*
X1025200Y510850D01*
Y508900D01*
X1025650Y508450D01*
Y506500D01*
X1025200Y506050D01*
Y504100D01*
X1025650Y503650D01*
Y501700D01*
X1025200Y501250D01*
Y499300D01*
X1025650Y498850D01*
Y486070D01*
X1027619Y484101D01*
Y475990D01*
X1027121Y475492D01*
Y473542D01*
X1027619Y473044D01*
Y469560D01*
X1029958Y467221D01*
Y451876D01*
G01X974017Y523900D02*
X974015Y523923D01*
Y529014D01*
G01X1014175Y523900D02*
X1014173D01*
Y519882D01*
X1014624Y519431D01*
X1016422D01*
X1022389Y513464D01*
Y506247D01*
X1022768Y505868D01*
Y503918D01*
X1022389Y503539D01*
Y501516D01*
X1022733Y501172D01*
Y499222D01*
X1022389Y498878D01*
Y496820D01*
X1022733Y496476D01*
Y494526D01*
X1022389Y494182D01*
Y490150D01*
G01X1026800Y497824D02*
Y512773D01*
X1028750Y514723D01*
Y524049D01*
X1019145Y533654D01*
X1014303D01*
X1013074Y534883D01*
Y536530D01*
X1014173Y537629D01*
Y542010D01*
X1014175D01*
G01X980710Y523900D02*
X980708Y523923D01*
Y529014D01*
G01X1004135Y523900D02*
X1004133Y523923D01*
Y529022D01*
G01X1000789Y523900D02*
X1000787Y523923D01*
Y529022D01*
G01X994096Y523900D02*
X994094Y523923D01*
Y529022D01*
G01X990750Y523900D02*
X990748Y523923D01*
Y529022D01*
G01X984057Y523900D02*
X984055Y523923D01*
Y529013D01*
X984054Y529014D01*
G01X977364Y542010D02*
X977362D01*
Y536957D01*
G01X974017Y542010D02*
X974015D01*
Y536957D01*
G01X984055D02*
Y542010D01*
X984057D01*
G01X1004135D02*
X1004133D01*
Y537058D01*
X1004134Y537057D01*
Y536957D01*
G01X997441D02*
Y542010D01*
X997443D01*
G01X994096D02*
X994094D01*
Y536957D01*
G01X987401D02*
Y542010D01*
X987403D01*
G01X977364Y579810D02*
X977362D01*
Y574757D01*
G01X974017Y561700D02*
X974015Y561723D01*
Y566814D01*
G01X974017Y579810D02*
X974015D01*
Y574757D01*
G01X1014175Y561700D02*
X1014173Y561723D01*
Y566814D01*
G01X1014175Y579810D02*
X1014173D01*
Y574742D01*
G01X1010828Y561700D02*
X1010826Y561723D01*
Y566814D01*
G01X1010828Y579810D02*
X1010826D01*
Y574742D01*
G01X984057Y579810D02*
X984055D01*
Y574757D01*
G01X980710Y561700D02*
X980708Y561723D01*
Y566814D01*
G01X1004135Y561700D02*
X1004133Y561723D01*
Y566822D01*
G01X1004135Y579810D02*
X1004133D01*
Y574858D01*
X1004134Y574857D01*
Y574757D01*
G01X1000789Y561700D02*
X1000787Y561723D01*
Y566822D01*
G01X997443Y579810D02*
X997441D01*
Y574757D01*
G01X994096Y579810D02*
X994094D01*
Y574757D01*
G01X994096Y561700D02*
X994094Y561723D01*
Y566822D01*
G01X987403Y579810D02*
X987401D01*
Y574757D01*
G01X990750Y561700D02*
X990748Y561723D01*
Y566822D01*
G01X984057Y561700D02*
X984055Y561723D01*
Y566813D01*
X984054Y566814D01*
G01X977364Y617610D02*
X977362D01*
Y612457D01*
G01X974017Y599500D02*
X974015Y599523D01*
Y604499D01*
G01Y609864D02*
Y617610D01*
X974017D01*
G01X1014175Y599500D02*
X1014173Y599523D01*
Y604614D01*
G01Y612242D02*
Y617610D01*
X1014175D01*
G01X1010828Y599500D02*
X1010826Y599523D01*
Y604614D01*
G01Y612242D02*
Y617610D01*
X1010828D01*
G01X984055Y612457D02*
Y617610D01*
X984057D01*
G01X980710Y599500D02*
X980708Y599523D01*
Y604614D01*
G01X1004135Y599500D02*
X1004133Y599523D01*
X1004134Y599524D01*
Y607292D01*
G01X1004133Y612358D02*
Y617610D01*
X1004135D01*
G01X1000789Y599500D02*
X1000787Y599523D01*
Y604499D01*
G01X997441Y612357D02*
Y617610D01*
X997443D01*
G01X994094Y609864D02*
Y617610D01*
X994096D01*
G01Y599500D02*
X994094Y599523D01*
Y604614D01*
G01X987401Y609864D02*
Y617610D01*
X987403D01*
G01X990750Y599500D02*
X990748Y599523D01*
Y607292D01*
G01X984057Y599500D02*
X984055Y599523D01*
Y607292D01*
G01X1054332Y22923D02*
X1054330D01*
Y28021D01*
X1054331Y28022D01*
G01X1064372Y22923D02*
X1064370D01*
Y28021D01*
X1064371Y28022D01*
G01X1081104Y22923D02*
X1081102D01*
Y28007D01*
G01X1094490Y22923D02*
X1094488D01*
Y28022D01*
G01X1047639Y22923D02*
X1047637D01*
Y28007D01*
G01X1071065Y22923D02*
X1071063D01*
Y28021D01*
X1071064Y28022D01*
G01X1057679Y22923D02*
X1057677D01*
Y28007D01*
G01X1074411Y22923D02*
X1074409D01*
Y28007D01*
G01X1087797Y22923D02*
X1087795D01*
Y28020D01*
X1087797Y28022D01*
G01X1054332Y-14877D02*
X1054330D01*
Y-9901D01*
G01X1050986Y3233D02*
X1050984D01*
Y-1742D01*
X1050983Y-1743D01*
G01X1087797Y3233D02*
X1087795D01*
Y-4536D01*
G01X1064372Y-14877D02*
X1064370D01*
Y-7109D01*
X1064369Y-7108D01*
G01X1081104Y-14877D02*
X1081102D01*
Y-9901D01*
G01X1094490Y-14877D02*
X1094488D01*
Y-9786D01*
G01X1094490Y3233D02*
X1094488D01*
Y-4536D01*
G01X1047639Y-14877D02*
X1047637D01*
Y-9901D01*
G01X1054332Y3233D02*
X1054330D01*
Y-4536D01*
G01X1077757Y3233D02*
X1077755D01*
Y-1743D01*
G01X1064372Y3233D02*
X1064370D01*
Y-1742D01*
X1064369Y-1743D01*
G01X1071065Y-14877D02*
Y-7111D01*
X1071062Y-7108D01*
G01X1057679Y-14877D02*
X1057677D01*
Y-7109D01*
X1057676Y-7108D01*
G01X1084450Y3233D02*
X1084448D01*
Y-1743D01*
G01X1074411Y-14877D02*
X1074409D01*
Y-9786D01*
G01X1087797Y-14877D02*
X1087795D01*
Y-9786D01*
G01X1044293Y3233D02*
X1044291D01*
Y-2200D01*
G01X1054332Y60723D02*
X1054330D01*
Y65821D01*
X1054331Y65822D01*
G01X1054330Y89964D02*
X1053624Y89258D01*
X1051126D01*
X1048972Y91412D01*
Y94128D01*
X1042800Y100300D01*
Y101900D01*
X1041762Y102938D01*
X1040162D01*
X1033985Y109115D01*
Y115181D01*
G01X1050986Y78833D02*
X1050984D01*
Y73758D01*
X1050985Y73757D01*
G01X1064372Y60723D02*
X1064370D01*
Y65821D01*
X1064371Y65822D01*
G01X1081104Y60723D02*
X1081102D01*
Y65807D01*
G01X1094490Y60723D02*
X1094488D01*
Y65822D01*
G01X1094490Y78833D02*
X1094488D01*
Y81813D01*
X1092400Y83901D01*
Y85900D01*
X1093000Y86500D01*
Y88200D01*
X1092000Y89200D01*
X1091700D01*
X1089200Y91700D01*
Y93900D01*
X1081732Y101368D01*
Y104117D01*
G01X1045884Y114809D02*
X1048736Y111957D01*
Y111036D01*
X1047910Y110210D01*
Y109190D01*
X1049160Y107940D01*
X1050080D01*
X1050930Y108790D01*
X1051903D01*
X1052800Y107893D01*
Y101100D01*
X1057455Y96445D01*
X1058375D01*
X1059255Y97325D01*
X1060443D01*
X1061600Y96168D01*
Y95100D01*
X1060214Y93714D01*
Y92214D01*
X1058516Y90516D01*
Y89340D01*
X1060474Y87382D01*
X1061572D01*
X1062900Y88710D01*
Y91288D01*
X1064369Y92757D01*
G01X1081102Y89964D02*
Y91898D01*
X1080000Y93000D01*
Y97301D01*
X1079178Y98123D01*
X1077851D01*
X1077200Y97472D01*
Y95576D01*
X1076550Y94926D01*
X1075219D01*
X1074446Y95699D01*
Y99355D01*
X1073001Y100800D01*
X1070400D01*
X1068700Y102500D01*
Y104697D01*
G01X1081142Y110428D02*
X1086212Y105358D01*
Y104438D01*
X1084509Y102735D01*
Y101815D01*
X1085428Y100896D01*
X1086348D01*
X1088106Y102654D01*
X1089026D01*
X1089956Y101724D01*
Y100804D01*
X1088186Y99034D01*
Y98114D01*
X1089105Y97195D01*
X1090025D01*
X1091795Y98965D01*
X1092715D01*
X1093700Y97980D01*
Y90752D01*
X1094488Y89964D01*
G01X1090500Y104033D02*
X1096400Y98133D01*
Y89100D01*
X1095601Y88301D01*
Y85827D01*
X1094488Y84714D01*
G01X1047639Y60723D02*
X1047637D01*
Y65807D01*
G01X1054332Y78833D02*
X1054330D01*
Y73758D01*
X1054331Y73757D01*
G01X1077757Y78833D02*
X1077755D01*
Y73759D01*
X1077757Y73757D01*
G01X1064372Y78833D02*
X1064370D01*
Y73758D01*
X1064371Y73757D01*
G01X1055341Y104472D02*
Y101559D01*
X1057217Y99683D01*
X1061253D01*
X1066621Y94315D01*
Y91821D01*
X1065900Y91100D01*
Y88923D01*
X1064369Y87392D01*
G01X1071065Y60723D02*
X1071063D01*
Y65821D01*
X1071064Y65822D01*
G01X1057679Y60723D02*
X1057677D01*
Y65807D01*
G01X1057676Y92757D02*
X1056921Y92002D01*
X1054298D01*
X1052607Y93693D01*
Y94712D01*
X1053705Y95810D01*
Y97317D01*
X1053055Y97967D01*
X1051549D01*
X1050351Y96769D01*
X1049431D01*
X1048512Y97688D01*
Y98609D01*
X1049938Y100035D01*
Y100955D01*
X1049019Y101874D01*
X1048099D01*
X1046672Y100447D01*
X1045755D01*
X1044834Y101368D01*
Y102286D01*
X1046031Y103484D01*
Y104672D01*
X1045380Y105323D01*
X1044192D01*
X1043594Y104725D01*
X1042677D01*
X1041756Y105646D01*
Y106564D01*
X1042353Y107161D01*
Y108748D01*
X1038756Y112345D01*
G01X1084450Y78833D02*
X1084448D01*
Y73759D01*
X1084450Y73757D01*
G01X1074411Y60723D02*
X1074409D01*
Y65807D01*
G01X1087797Y60723D02*
X1087795D01*
Y65820D01*
X1087797Y65822D01*
G01X1074409Y89964D02*
Y92711D01*
X1071481Y95639D01*
X1070365D01*
X1068399Y97605D01*
Y98891D01*
X1066590Y100700D01*
X1064100D01*
X1062400Y102400D01*
Y104568D01*
G01X1075100Y104812D02*
Y102500D01*
X1077300Y100300D01*
X1079900D01*
X1086300Y93900D01*
Y91459D01*
X1087795Y89964D01*
G01X1044293Y78833D02*
X1044291D01*
Y87391D01*
X1044290Y87392D01*
G01X1050986Y41033D02*
X1050984D01*
Y35958D01*
X1050985Y35957D01*
G01X1094490Y41033D02*
X1094488D01*
Y35959D01*
X1094490Y35957D01*
G01X1054332Y41033D02*
X1054330D01*
Y36058D01*
X1054331Y36057D01*
Y35957D01*
G01X1077757Y41033D02*
X1077755D01*
Y35959D01*
X1077757Y35957D01*
G01X1064372Y41033D02*
X1064370D01*
Y35958D01*
X1064371Y35957D01*
G01X1084450Y41033D02*
X1084448D01*
Y35959D01*
X1084450Y35957D01*
G01X1044293Y41033D02*
X1044291D01*
Y36058D01*
X1044292Y36057D01*
Y35957D01*
G01X1048016Y106083D02*
X1050983Y103116D01*
G01X1064427D02*
X1066300Y104989D01*
Y106468D01*
X1060718Y112050D01*
G01D02*
X1047880Y124888D01*
Y187498D01*
G01X1055820Y190701D02*
Y129824D01*
X1074425Y111219D01*
G01D02*
X1079136Y106508D01*
Y104932D01*
X1077304Y103100D01*
G01X1081732Y104117D02*
Y106875D01*
X1057805Y130802D01*
Y193595D01*
X1056800Y194600D01*
Y201726D01*
X1055363Y203163D01*
X1054037D01*
X1051989Y205211D01*
X1048155D01*
X1048154Y205210D01*
G01X1039940Y186892D02*
Y120753D01*
X1045884Y114809D01*
G01X1068700Y104697D02*
Y107031D01*
X1049865Y125866D01*
Y187877D01*
G01X1054914Y205210D02*
X1058050D01*
X1058900Y204360D01*
Y195500D01*
X1059790Y194610D01*
Y131780D01*
X1081142Y110428D01*
G01X1054914Y213009D02*
X1056491D01*
X1061100Y208400D01*
Y196399D01*
X1061775Y195724D01*
Y132758D01*
X1090500Y104033D01*
G01X1070663Y159000D02*
Y145703D01*
X1092673Y123693D01*
Y122773D01*
X1091691Y121791D01*
X1090771D01*
X1087820Y124742D01*
X1086743D01*
X1085916Y123915D01*
Y122839D01*
X1104128Y104627D01*
G01X1101598Y110917D02*
X1096894Y115621D01*
Y116595D01*
X1097822Y117523D01*
X1098798D01*
X1101050Y115271D01*
X1101970D01*
X1102952Y116253D01*
Y117173D01*
X1073182Y146943D01*
Y158900D01*
G01X1088077Y159300D02*
Y157269D01*
X1126453Y118893D01*
Y112696D01*
X1131299Y107850D01*
Y104000D01*
G01X1090596Y159600D02*
Y158314D01*
X1128972Y119938D01*
Y115328D01*
X1131400Y112900D01*
G01X1101181Y92757D02*
X1101131Y92807D01*
Y100106D01*
X1069773Y131464D01*
Y132172D01*
X1070967Y133366D01*
X1071675D01*
X1073210Y131831D01*
X1074130D01*
X1075113Y132814D01*
Y133734D01*
X1065625Y143222D01*
Y159300D01*
G01X1104227Y87714D02*
X1106196Y89683D01*
Y91104D01*
X1103750Y93550D01*
Y101245D01*
X1078300Y126695D01*
Y134305D01*
X1068144Y144461D01*
Y159100D01*
G01X1083039D02*
Y155179D01*
X1119700Y118518D01*
Y116492D01*
G01X1085558Y159100D02*
Y156224D01*
X1123934Y117848D01*
Y112500D01*
G01X1114340Y89900D02*
X1115461D01*
X1116111Y90550D01*
Y93289D01*
X1114300Y95100D01*
X1113428D01*
X1112900Y95628D01*
Y105827D01*
X1110250Y108477D01*
Y110549D01*
X1111050Y111349D01*
Y118123D01*
X1108641Y120532D01*
X1106695D01*
X1106355Y120192D01*
X1105363D01*
X1103887Y121668D01*
Y122660D01*
X1104227Y123000D01*
Y124946D01*
X1102076Y127097D01*
X1100130D01*
X1099790Y126757D01*
X1098798D01*
X1097322Y128233D01*
Y129225D01*
X1097662Y129565D01*
Y131511D01*
X1095511Y133662D01*
X1093565D01*
X1093225Y133322D01*
X1092233D01*
X1090757Y134798D01*
Y135790D01*
X1091097Y136130D01*
Y138076D01*
X1088946Y140227D01*
X1085609D01*
X1082709Y143127D01*
Y143835D01*
X1082002Y144542D01*
X1081294D01*
X1080277Y145559D01*
Y146266D01*
X1079569Y146974D01*
X1078862D01*
X1076851Y148985D01*
Y158861D01*
G01X1109228Y123800D02*
X1079370Y153658D01*
Y158760D01*
G01X1075701Y158861D02*
Y148508D01*
X1085132Y139077D01*
X1088469D01*
X1089947Y137599D01*
Y136607D01*
X1089607Y136267D01*
Y134321D01*
X1091756Y132172D01*
X1093702D01*
X1094042Y132512D01*
X1095034D01*
X1096512Y131034D01*
Y130042D01*
X1096172Y129702D01*
Y127756D01*
X1098321Y125607D01*
X1100267D01*
X1100607Y125947D01*
X1101599D01*
X1103077Y124469D01*
Y123477D01*
X1102737Y123137D01*
Y121191D01*
X1104886Y119042D01*
X1106832D01*
X1107172Y119382D01*
X1108164D01*
X1109900Y117646D01*
Y115000D01*
G01X1080520Y158726D02*
Y154135D01*
X1116870Y117785D01*
Y109000D01*
G01X1041925Y187013D02*
Y121675D01*
X1055341Y108259D01*
Y104472D01*
G01X1043910Y187013D02*
Y122690D01*
X1053630Y112970D01*
G01D02*
X1060300Y106300D01*
Y103766D01*
X1059650Y103116D01*
X1057734D01*
G01X1071120D02*
X1073000Y104996D01*
Y106450D01*
X1066798Y112652D01*
G01D02*
X1051850Y127600D01*
Y188251D01*
G01X1062400Y104568D02*
Y107163D01*
X1045895Y123668D01*
Y186770D01*
G01X1053835Y189513D02*
Y128578D01*
X1075100Y107313D01*
Y104812D01*
G01X1067692Y216196D02*
X1065242D01*
G01X1118586Y143516D02*
X1114362Y147740D01*
Y148660D01*
X1114741Y149039D01*
Y149959D01*
X1113787Y150913D01*
X1112867D01*
X1112488Y150534D01*
X1111568D01*
X1110614Y151488D01*
Y152408D01*
X1110993Y152787D01*
Y153707D01*
X1109575Y155125D01*
X1108200D01*
X1107550Y155775D01*
X1106350D01*
X1105700Y156425D01*
Y157775D01*
X1106350Y158425D01*
X1107550D01*
X1108200Y159075D01*
Y161000D01*
G01X1111300Y161400D02*
Y157012D01*
X1125712Y142600D01*
X1128900D01*
X1134169Y137331D01*
Y133231D01*
X1145500Y121900D01*
X1147000D01*
X1147500Y121400D01*
Y120000D01*
X1146510Y119010D01*
Y115200D01*
G01X1138242Y112357D02*
X1132900Y117699D01*
Y121601D01*
X1095500Y159001D01*
Y163750D01*
X1096150Y164400D01*
X1098400D01*
X1098900Y163900D01*
Y163500D01*
X1099400Y163000D01*
X1101600D01*
G01X1105500Y161700D02*
X1102000Y158200D01*
Y156300D01*
X1135700Y122600D01*
Y118500D01*
X1138850Y115350D01*
G01X1067692Y220096D02*
X1065242D01*
G01X1067692Y227896D02*
X1065242D01*
G01X1067692Y231797D02*
X1065242D01*
G01X1074452Y247396D02*
X1072202D01*
G01X1084591Y374146D02*
X1086841D01*
G01X1081212Y376096D02*
X1083462D01*
G01X1081212Y368296D02*
X1083462D01*
G01X1087971D02*
X1090221D01*
G01X1048154Y384609D02*
X1045904D01*
G01X1043875Y413053D02*
X1043760Y413168D01*
Y485823D01*
X1048578Y490641D01*
Y491878D01*
X1047910Y492546D01*
Y493566D01*
X1049160Y494816D01*
X1050080D01*
X1050815Y494081D01*
X1051816D01*
X1052800Y495065D01*
Y498443D01*
G01X1051700Y476126D02*
Y416028D01*
G01X1059640Y474572D02*
Y413141D01*
X1051471Y404972D01*
G01X1084800Y499400D02*
Y497100D01*
X1083163Y495463D01*
X1080902D01*
X1063186Y477747D01*
Y477746D01*
X1061625Y476185D01*
Y412025D01*
X1051800Y402200D01*
G01X1064369Y518157D02*
X1067643D01*
X1069600Y516200D01*
Y514300D01*
X1069100Y513800D01*
Y511500D01*
X1069528Y511072D01*
Y509228D01*
X1066400Y506100D01*
X1061070D01*
X1056656Y501686D01*
Y495812D01*
X1045745Y484901D01*
Y413983D01*
X1045975Y413753D01*
G01X1081102Y515364D02*
X1082049Y514417D01*
Y512351D01*
X1083654Y510746D01*
Y509407D01*
X1082147Y507900D01*
X1080244D01*
X1078443Y506099D01*
Y504456D01*
X1077277Y503290D01*
X1075496D01*
X1073484Y501278D01*
Y500085D01*
X1053685Y480286D01*
Y417443D01*
G01X1063250Y396123D02*
Y407549D01*
X1065595Y409894D01*
Y471347D01*
X1089564Y495316D01*
Y501008D01*
X1096400Y507844D01*
Y510800D01*
X1095500Y511700D01*
Y512920D01*
X1094488Y515364D01*
G01X1054914Y392410D02*
Y393982D01*
X1057432Y396500D01*
X1060000D01*
X1060850Y397350D01*
Y402684D01*
X1060200Y403334D01*
X1058148D01*
X1057561Y403921D01*
Y405271D01*
X1058274Y405984D01*
X1060200D01*
X1060850Y406634D01*
Y408350D01*
X1063610Y411110D01*
Y473054D01*
X1064654Y474098D01*
X1065498D01*
X1067768Y476368D01*
Y477288D01*
X1067138Y477918D01*
Y478838D01*
X1068092Y479792D01*
X1069012D01*
X1069642Y479162D01*
X1070562D01*
X1071958Y480558D01*
Y481478D01*
X1071300Y482136D01*
Y483041D01*
X1072254Y483995D01*
X1073189D01*
X1073832Y483352D01*
X1074752D01*
X1075706Y484306D01*
Y485226D01*
X1075048Y485884D01*
Y486789D01*
X1076002Y487743D01*
X1076937D01*
X1077580Y487100D01*
X1078500D01*
X1079454Y488054D01*
Y488974D01*
X1078781Y489647D01*
Y490497D01*
X1079694Y491410D01*
X1080766D01*
X1081328Y490848D01*
X1082248D01*
X1087549Y496149D01*
Y501350D01*
X1094488Y508289D01*
Y510114D01*
G01X1131299Y518157D02*
X1130000Y516858D01*
Y515100D01*
X1133950Y511150D01*
Y509796D01*
X1131800Y507646D01*
Y491226D01*
X1128908Y488334D01*
X1127932D01*
X1126523Y489743D01*
X1125596D01*
X1124669Y488816D01*
Y487791D01*
X1126029Y486431D01*
Y485455D01*
X1101000Y460426D01*
Y450400D01*
X1094100Y443500D01*
X1090901D01*
G01X1069500D02*
Y455700D01*
X1072700Y458900D01*
Y472892D01*
X1093700Y493892D01*
Y498400D01*
X1100600Y505300D01*
Y506900D01*
X1103153Y509453D01*
Y510947D01*
X1102100Y512000D01*
Y517238D01*
X1101181Y518157D01*
G01X1072043Y443457D02*
Y454543D01*
X1075300Y457800D01*
Y471928D01*
X1097498Y494126D01*
Y495469D01*
X1096595Y496372D01*
Y497194D01*
X1097691Y498290D01*
X1098564D01*
X1100617Y496237D01*
X1101537D01*
X1102520Y497220D01*
Y498140D01*
X1100341Y500319D01*
Y501489D01*
X1101665Y502813D01*
X1102432D01*
X1103315Y501930D01*
X1104310D01*
X1105521Y503141D01*
Y504362D01*
X1104134Y505749D01*
Y506733D01*
X1105899Y508498D01*
Y511442D01*
X1104227Y513114D01*
G01X1090650Y448150D02*
X1095800Y453300D01*
Y462742D01*
X1107388Y474330D01*
Y479046D01*
X1110217Y481875D01*
X1111142D01*
X1112344Y480673D01*
X1113320D01*
X1114247Y481600D01*
Y482627D01*
X1113096Y483778D01*
Y484754D01*
X1125200Y496858D01*
Y508100D01*
X1126700Y509600D01*
Y511126D01*
X1122500Y515326D01*
Y516051D01*
X1124606Y518157D01*
G01X1091351Y381947D02*
X1093601D01*
G01X1091351Y389747D02*
X1093601D01*
G01X1087971Y383896D02*
X1090221D01*
G01X1087971Y387796D02*
X1090221D01*
G01X1080800Y448100D02*
Y449700D01*
X1088370Y457270D01*
Y469914D01*
X1118400Y499944D01*
Y502000D01*
X1117650Y502750D01*
Y505050D01*
X1118400Y505800D01*
Y511328D01*
X1114428Y515300D01*
X1114340D01*
G01X1094731Y383896D02*
X1096981D01*
G01X1094731Y391696D02*
X1096981D01*
G01X1079650Y448100D02*
Y450177D01*
X1087220Y457747D01*
Y461050D01*
X1086720Y461550D01*
Y462850D01*
X1087220Y463350D01*
Y466550D01*
X1086720Y467050D01*
Y468350D01*
X1087220Y468850D01*
Y470391D01*
X1099351Y482522D01*
Y483229D01*
X1100271Y484149D01*
X1100978D01*
X1117250Y500421D01*
Y501523D01*
X1116500Y502273D01*
Y505527D01*
X1117250Y506277D01*
Y510851D01*
X1115401Y512700D01*
X1114340D01*
G01X1094731Y379996D02*
X1096981D01*
G01X1084711Y446289D02*
Y447510D01*
X1092963Y455762D01*
Y466018D01*
X1092122Y466859D01*
Y467879D01*
X1093080Y468837D01*
X1093896D01*
X1094687Y468046D01*
X1096713D01*
X1098733Y470066D01*
Y472259D01*
X1097995Y472997D01*
Y473989D01*
X1099219Y475213D01*
X1100362D01*
X1101250Y474325D01*
X1102995D01*
X1104793Y476123D01*
Y478069D01*
X1104215Y478647D01*
Y479659D01*
X1122510Y497954D01*
Y512445D01*
X1119441Y515514D01*
X1119440D01*
G01X1094731Y387796D02*
X1096981D01*
G01X1044774Y386560D02*
X1042524D01*
G01X1041395Y384609D02*
X1039145D01*
G01X1051534Y390460D02*
X1049284D01*
G01X1047730Y470954D02*
Y414698D01*
G01X1055670Y464870D02*
Y417690D01*
G01X1074409Y515364D02*
X1075600Y514173D01*
Y512501D01*
X1076200Y511901D01*
Y509301D01*
X1067551Y500652D01*
X1065573D01*
X1062164Y497243D01*
Y495265D01*
X1049715Y482816D01*
Y415513D01*
G01X1057655Y418266D02*
Y478055D01*
X1087730Y508130D01*
X1088925Y508625D01*
X1089600Y509300D01*
Y511006D01*
X1087795Y515364D01*
G01X1071072Y389747D02*
X1073322D01*
G01X1071072Y393647D02*
X1073322D01*
G01X1081212Y383896D02*
X1083462D01*
G01X1081212Y387796D02*
X1083462D01*
G01X1071072Y378047D02*
X1073322D01*
G01X1071072Y381947D02*
X1073322D01*
G01X1077832D02*
X1080082D01*
G01X1077832Y389747D02*
X1080082D01*
G01X1074452Y383896D02*
X1076702D01*
G01X1074452Y391696D02*
X1076702D01*
G01X1074452Y379996D02*
X1076702D01*
G01X1074452Y387796D02*
X1076702D01*
G01X1074452Y364396D02*
X1076702D01*
G01X1071072Y370247D02*
X1073322D01*
G01X1084591Y366347D02*
X1086841D01*
G01X1084591Y370247D02*
X1086841D01*
G01X1071072Y366347D02*
X1073322D01*
G01X1081212Y364396D02*
X1083462D01*
G01X1081212Y372197D02*
X1083462D01*
G01X1091351Y354647D02*
X1093601D01*
G01X1091351Y362447D02*
X1093601D01*
G01X1087971Y356596D02*
X1090221D01*
G01X1087971Y360496D02*
X1090221D01*
G01X1077832Y366347D02*
X1080082D01*
G01X1094731Y356596D02*
X1096981D01*
G01X1077832Y370247D02*
X1080082D01*
G01X1094731Y364396D02*
X1096981D01*
G01X1077832Y362447D02*
X1080082D01*
G01X1094731Y352696D02*
X1096981D01*
G01X1077832Y374146D02*
X1080082D01*
G01X1094731Y360496D02*
X1096981D01*
G01X1074562Y443937D02*
Y453263D01*
X1077900Y456601D01*
Y470964D01*
X1098736Y491800D01*
X1100916D01*
X1106394Y497278D01*
Y498254D01*
X1105421Y499227D01*
Y500253D01*
X1106348Y501180D01*
X1107274D01*
X1108297Y500157D01*
X1109273D01*
X1110200Y501084D01*
Y502500D01*
X1107700Y505000D01*
Y506100D01*
X1109700Y508100D01*
Y510900D01*
X1106100Y514500D01*
Y516383D01*
X1107874Y518157D01*
G01X1077081Y446981D02*
Y452008D01*
X1083844Y458771D01*
Y460176D01*
X1083068Y460952D01*
X1081276D01*
X1080500Y461728D01*
Y462826D01*
X1081276Y463602D01*
X1083068D01*
X1083844Y464378D01*
Y465476D01*
X1083068Y466252D01*
X1081276D01*
X1080500Y467028D01*
Y468126D01*
X1081276Y468902D01*
X1083068D01*
X1083844Y469678D01*
Y472275D01*
X1084494Y472925D01*
X1086076D01*
X1087448Y474297D01*
Y475192D01*
X1087030Y475610D01*
Y476530D01*
X1088402Y477902D01*
X1089322D01*
X1089766Y477458D01*
X1090585D01*
X1091957Y478830D01*
Y479851D01*
X1091614Y480194D01*
Y481114D01*
X1092986Y482486D01*
X1093906D01*
X1094349Y482043D01*
X1095168D01*
X1096540Y483415D01*
Y484436D01*
X1096198Y484778D01*
Y485698D01*
X1097570Y487070D01*
X1098490D01*
X1098757Y486803D01*
X1099677D01*
X1112100Y499226D01*
Y502427D01*
X1112750Y503077D01*
X1113550D01*
X1114200Y503727D01*
Y505667D01*
X1113550Y506317D01*
X1112750D01*
X1111953Y507114D01*
Y508621D01*
X1112516Y509184D01*
Y512184D01*
X1111586Y513114D01*
X1110520D01*
G01X1090700Y440900D02*
X1095600D01*
X1103900Y449200D01*
Y459568D01*
X1134500Y490168D01*
Y501400D01*
X1135557Y502457D01*
Y503377D01*
X1133982Y504952D01*
Y505997D01*
X1135354Y507369D01*
X1136149D01*
X1137849Y505669D01*
X1138769D01*
X1140100Y507000D01*
Y510900D01*
X1137886Y513114D01*
X1134645D01*
G01X1092400Y446000D02*
X1098400Y452000D01*
Y461584D01*
X1111070Y474254D01*
Y475201D01*
X1109912Y476359D01*
Y477068D01*
X1111003Y478159D01*
X1111860D01*
X1112939Y477080D01*
X1113896D01*
X1118100Y481284D01*
Y482532D01*
X1116791Y483841D01*
Y484880D01*
X1117918Y486007D01*
X1118831D01*
X1120406Y484432D01*
X1121382D01*
X1122309Y485359D01*
Y486335D01*
X1120860Y487784D01*
Y488760D01*
X1125050Y492950D01*
X1128550D01*
X1129200Y493600D01*
Y495540D01*
X1128550Y496190D01*
X1128450D01*
X1127800Y496840D01*
Y499880D01*
X1128350Y500430D01*
X1129006D01*
X1129681Y501105D01*
Y503045D01*
X1129056Y503670D01*
X1127678D01*
X1127178Y504170D01*
Y506920D01*
X1129400Y509142D01*
Y511666D01*
X1127952Y513114D01*
G01X1083500Y446350D02*
X1083561Y446411D01*
Y447987D01*
X1085068Y449494D01*
Y450201D01*
X1085776Y450909D01*
X1086483D01*
X1087190Y451616D01*
Y452323D01*
X1087898Y453031D01*
X1088605D01*
X1089312Y453738D01*
Y454445D01*
X1090020Y455153D01*
X1090727D01*
X1091813Y456239D01*
Y460739D01*
X1091313Y461239D01*
Y462239D01*
X1091813Y462739D01*
Y465541D01*
X1090972Y466382D01*
Y468356D01*
X1092603Y469987D01*
X1094373D01*
X1095164Y469196D01*
X1096236D01*
X1097583Y470543D01*
Y471782D01*
X1096845Y472520D01*
Y474466D01*
X1098742Y476363D01*
X1100839D01*
X1101727Y475475D01*
X1102518D01*
X1103643Y476600D01*
Y477592D01*
X1103065Y478170D01*
Y480136D01*
X1105229Y482300D01*
Y483178D01*
X1105937Y483885D01*
X1106814D01*
X1107521Y484592D01*
Y485469D01*
X1108228Y486176D01*
X1109105D01*
X1109900Y486971D01*
Y487849D01*
X1110608Y488556D01*
X1111485D01*
X1112192Y489263D01*
Y490141D01*
X1112900Y490848D01*
X1113777D01*
X1114484Y491555D01*
Y492433D01*
X1115192Y493140D01*
X1116069D01*
X1116776Y493847D01*
Y494725D01*
X1117484Y495432D01*
X1118361D01*
X1119068Y496139D01*
Y497017D01*
X1119776Y497724D01*
X1120653D01*
X1121360Y498431D01*
Y499577D01*
X1120860Y500077D01*
Y501077D01*
X1121360Y501577D01*
Y502577D01*
X1120860Y503077D01*
Y504077D01*
X1121360Y504577D01*
Y505577D01*
X1120860Y506077D01*
Y507077D01*
X1121360Y507577D01*
Y508577D01*
X1120860Y509077D01*
Y510077D01*
X1121360Y510577D01*
Y511968D01*
X1120414Y512914D01*
X1119440D01*
G01X1108000Y451400D02*
Y457922D01*
X1116871Y466793D01*
X1117791D01*
X1118370Y466214D01*
X1119290D01*
X1120244Y467168D01*
Y468088D01*
X1119626Y468706D01*
Y469626D01*
X1120580Y470580D01*
X1121500D01*
X1122118Y469962D01*
X1123038D01*
X1123992Y470916D01*
Y471836D01*
X1123413Y472415D01*
Y473335D01*
X1134178Y484100D01*
X1137700D01*
X1138500Y484900D01*
Y492100D01*
X1139200Y492800D01*
Y494500D01*
X1139800Y495100D01*
Y496679D01*
X1137992Y498487D01*
G01X1110600Y450300D02*
X1111000Y450700D01*
Y454200D01*
X1113172Y456372D01*
Y457292D01*
X1112534Y457930D01*
Y458850D01*
X1113488Y459804D01*
X1114408D01*
X1115046Y459166D01*
X1115966D01*
X1116920Y460120D01*
Y461040D01*
X1116282Y461678D01*
Y462598D01*
X1117236Y463552D01*
X1118156D01*
X1118794Y462914D01*
X1119714D01*
X1126527Y469727D01*
Y472695D01*
X1127616Y473784D01*
X1128536D01*
X1129231Y473089D01*
X1130151D01*
X1131105Y474043D01*
Y474963D01*
X1130410Y475658D01*
Y476578D01*
X1131364Y477532D01*
X1132284D01*
X1132979Y476837D01*
X1133899D01*
X1134853Y477791D01*
Y478711D01*
X1134286Y479278D01*
Y479986D01*
X1135452Y481152D01*
X1136160D01*
X1138412Y478900D01*
X1140100D01*
X1142639Y481439D01*
Y484661D01*
X1141038Y486262D01*
Y491144D01*
G01X1054332Y523900D02*
X1054330Y523923D01*
Y529021D01*
X1054331Y529022D01*
G01X1052800Y498443D02*
Y501800D01*
X1059200Y508200D01*
X1062400D01*
X1066200Y512000D01*
Y513700D01*
X1062500Y517400D01*
Y519101D01*
X1064370Y520971D01*
Y523900D01*
X1064372D01*
G01X1051700Y476126D02*
Y481900D01*
X1078100Y508300D01*
Y510300D01*
X1079554Y511754D01*
Y514146D01*
X1079200Y514500D01*
Y516200D01*
X1080900Y517900D01*
Y523721D01*
X1081091Y523912D01*
X1081104Y523900D01*
G01X1094490D02*
X1094488D01*
Y518388D01*
X1092700Y516600D01*
Y514300D01*
X1093400Y513600D01*
Y511700D01*
X1092150Y510450D01*
Y508750D01*
X1090813Y507413D01*
X1089276Y506776D01*
X1059640Y477140D01*
Y474572D01*
G01X1047639Y523900D02*
X1047637Y523923D01*
Y529007D01*
G01X1071065Y523900D02*
X1071063Y523923D01*
Y529021D01*
X1071064Y529022D01*
G01X1057679Y523900D02*
X1057677Y523923D01*
Y529007D01*
G01X1047730Y470954D02*
Y483886D01*
X1059091Y495247D01*
Y500379D01*
X1062596Y503884D01*
X1066884D01*
X1072300Y509300D01*
Y511500D01*
X1072900Y512100D01*
Y513700D01*
X1071900Y514700D01*
Y516100D01*
X1073900Y518100D01*
Y523414D01*
X1074409Y523923D01*
X1074411Y523900D01*
G01X1087797D02*
X1087795D01*
Y517995D01*
X1085735Y515935D01*
Y514331D01*
X1086500Y513566D01*
Y511500D01*
X1086000Y511000D01*
Y509400D01*
X1055670Y479070D01*
Y464870D01*
G01X1050986Y542010D02*
X1050984D01*
Y536958D01*
X1050985Y536957D01*
G01X1094490Y542010D02*
X1094488D01*
Y536959D01*
X1094490Y536957D01*
G01X1054332Y542010D02*
X1054330D01*
Y536958D01*
X1054331Y536957D01*
G01X1077757Y542010D02*
X1077755D01*
Y536959D01*
X1077757Y536957D01*
G01X1064372Y542010D02*
X1064370D01*
Y536958D01*
X1064371Y536957D01*
G01X1084450Y542010D02*
X1084448D01*
Y536959D01*
X1084450Y536957D01*
G01X1044293Y542010D02*
X1044291D01*
Y537146D01*
X1044203Y537058D01*
G01X1054332Y561700D02*
X1054330Y561723D01*
Y566821D01*
X1054331Y566822D01*
G01X1050985Y574757D02*
X1050984Y574758D01*
Y579810D01*
X1050986D01*
G01X1064372Y561700D02*
X1064370Y561723D01*
Y566821D01*
X1064371Y566822D01*
G01X1081104Y561700D02*
X1081102Y561723D01*
Y566807D01*
G01X1094490Y561700D02*
X1094488Y561723D01*
Y566822D01*
G01X1094490Y574757D02*
X1094488Y574759D01*
Y579810D01*
X1094490D01*
G01X1047639Y561700D02*
X1047637Y561723D01*
Y566807D01*
G01X1054331Y574757D02*
Y574857D01*
X1054330Y574858D01*
Y579810D01*
X1054332D01*
G01X1077757Y574757D02*
X1077755Y574759D01*
Y579810D01*
X1077757D01*
G01X1064371Y574757D02*
X1064370Y574758D01*
Y579810D01*
X1064372D01*
G01X1071065Y561700D02*
X1071063Y561723D01*
Y566821D01*
X1071064Y566822D01*
G01X1057679Y561700D02*
X1057677Y561723D01*
Y566807D01*
G01X1084450Y574757D02*
X1084448Y574759D01*
Y579810D01*
X1084450D01*
G01X1074411Y561700D02*
X1074409Y561723D01*
Y566807D01*
G01X1087797Y561700D02*
X1087795Y561723D01*
Y566820D01*
X1087797Y566822D01*
G01X1044293Y579810D02*
X1044291D01*
Y574858D01*
X1044292Y574857D01*
Y574757D01*
G01X1054332Y599500D02*
X1054330Y599523D01*
Y604499D01*
G01X1050984Y612658D02*
Y617610D01*
X1050986D01*
G01X1087795Y609864D02*
Y617610D01*
X1087797D01*
G01X1064372Y599500D02*
X1064370Y599523D01*
Y607291D01*
X1064369Y607292D01*
G01X1081104Y599500D02*
X1081102Y599523D01*
Y604499D01*
G01X1094490Y599500D02*
X1094488Y599523D01*
Y604614D01*
G01Y609864D02*
Y617610D01*
X1094490D01*
G01X1047639Y599500D02*
X1047637Y599523D01*
Y604499D01*
G01X1054330Y609864D02*
Y617610D01*
X1054332D01*
G01X1077757D02*
X1077755D01*
Y612657D01*
G01X1064369D02*
X1064370Y612658D01*
Y617610D01*
X1064372D01*
G01X1071065Y599500D02*
X1071063Y599523D01*
Y607291D01*
X1071062Y607292D01*
G01X1057679Y599500D02*
X1057677Y599523D01*
Y607291D01*
X1057676Y607292D01*
G01X1084448Y612657D02*
Y617610D01*
X1084450D01*
G01X1074411Y599500D02*
X1074409Y599523D01*
Y604614D01*
G01X1087797Y599500D02*
X1087795Y599523D01*
Y604614D01*
G01X1044293Y617610D02*
X1044291D01*
Y612658D01*
G01X1107876Y22923D02*
X1107874D01*
Y27899D01*
G01X1131301Y22923D02*
X1131299D01*
Y27899D01*
G01X1101183Y22923D02*
X1101181D01*
Y27899D01*
G01X1124608Y22923D02*
X1124606D01*
Y27899D01*
G01X1144687Y22923D02*
X1144685D01*
Y27899D01*
G01X1137994Y22923D02*
X1137992D01*
Y27899D01*
G01X1117915Y22923D02*
X1117913D01*
Y25495D01*
X1116266Y27142D01*
Y28800D01*
X1116998Y29532D01*
Y30503D01*
X1116006Y31495D01*
X1115111D01*
X1114366Y30750D01*
G01X1154726Y22923D02*
X1154723D01*
Y25496D01*
X1153077Y27142D01*
Y28800D01*
X1153809Y29532D01*
Y30503D01*
X1152817Y31495D01*
X1151997D01*
X1151252Y30750D01*
X1151177D01*
G01X1117915Y41033D02*
Y36808D01*
X1116408Y35301D01*
Y33601D01*
X1117709Y32300D01*
X1118591D01*
X1119440Y33149D01*
G01X1154726Y41033D02*
Y36808D01*
X1153201Y35283D01*
Y33619D01*
X1154520Y32300D01*
X1155402D01*
X1156251Y33149D01*
G01X1114568Y22923D02*
X1114566D01*
Y25411D01*
X1112400Y27577D01*
Y30693D01*
X1112837Y31896D01*
X1114340Y33399D01*
G01X1151151D02*
X1149649Y31897D01*
Y31896D01*
X1149328Y31013D01*
Y27792D01*
X1149661Y27068D01*
X1151378Y25351D01*
Y22923D01*
X1151380D01*
G01X1121261Y41033D02*
X1121259D01*
Y37049D01*
X1121408Y36900D01*
Y31500D01*
X1120448Y30540D01*
X1119440D01*
G01X1158072Y41033D02*
X1158070D01*
Y37049D01*
X1158219Y36900D01*
Y31500D01*
X1157259Y30540D01*
X1156251D01*
G01X1111222Y3233D02*
X1111220D01*
X1110520Y-4100D01*
G01X1107876Y-14877D02*
X1107874D01*
Y-9901D01*
G01X1134647Y3233D02*
X1134645D01*
Y-692D01*
X1135163Y-1210D01*
Y-2090D01*
X1134645Y-2608D01*
Y-3700D01*
G01X1131301Y-14877D02*
X1131299D01*
Y-9901D01*
G01X1104529Y3233D02*
X1104527D01*
Y-2008D01*
X1104141Y-4100D01*
G01X1101183Y-14877D02*
X1101181D01*
Y-9901D01*
G01X1127954Y3233D02*
X1127953Y3232D01*
Y-600D01*
X1128473Y-1120D01*
Y-1980D01*
X1127953Y-2500D01*
Y-3699D01*
X1127952Y-3700D01*
G01X1124608Y-14877D02*
X1124606D01*
Y-9901D01*
G01X1148033Y3233D02*
X1148031D01*
X1147331Y-4100D01*
G01X1144687Y-14877D02*
X1144685D01*
Y-9901D01*
G01X1141340Y3233D02*
X1141338D01*
Y-2008D01*
X1140952Y-4100D01*
G01X1137994Y-14877D02*
X1137992D01*
Y-9901D01*
G01X1117915Y-14877D02*
X1117913D01*
Y-11561D01*
X1116266Y-9914D01*
Y-9000D01*
X1116998Y-8268D01*
Y-7297D01*
X1116006Y-6305D01*
X1115186D01*
X1114441Y-7050D01*
X1114366D01*
G01X1154726Y-14877D02*
X1154724D01*
Y-11560D01*
X1153078Y-9914D01*
Y-9000D01*
X1153810Y-8268D01*
Y-7297D01*
X1152818Y-6305D01*
X1151998D01*
X1151253Y-7050D01*
X1151178D01*
G01X1117915Y3233D02*
Y-752D01*
X1116866Y-1801D01*
Y-4686D01*
X1119440Y-7260D01*
G01X1154726Y3233D02*
X1154724D01*
Y-755D01*
X1153678Y-1801D01*
Y-4686D01*
X1156252Y-7260D01*
G01X1114568Y-14877D02*
X1114566D01*
Y-12448D01*
X1112849Y-10731D01*
X1112516Y-10008D01*
Y-6787D01*
X1112837Y-5904D01*
X1114340Y-4401D01*
G01X1151152D02*
X1149649Y-5904D01*
X1149328Y-6787D01*
Y-10008D01*
X1149661Y-10732D01*
X1151378Y-12449D01*
Y-14877D01*
X1151380D01*
G01X1121261Y3233D02*
X1121258Y3230D01*
Y-1092D01*
X1122131Y-1965D01*
Y-4887D01*
X1121289Y-5729D01*
X1120518D01*
X1119440Y-4651D01*
G01X1158072Y3233D02*
X1158070D01*
Y-1092D01*
X1158943Y-1965D01*
Y-4887D01*
X1158101Y-5729D01*
X1157330D01*
X1156252Y-4651D01*
G01X1111222Y78833D02*
X1111220D01*
X1110902Y75500D01*
X1110520Y71500D01*
G01X1104128Y104627D02*
X1106350Y102405D01*
Y94281D01*
X1107874Y92757D01*
G01X1110520Y87714D02*
X1108516Y89718D01*
Y90866D01*
X1109966Y92316D01*
Y93856D01*
X1108950Y94872D01*
Y103565D01*
X1101598Y110917D01*
G01X1107876Y60723D02*
X1107874D01*
Y65699D01*
G01X1134647Y78833D02*
X1134645D01*
Y74908D01*
X1135163Y74390D01*
Y73510D01*
X1134645Y72992D01*
Y71900D01*
G01X1131299Y104000D02*
Y97201D01*
X1133800Y94700D01*
Y92801D01*
X1133100Y92101D01*
Y91490D01*
X1132779Y91169D01*
Y90227D01*
X1131900Y89348D01*
X1131192D01*
X1130200Y90340D01*
Y91658D01*
X1131299Y92757D01*
G01X1131301Y60723D02*
X1131299D01*
Y65699D01*
G01X1131400Y112900D02*
X1134100Y110200D01*
Y101700D01*
X1140346Y95454D01*
Y92546D01*
X1137569Y89769D01*
X1136700D01*
X1134645Y87714D01*
G01X1104529Y78833D02*
X1104527D01*
Y73592D01*
X1104141Y71500D01*
G01X1101183Y60723D02*
X1101181D01*
Y65699D01*
G01X1127952Y71900D02*
X1127953Y71901D01*
Y73100D01*
X1128473Y73620D01*
Y74480D01*
X1127953Y75000D01*
Y78832D01*
X1127954Y78833D01*
G01X1119700Y116492D02*
Y103701D01*
X1120201Y103200D01*
X1125450D01*
X1126100Y102550D01*
Y101050D01*
X1125450Y100400D01*
X1120050D01*
X1119500Y99850D01*
Y97800D01*
X1120300Y97000D01*
X1125401D01*
X1125900Y96501D01*
Y95599D01*
X1124606Y94305D01*
Y92757D01*
G01X1124608Y60723D02*
X1124606D01*
Y65699D01*
G01X1123934Y112500D02*
Y109758D01*
X1128700Y104992D01*
Y94100D01*
X1125800Y91200D01*
Y88364D01*
X1126450Y87714D01*
X1127952D01*
G01X1148033Y78833D02*
X1148031D01*
X1147713Y75500D01*
X1147331Y71500D01*
G01X1144687Y60723D02*
X1144685D01*
Y65699D01*
G01X1141340Y78833D02*
X1141338D01*
Y73592D01*
X1140952Y71500D01*
G01X1137994Y60723D02*
X1137992D01*
Y65699D01*
G01X1117915Y60723D02*
X1117913D01*
Y63295D01*
X1116266Y64942D01*
Y66600D01*
X1116998Y67332D01*
Y68303D01*
X1116006Y69295D01*
X1115186D01*
X1114441Y68550D01*
X1114366D01*
G01X1154726Y60723D02*
X1154724D01*
Y63296D01*
X1153078Y64942D01*
Y66600D01*
X1153810Y67332D01*
Y68303D01*
X1152818Y69295D01*
X1151998D01*
X1151253Y68550D01*
X1151178D01*
G01X1117915Y78833D02*
Y74608D01*
X1116408Y73101D01*
Y71401D01*
X1117709Y70100D01*
X1118591D01*
X1119440Y70949D01*
G01Y87514D02*
X1117645Y89309D01*
Y94255D01*
X1115720Y96180D01*
Y117308D01*
X1109228Y123800D01*
G01X1154726Y78833D02*
X1154724D01*
Y74605D01*
X1153220Y73101D01*
Y71401D01*
X1154521Y70100D01*
X1155403D01*
X1156252Y70949D01*
G01X1109900Y115000D02*
Y111826D01*
X1109100Y111026D01*
Y108000D01*
X1111750Y105350D01*
Y95151D01*
X1112450Y94451D01*
Y89190D01*
X1114340Y87300D01*
G01X1114568Y60723D02*
X1114566D01*
Y63152D01*
X1112849Y64869D01*
X1112516Y65592D01*
Y68813D01*
X1112837Y69696D01*
X1114340Y71199D01*
G01X1151152D02*
X1149649Y69696D01*
X1149328Y68813D01*
Y65592D01*
X1149661Y64868D01*
X1151378Y63151D01*
Y60723D01*
X1151380D01*
G01X1116870Y109000D02*
Y96657D01*
X1118927Y94600D01*
X1120477D01*
X1121800Y93277D01*
Y90764D01*
X1121150Y90114D01*
X1119440D01*
G01X1121261Y78833D02*
X1121259D01*
Y74849D01*
X1121408Y74700D01*
Y69300D01*
X1120448Y68340D01*
X1119440D01*
G01X1156252D02*
X1157260D01*
X1158220Y69300D01*
Y74700D01*
X1158071Y74849D01*
Y78832D01*
X1158072Y78833D01*
G01X1111222Y41033D02*
Y34402D01*
X1110520Y33700D01*
G01X1134647Y41033D02*
X1134645D01*
Y37108D01*
X1135163Y36590D01*
Y35710D01*
X1134645Y35192D01*
Y34100D01*
G01X1104529Y41033D02*
Y34088D01*
X1104141Y33700D01*
G01X1127952Y34100D02*
X1127953Y34101D01*
Y35300D01*
X1128473Y35820D01*
Y36680D01*
X1127953Y37200D01*
Y41032D01*
X1127954Y41033D01*
G01X1148033D02*
X1148031D01*
X1147455Y35000D01*
X1147407Y34500D01*
X1147331Y33700D01*
G01X1141340Y41033D02*
X1141338D01*
Y35792D01*
X1141192Y35000D01*
X1141100Y34500D01*
X1140952Y33700D01*
G01X1144535Y112357D02*
X1143300Y113592D01*
Y114900D01*
X1141900Y116300D01*
Y117200D01*
X1143796Y119096D01*
Y119804D01*
X1142360Y121240D01*
X1141440D01*
X1139760Y119560D01*
X1139052D01*
X1138219Y120393D01*
Y121767D01*
X1139566Y123114D01*
Y124034D01*
X1131650Y131950D01*
Y136150D01*
X1127719Y140081D01*
X1122021D01*
X1118586Y143516D01*
G01X1146510Y115200D02*
Y111434D01*
X1144300Y109224D01*
Y106800D01*
X1142700Y105200D01*
Y103300D01*
X1144500Y101500D01*
X1146681D01*
X1147331Y102150D01*
Y106964D01*
G01X1131904Y163803D02*
X1135300Y160407D01*
Y158200D01*
X1144300Y149200D01*
X1151700D01*
X1166050Y134850D01*
Y130500D01*
G01X1134000Y165900D02*
X1137819Y162081D01*
Y159381D01*
X1145400Y151800D01*
X1153000D01*
X1170660Y134140D01*
Y117000D01*
G01X1138850Y115350D02*
X1140600Y113600D01*
Y111800D01*
X1139200Y110400D01*
X1137852D01*
X1137202Y109750D01*
Y107614D01*
X1138616Y106200D01*
X1140274D01*
X1141038Y106964D01*
G01X1126600Y161900D02*
X1128700Y159800D01*
Y157600D01*
X1144476Y141824D01*
X1145396D01*
X1147276Y143704D01*
X1148196D01*
X1149150Y142750D01*
Y141830D01*
X1147270Y139950D01*
Y139030D01*
X1148224Y138076D01*
X1149144D01*
X1151024Y139956D01*
X1151944D01*
X1152898Y139002D01*
Y138082D01*
X1151018Y136202D01*
Y135282D01*
X1151972Y134328D01*
X1152892D01*
X1154772Y136208D01*
X1155692D01*
X1156646Y135254D01*
Y134334D01*
X1154766Y132454D01*
Y131534D01*
X1158500Y127800D01*
Y122500D01*
G01X1129400Y162700D02*
X1132000Y160100D01*
Y157900D01*
X1143500Y146400D01*
X1150456D01*
X1161100Y135675D01*
Y133000D01*
G01X1134363Y143064D02*
X1130777Y146650D01*
X1126876D01*
X1124143Y149383D01*
Y150091D01*
X1123435Y150798D01*
X1122728D01*
X1122021Y151505D01*
Y152213D01*
X1121313Y152921D01*
X1120605D01*
X1119406Y154120D01*
Y154828D01*
X1118698Y155535D01*
X1117991D01*
X1117284Y156242D01*
Y156950D01*
X1116576Y157657D01*
X1115869D01*
X1115162Y158364D01*
Y161600D01*
G01X1134363Y143064D02*
X1139252Y138175D01*
Y136301D01*
X1138142Y135191D01*
Y134485D01*
X1139312Y133315D01*
X1140018D01*
X1141128Y134425D01*
X1143002D01*
X1145923Y131504D01*
Y129630D01*
X1145350Y129057D01*
Y127749D01*
X1146899Y126200D01*
X1150677D01*
X1151850Y125027D01*
Y118322D01*
X1150527Y116999D01*
Y115573D01*
X1151100Y115000D01*
X1152400D01*
X1152947Y114453D01*
Y111447D01*
X1152014Y110514D01*
X1151152D01*
G01X1141231Y139841D02*
X1131572Y149500D01*
X1129200D01*
X1118312Y160388D01*
Y161700D01*
G01X1141231Y139841D02*
X1154462Y126610D01*
Y115180D01*
X1154483Y115159D01*
Y109424D01*
X1156252Y107655D01*
G01X1151178Y107865D02*
X1149377Y109666D01*
Y117476D01*
X1150700Y118799D01*
Y124550D01*
X1150200Y125050D01*
X1146422D01*
X1144200Y127272D01*
Y129534D01*
X1144773Y130107D01*
Y131027D01*
X1142525Y133275D01*
X1141605D01*
X1140495Y132165D01*
X1138835D01*
X1136992Y134008D01*
Y135668D01*
X1138102Y136778D01*
Y137698D01*
X1130300Y145500D01*
X1126399D01*
X1114012Y157887D01*
Y161600D01*
G01X1156278Y110264D02*
X1157364D01*
X1158500Y111400D01*
Y113399D01*
X1155612Y116287D01*
Y127087D01*
X1132049Y150650D01*
X1129677D01*
X1127950Y152377D01*
Y153085D01*
X1127242Y153792D01*
X1126535D01*
X1125828Y154499D01*
Y155207D01*
X1125120Y155914D01*
X1124413D01*
X1123706Y156621D01*
Y157329D01*
X1122998Y158036D01*
X1122291D01*
X1121584Y158743D01*
Y159451D01*
X1120876Y160158D01*
X1120169D01*
X1119462Y160865D01*
Y161700D01*
G01X1133040Y216196D02*
X1135290D01*
G01X1181496Y112357D02*
X1180100Y113753D01*
Y129572D01*
X1182081Y131553D01*
Y132950D01*
X1179800Y135231D01*
Y137519D01*
X1183355Y141074D01*
Y141782D01*
X1181698Y143439D01*
X1180990D01*
X1179679Y142128D01*
X1178971D01*
X1177705Y143394D01*
Y144104D01*
X1179015Y145414D01*
Y146122D01*
X1177601Y147536D01*
X1176893D01*
X1173782Y144425D01*
X1173074D01*
X1171992Y145507D01*
Y146229D01*
X1174783Y149020D01*
Y150316D01*
X1165700Y159399D01*
Y165812D01*
X1165718Y165830D01*
G01X1182811Y119500D02*
Y128720D01*
X1184600Y130509D01*
Y138214D01*
X1186050Y139664D01*
Y142650D01*
X1168300Y160400D01*
Y165406D01*
X1168268Y165438D01*
G01X1182546Y171200D02*
X1207300Y146446D01*
Y133500D01*
G01X1183710Y173600D02*
X1209819Y147491D01*
Y140500D01*
G01X1174000Y132500D02*
Y135496D01*
X1159504Y149992D01*
Y151016D01*
X1160458Y151970D01*
X1161378D01*
X1163514Y149834D01*
X1164434D01*
X1165311Y150711D01*
Y151631D01*
X1161378Y155564D01*
X1160458D01*
X1159657Y154763D01*
X1158737D01*
X1157754Y155746D01*
Y156454D01*
X1160618Y159318D01*
Y167318D01*
G01X1176519Y125000D02*
Y136541D01*
X1166036Y147024D01*
Y147872D01*
X1167228Y149064D01*
X1167936D01*
X1168896Y148104D01*
X1169604D01*
X1171096Y149596D01*
Y150304D01*
X1163168Y158232D01*
Y166768D01*
G01X1179300Y167319D02*
X1196936Y149683D01*
Y144519D01*
X1197586Y143869D01*
X1201586D01*
X1202236Y143219D01*
Y134350D01*
X1201586Y133700D01*
X1200236D01*
X1199586Y134350D01*
Y137150D01*
X1198936Y137800D01*
X1197586D01*
X1196936Y137150D01*
Y120500D01*
G01X1181200Y168982D02*
X1204755Y145427D01*
Y139000D01*
G01X1172000Y164900D02*
Y161927D01*
X1172707Y161220D01*
X1173414D01*
X1174122Y160513D01*
Y159805D01*
X1175106Y158821D01*
X1175814D01*
X1176521Y158114D01*
Y157406D01*
X1190600Y143327D01*
Y141000D01*
G01X1175550Y164800D02*
Y163050D01*
X1193267Y145333D01*
Y126500D01*
G01X1170850Y164900D02*
Y161450D01*
X1189450Y142850D01*
Y139500D01*
X1187119Y137169D01*
Y135500D01*
G01X1176700Y164800D02*
Y163527D01*
X1177407Y162820D01*
X1178114D01*
X1178822Y162113D01*
Y161405D01*
X1179606Y160621D01*
X1180314D01*
X1181021Y159914D01*
Y159206D01*
X1181806Y158421D01*
X1182514D01*
X1183221Y157714D01*
Y157006D01*
X1183928Y156299D01*
X1184635D01*
X1185343Y155592D01*
Y154884D01*
X1186050Y154177D01*
X1186757D01*
X1187465Y153470D01*
Y152762D01*
X1194417Y145810D01*
Y135000D01*
G01X1133040Y227896D02*
X1135290D01*
G01X1133040Y220096D02*
X1135290D01*
G01X1138670Y381947D02*
X1140920D01*
G01X1130780Y360496D02*
X1128530D01*
G01X1142050Y356596D02*
X1144300D01*
G01X1108251Y372197D02*
X1110501D01*
G01X1101491Y383896D02*
X1103741D01*
G01X1101491Y387796D02*
X1103741D01*
G01X1098111Y381947D02*
X1100361D01*
G01X1098111Y389747D02*
X1100361D01*
G01X1111631Y381947D02*
X1113881D01*
G01X1111631Y389747D02*
X1113881D01*
G01X1121771Y383896D02*
X1124021D01*
G01X1121771Y387796D02*
X1124021D01*
G01X1108251Y383896D02*
X1110501D01*
G01X1108251Y387796D02*
X1110501D01*
G01X1118391Y381947D02*
X1120641D01*
G01X1118391Y389747D02*
X1120641D01*
G01X1131910Y381947D02*
X1134160D01*
G01X1131910Y389747D02*
X1134160D01*
G01X1142050Y395597D02*
X1144300D01*
G01X1142050Y399496D02*
X1144300D01*
G01X1130780Y383896D02*
X1128530D01*
G01X1130780Y387796D02*
X1128530D01*
G01X1138670Y401447D02*
X1140920D01*
G01X1138670Y393647D02*
X1140920D01*
G01X1115011Y379996D02*
X1117261D01*
G01X1135290D02*
X1137540D01*
G01X1115011Y391696D02*
X1117261D01*
G01X1135290D02*
X1137540D01*
G01X1115011Y383896D02*
X1117261D01*
G01X1135290D02*
X1137540D01*
G01X1115011Y387796D02*
X1117261D01*
G01X1135290D02*
X1137540D01*
G01X1113200Y449100D02*
X1114000Y449900D01*
Y453372D01*
X1136328Y475700D01*
X1140700D01*
X1146000Y481000D01*
Y485500D01*
X1143600Y487900D01*
Y492400D01*
X1142800Y493200D01*
Y494500D01*
X1141800Y495500D01*
Y501000D01*
X1142500Y501700D01*
X1146000D01*
X1146685Y501015D01*
Y499485D01*
X1145687Y498487D01*
X1144385D01*
G01X1115800Y448100D02*
X1117000Y449300D01*
Y452500D01*
X1119400Y454900D01*
X1123308D01*
X1125300Y456892D01*
Y457990D01*
X1124394Y458896D01*
Y459994D01*
X1125170Y460770D01*
X1126268D01*
X1127174Y459864D01*
X1128272D01*
X1129048Y460640D01*
Y461738D01*
X1128142Y462644D01*
Y463742D01*
X1128918Y464518D01*
X1130016D01*
X1130922Y463612D01*
X1132020D01*
X1132796Y464388D01*
Y465486D01*
X1131890Y466392D01*
Y467490D01*
X1132666Y468266D01*
X1133764D01*
X1134670Y467360D01*
X1135768D01*
X1136544Y468136D01*
Y469234D01*
X1135638Y470140D01*
Y471238D01*
X1136414Y472014D01*
X1137512D01*
X1138418Y471108D01*
X1139516D01*
X1140904Y472496D01*
X1141204D01*
X1149100Y480392D01*
Y484904D01*
X1149925Y485729D01*
Y489000D01*
X1148031Y490894D01*
X1147331D01*
G01X1135400Y443500D02*
X1144589Y452689D01*
X1150497D01*
X1154188Y456380D01*
X1156963D01*
X1159532Y458949D01*
Y464295D01*
X1170440Y475203D01*
Y487160D01*
X1168800Y488800D01*
Y494500D01*
X1169300Y495000D01*
Y496697D01*
X1167510Y498487D01*
G01X1137200Y441700D02*
X1145608Y450108D01*
X1151521D01*
X1155271Y453858D01*
X1159331D01*
X1162105Y456632D01*
Y458153D01*
X1162755Y458803D01*
X1164959D01*
X1165609Y459453D01*
Y460803D01*
X1164959Y461453D01*
X1162755D01*
X1162105Y462103D01*
Y463288D01*
X1173000Y474183D01*
Y488300D01*
X1172500Y488800D01*
Y492000D01*
X1170656Y493844D01*
G01X1129850Y445950D02*
X1145548Y461648D01*
X1149049D01*
X1161325Y473924D01*
X1161324Y474898D01*
X1160799Y475423D01*
Y476397D01*
X1161727Y477325D01*
X1162703D01*
X1163227Y476801D01*
X1164202D01*
X1165252Y477851D01*
Y485148D01*
X1162200Y488200D01*
Y494100D01*
X1163100Y495000D01*
Y496804D01*
X1161417Y498487D01*
G01X1170400Y438001D02*
Y439501D01*
X1176300Y445401D01*
Y447188D01*
X1171492Y451994D01*
Y453090D01*
X1172270Y453868D01*
X1173366D01*
X1176119Y451116D01*
X1177215D01*
X1177600Y451501D01*
Y465200D01*
X1184000Y471600D01*
Y485201D01*
X1182274Y486927D01*
Y497709D01*
X1181596Y498387D01*
X1180400D01*
G01X1202961Y464997D02*
Y441461D01*
X1188150Y426650D01*
X1186950D01*
G01X1188000Y423900D02*
X1191000D01*
X1205618Y438518D01*
Y466800D01*
X1210445Y471627D01*
Y489068D01*
X1212154Y490777D01*
Y494277D01*
X1210287Y496144D01*
X1208267D01*
G01X1165200Y438200D02*
Y439400D01*
X1159500Y445100D01*
Y448500D01*
X1172000Y461000D01*
Y467499D01*
X1176400Y471899D01*
Y489500D01*
X1176000Y489900D01*
Y496590D01*
X1174203Y498387D01*
G01X1167800Y437650D02*
Y440600D01*
X1162700Y445700D01*
Y448100D01*
X1164200Y449600D01*
X1165298D01*
X1168000Y446898D01*
X1169098D01*
X1169874Y447674D01*
Y448772D01*
X1167172Y451474D01*
Y452572D01*
X1174700Y460100D01*
Y466200D01*
X1179257Y470757D01*
Y487757D01*
X1179724Y488224D01*
Y491619D01*
X1177799Y493544D01*
G01X1180596Y428996D02*
X1197647Y446047D01*
Y474947D01*
X1200490Y477790D01*
Y483610D01*
X1198900Y485200D01*
Y493900D01*
X1199900Y494900D01*
Y496815D01*
X1198315Y498400D01*
X1198100D01*
G01X1121771Y368296D02*
X1124021D01*
G01X1121771Y376096D02*
X1124021D01*
G01X1131910Y374146D02*
X1134160D01*
G01X1118391Y370247D02*
X1120641D01*
G01X1118391Y374146D02*
X1120641D01*
G01X1130780Y368296D02*
X1128530D01*
G01X1130780Y376096D02*
X1128530D01*
G01X1124561Y450934D02*
X1142447Y468820D01*
X1144320D01*
X1154180Y478680D01*
Y493300D01*
X1152863Y494617D01*
X1152763D01*
X1151213Y496167D01*
X1151168D01*
G01X1177000Y435000D02*
X1190650Y448650D01*
Y466472D01*
G01X1125150Y370247D02*
X1127400D01*
G01X1125150Y378047D02*
X1127400D01*
G01X1123748Y451748D02*
X1141970Y469970D01*
X1143843D01*
X1145000Y471127D01*
Y472135D01*
X1145765Y472900D01*
X1146773D01*
X1147700Y473827D01*
Y474835D01*
X1148365Y475500D01*
X1149373D01*
X1150600Y476727D01*
Y477735D01*
X1151231Y478366D01*
X1152239D01*
X1153030Y479157D01*
Y492823D01*
X1152386Y493467D01*
X1151168D01*
G01X1187978Y493209D02*
X1189874Y491313D01*
Y481202D01*
X1189500Y480828D01*
Y449127D01*
X1186796Y446423D01*
X1186088D01*
X1185381Y445715D01*
Y445008D01*
X1184674Y444301D01*
X1183966D01*
X1183259Y443593D01*
Y442886D01*
X1182552Y442179D01*
X1181844D01*
X1181137Y441471D01*
Y440764D01*
X1180430Y440057D01*
X1179722D01*
X1179015Y439349D01*
Y438642D01*
X1178308Y437935D01*
X1177600D01*
X1177100Y437435D01*
X1176893Y437227D01*
Y436520D01*
X1176186Y435813D01*
G01X1125150Y366347D02*
X1127400D01*
G01X1126600Y446500D02*
X1144300Y464200D01*
X1147700D01*
X1157893Y474393D01*
Y479980D01*
X1158672Y480759D01*
X1160377D01*
X1161550Y481932D01*
Y485136D01*
X1160377Y486309D01*
X1158676D01*
X1158100Y486885D01*
Y488100D01*
X1159374Y489374D01*
Y493045D01*
X1156252Y496167D01*
G01X1180000Y432041D02*
X1194970Y447011D01*
Y474489D01*
G01X1125150Y374146D02*
X1127400D01*
G01X1101491Y368296D02*
X1103741D01*
G01X1101491Y376096D02*
X1103741D01*
G01X1111631Y370247D02*
X1113881D01*
G01X1111631Y374146D02*
X1113881D01*
G01X1098111Y370247D02*
X1100361D01*
G01X1098111Y374146D02*
X1100361D01*
G01X1108251Y368296D02*
X1110501D01*
G01X1108251Y376096D02*
X1110501D01*
G01X1101491Y356596D02*
X1103741D01*
G01X1101491Y360496D02*
X1103741D01*
G01X1098111Y354647D02*
X1100361D01*
G01X1098111Y362447D02*
X1100361D01*
G01X1111631Y354647D02*
X1113881D01*
G01X1111631Y362447D02*
X1113881D01*
G01X1121771Y356596D02*
X1124021D01*
G01X1121771Y360496D02*
X1124021D01*
G01X1108251Y356596D02*
X1110501D01*
G01X1108251Y360496D02*
X1110501D01*
G01X1118391Y354647D02*
X1120641D01*
G01X1118391Y362447D02*
X1120641D01*
G01X1104871Y370247D02*
X1107121D01*
G01X1115011Y356596D02*
X1117261D01*
G01X1104871Y378047D02*
X1107121D01*
G01X1115011Y364396D02*
X1117261D01*
G01X1104871Y366347D02*
X1107121D01*
G01X1115011Y352696D02*
X1117261D01*
G01X1104871Y374146D02*
X1107121D01*
G01X1115011Y360496D02*
X1117261D01*
G01X1133100Y445600D02*
X1145577Y458077D01*
X1146285D01*
X1146877Y457485D01*
Y455743D01*
X1147412Y455208D01*
X1149266D01*
X1149802Y455744D01*
Y458829D01*
X1151694Y460721D01*
X1153142D01*
X1154921Y458942D01*
X1155918D01*
X1156872Y459896D01*
Y460739D01*
X1155016Y462595D01*
Y463515D01*
X1167909Y476408D01*
Y486091D01*
X1166200Y487800D01*
Y491907D01*
X1164363Y493744D01*
G01X1172400Y436700D02*
X1181400Y445700D01*
Y463150D01*
X1182050Y463800D01*
X1183400D01*
X1184050Y463150D01*
Y456750D01*
X1184700Y456100D01*
X1186050D01*
X1186700Y456750D01*
Y488900D01*
X1186074Y489526D01*
Y492894D01*
X1185574Y493394D01*
X1184142D01*
G01X1125873Y447400D02*
X1126367Y447895D01*
Y448603D01*
X1126862Y449098D01*
X1127570D01*
X1128064Y449592D01*
Y450301D01*
X1128559Y450796D01*
X1129268D01*
X1129762Y451290D01*
Y451999D01*
X1130257Y452494D01*
X1130965D01*
X1131459Y452988D01*
Y453697D01*
X1131954Y454192D01*
X1132663D01*
X1133157Y454686D01*
Y455395D01*
X1133652Y455890D01*
X1134361D01*
X1134855Y456384D01*
Y457093D01*
X1135350Y457588D01*
X1136059D01*
X1136553Y458082D01*
Y458791D01*
X1137048Y459286D01*
X1137757D01*
X1138251Y459780D01*
Y460489D01*
X1138746Y460984D01*
X1139455D01*
X1139949Y461478D01*
Y462187D01*
X1140444Y462682D01*
X1141155D01*
X1141649Y463176D01*
Y463885D01*
X1142144Y464380D01*
X1142853D01*
X1143823Y465350D01*
X1147223D01*
X1148000Y466127D01*
Y467135D01*
X1148565Y467700D01*
X1149573D01*
X1150400Y468527D01*
Y469535D01*
X1150965Y470100D01*
X1151973D01*
X1152800Y470927D01*
Y471935D01*
X1153365Y472500D01*
X1154373D01*
X1156743Y474870D01*
Y475856D01*
X1156203Y476396D01*
Y477104D01*
X1156743Y477644D01*
Y480457D01*
X1158195Y481909D01*
X1159900D01*
X1160400Y482409D01*
Y484659D01*
X1159900Y485159D01*
X1158199D01*
X1156950Y486408D01*
Y488577D01*
X1158224Y489851D01*
Y492568D01*
X1157225Y493567D01*
X1156252D01*
G01X1179236Y432900D02*
X1179942Y433607D01*
Y434314D01*
X1180649Y435022D01*
X1181357D01*
X1182063Y435729D01*
Y436436D01*
X1182770Y437144D01*
X1183478D01*
X1184000Y437667D01*
X1184184Y437851D01*
Y438558D01*
X1184891Y439266D01*
X1185599D01*
X1186305Y439973D01*
Y440680D01*
X1187012Y441388D01*
X1187720D01*
X1188426Y442095D01*
Y442802D01*
X1189133Y443510D01*
X1189841D01*
X1190548Y444217D01*
X1190547Y444924D01*
X1191254Y445632D01*
X1191963D01*
X1193820Y447490D01*
Y450408D01*
X1193320Y450908D01*
Y451908D01*
X1193820Y452408D01*
Y453408D01*
X1193320Y453908D01*
Y454908D01*
X1193820Y455408D01*
Y456408D01*
X1193320Y456908D01*
Y457908D01*
X1193820Y458408D01*
Y459500D01*
X1193320Y460000D01*
Y461000D01*
X1193820Y461500D01*
Y462500D01*
X1193320Y463000D01*
Y464000D01*
X1193820Y464500D01*
Y465500D01*
X1193320Y466000D01*
Y467000D01*
X1193820Y467500D01*
Y468500D01*
X1193320Y469000D01*
Y470000D01*
X1193820Y470500D01*
Y471500D01*
X1193320Y472000D01*
Y473000D01*
X1193820Y473500D01*
Y474500D01*
X1193320Y475000D01*
Y476000D01*
X1193820Y476500D01*
Y478023D01*
X1194897Y479100D01*
X1196268D01*
X1196768Y479600D01*
Y481250D01*
X1196268Y481750D01*
X1195097D01*
X1193774Y483073D01*
Y485401D01*
X1195174Y486801D01*
Y487600D01*
X1194674Y488100D01*
Y489100D01*
X1195174Y489600D01*
Y492426D01*
X1194091Y493509D01*
X1193063D01*
G01X1107876Y523900D02*
X1107874Y523923D01*
Y528899D01*
G01X1131301Y523900D02*
X1131299Y523923D01*
Y528899D01*
G01X1101183Y523900D02*
X1101181Y523923D01*
Y528899D01*
G01X1124608Y523900D02*
X1124606Y523923D01*
Y528899D01*
G01X1144687Y523900D02*
X1144685Y523923D01*
Y528899D01*
G01X1137994Y523900D02*
X1137992Y523923D01*
Y528899D01*
G01X1117915Y523900D02*
X1117913Y523923D01*
Y526495D01*
X1116266Y528142D01*
Y529800D01*
X1116998Y530532D01*
Y531503D01*
X1116006Y532495D01*
X1115186D01*
X1114441Y531750D01*
X1114366D01*
G01X1154726Y523900D02*
X1154724Y523923D01*
Y526496D01*
X1153078Y528142D01*
Y529800D01*
X1153810Y530532D01*
Y531503D01*
X1152818Y532495D01*
X1151998D01*
X1151253Y531750D01*
X1151178D01*
G01X1114568Y523900D02*
X1114566Y523923D01*
Y526352D01*
X1112849Y528069D01*
X1112600Y528610D01*
X1112516Y528792D01*
Y532013D01*
X1112837Y532896D01*
X1114340Y534399D01*
G01X1151380Y523900D02*
X1151378Y523923D01*
Y526351D01*
X1149661Y528068D01*
X1149412Y528610D01*
X1149328Y528792D01*
Y532013D01*
X1149649Y532896D01*
X1151152Y534399D01*
G01X1111222Y542010D02*
X1111220Y542033D01*
X1110520Y534700D01*
G01X1134645Y535100D02*
Y536192D01*
X1135163Y536710D01*
Y537590D01*
X1134645Y538108D01*
Y542010D01*
X1134647D01*
G01X1104529D02*
X1104527D01*
Y536792D01*
X1104141Y534700D01*
G01X1127954Y542010D02*
X1127953D01*
Y538200D01*
X1128473Y537680D01*
Y536820D01*
X1127953Y536300D01*
Y535101D01*
X1127952Y535100D01*
G01X1148033Y542010D02*
X1148031Y542033D01*
X1147331Y534700D01*
G01X1141340Y542010D02*
X1141338D01*
Y536792D01*
X1140952Y534700D01*
G01X1119440Y534149D02*
X1118591Y533300D01*
X1117709D01*
X1116408Y534601D01*
Y536301D01*
X1117912Y537805D01*
Y542010D01*
X1117915D01*
G01X1154726D02*
X1154724D01*
Y537805D01*
X1153220Y536301D01*
Y534601D01*
X1154521Y533300D01*
X1155403D01*
X1156252Y534149D01*
G01X1119440Y531540D02*
X1120448D01*
X1121408Y532500D01*
Y537900D01*
X1121259Y538049D01*
Y542010D01*
X1121261D01*
G01X1158072D02*
X1158071D01*
Y538049D01*
X1158220Y537900D01*
Y532500D01*
X1157260Y531540D01*
X1156252D01*
G01X1111222Y579810D02*
X1111220Y579833D01*
X1110520Y572500D01*
G01X1107876Y561700D02*
X1107874Y561723D01*
Y566699D01*
G01X1134647Y579810D02*
X1134645D01*
Y575908D01*
X1135163Y575390D01*
Y574510D01*
X1134645Y573992D01*
Y572900D01*
G01X1131301Y561700D02*
X1131299Y561723D01*
Y566699D01*
G01X1104529Y579810D02*
X1104527D01*
Y574592D01*
X1104141Y572500D01*
G01X1101183Y561700D02*
X1101181Y561723D01*
Y566699D01*
G01X1127954Y579810D02*
X1127953D01*
Y576000D01*
X1128473Y575480D01*
Y574620D01*
X1127953Y574100D01*
Y572901D01*
X1127952Y572900D01*
G01X1124608Y561700D02*
X1124606Y561723D01*
Y566699D01*
G01X1148033Y579810D02*
X1148031Y579833D01*
X1147331Y572500D01*
G01X1144687Y561700D02*
X1144685Y561723D01*
Y566699D01*
G01X1141340Y579810D02*
X1141338D01*
Y574592D01*
X1140952Y572500D01*
G01X1137994Y561700D02*
X1137992Y561723D01*
Y566699D01*
G01X1117915Y561700D02*
X1117913Y561723D01*
Y564295D01*
X1116266Y565942D01*
Y567600D01*
X1116998Y568332D01*
Y569303D01*
X1116006Y570295D01*
X1115186D01*
X1114441Y569550D01*
X1114366D01*
G01X1154726Y561700D02*
X1154724Y561723D01*
Y564296D01*
X1153078Y565942D01*
Y567600D01*
X1153810Y568332D01*
Y569303D01*
X1152818Y570295D01*
X1151998D01*
X1151253Y569550D01*
X1151178D01*
G01X1117915Y579810D02*
X1117912D01*
Y575605D01*
X1116408Y574101D01*
Y572401D01*
X1117709Y571100D01*
X1118591D01*
X1119440Y571949D01*
G01X1154726Y579810D02*
X1154724D01*
Y575605D01*
X1153220Y574101D01*
Y572401D01*
X1154521Y571100D01*
X1155403D01*
X1156252Y571949D01*
G01X1114568Y561700D02*
X1114566Y561723D01*
Y564152D01*
X1112849Y565869D01*
X1112516Y566592D01*
Y569813D01*
X1112837Y570696D01*
X1114340Y572199D01*
G01X1151380Y561700D02*
X1151378Y561723D01*
Y564151D01*
X1149661Y565868D01*
X1149328Y566592D01*
Y569813D01*
X1149649Y570696D01*
X1151152Y572199D01*
G01X1119440Y569340D02*
X1120448D01*
X1121408Y570300D01*
Y575700D01*
X1121259Y575849D01*
Y579810D01*
X1121261D01*
G01X1158072D02*
X1158071D01*
Y575849D01*
X1158220Y575700D01*
Y570300D01*
X1157260Y569340D01*
X1156252D01*
G01X1111222Y617610D02*
X1111220Y617633D01*
X1110520Y610300D01*
G01X1107876Y599500D02*
X1107874Y599523D01*
Y604499D01*
G01X1134645Y610700D02*
Y611792D01*
X1135163Y612310D01*
Y613190D01*
X1134645Y613708D01*
Y617610D01*
X1134647D01*
G01X1131301Y599500D02*
X1131299Y599523D01*
Y604499D01*
G01X1104141Y610300D02*
X1104527Y612392D01*
Y617610D01*
X1104529D01*
G01X1101183Y599500D02*
X1101181Y599523D01*
Y604499D01*
G01X1127954Y617610D02*
X1127953D01*
Y613800D01*
X1128473Y613280D01*
Y612420D01*
X1127953Y611900D01*
Y610701D01*
X1127952Y610700D01*
G01X1124608Y599500D02*
X1124606Y599523D01*
Y604499D01*
G01X1148033Y617610D02*
X1148031Y617633D01*
X1147718Y614358D01*
X1147446Y611507D01*
X1147700Y611200D01*
G01X1144687Y599500D02*
X1144685Y599523D01*
Y604499D01*
G01X1141340Y617610D02*
X1141338D01*
Y611674D01*
X1141332Y611668D01*
G01X1137994Y599500D02*
X1137992Y599523D01*
Y604499D01*
G01X1117915Y599500D02*
X1117913Y599523D01*
Y602095D01*
X1116266Y603742D01*
Y605400D01*
X1116998Y606132D01*
Y607103D01*
X1116006Y608095D01*
X1115186D01*
X1114441Y607350D01*
X1114366D01*
G01X1154726Y599500D02*
X1154724Y599523D01*
Y602096D01*
X1153078Y603742D01*
Y605400D01*
X1153810Y606132D01*
Y607103D01*
X1152818Y608095D01*
X1151998D01*
X1151253Y607350D01*
X1151178D01*
G01X1117915Y617610D02*
X1117912D01*
Y613405D01*
X1116408Y611901D01*
Y610201D01*
X1117709Y608900D01*
X1118591D01*
X1119440Y609749D01*
G01X1154726Y617610D02*
X1154724D01*
Y613405D01*
X1153220Y611901D01*
Y610201D01*
X1154521Y608900D01*
X1155403D01*
X1156252Y609749D01*
G01X1114568Y599500D02*
X1114566Y599523D01*
Y601952D01*
X1112849Y603669D01*
X1112516Y604392D01*
Y607613D01*
X1112837Y608496D01*
X1114340Y609999D01*
G01X1151380Y599500D02*
X1151378Y599523D01*
Y601951D01*
X1149661Y603668D01*
X1149328Y604392D01*
Y607613D01*
X1149649Y608496D01*
X1151152Y609999D01*
G01X1121261Y617610D02*
X1121259D01*
Y613649D01*
X1121408Y613500D01*
Y608100D01*
X1120448Y607140D01*
X1119440D01*
G01X1158072Y617610D02*
X1158071D01*
Y613649D01*
X1158220Y613500D01*
Y608100D01*
X1157260Y607140D01*
X1156252D01*
G01X1168112Y22923D02*
X1168110D01*
Y27899D01*
G01X1161419Y22923D02*
X1161417D01*
Y27899D01*
G01X1181498Y22923D02*
X1181496D01*
Y27899D01*
G01X1204923Y22923D02*
X1204921D01*
Y27899D01*
G01X1174805Y22923D02*
X1174803D01*
Y27899D01*
G01X1198230Y22923D02*
X1198228D01*
Y27899D01*
G01X1218309Y22923D02*
X1218307D01*
Y27899D01*
G01X1211616Y22923D02*
X1211614D01*
Y27899D01*
G01X1187989Y30750D02*
X1188064D01*
X1188809Y31495D01*
X1189629D01*
X1190621Y30503D01*
Y29532D01*
X1189889Y28800D01*
Y27142D01*
X1191535Y25496D01*
Y22923D01*
X1191537D01*
G01Y41033D02*
X1191535D01*
Y36805D01*
X1190031Y35301D01*
Y33601D01*
X1191332Y32300D01*
X1192214D01*
X1193063Y33149D01*
G01X1188191Y22923D02*
X1188189D01*
Y25351D01*
X1186472Y27068D01*
X1186139Y27792D01*
Y31013D01*
X1186460Y31896D01*
X1187963Y33399D01*
G01X1193063Y30540D02*
X1194071D01*
X1195031Y31500D01*
Y36900D01*
X1194882Y37049D01*
Y41032D01*
X1194883Y41033D01*
G01X1171458Y3233D02*
X1171456D01*
Y-692D01*
X1171974Y-1210D01*
Y-2090D01*
X1171456Y-2608D01*
Y-3700D01*
G01X1168112Y-14877D02*
X1168110D01*
Y-9901D01*
G01X1164763Y-3700D02*
X1164764Y-3699D01*
Y-2500D01*
X1165284Y-1980D01*
Y-1120D01*
X1164764Y-600D01*
Y3232D01*
X1164765Y3233D01*
G01X1161419Y-14877D02*
X1161417D01*
Y-9901D01*
G01X1184844Y3233D02*
X1184842D01*
X1184142Y-4100D01*
G01X1181498Y-14877D02*
X1181496D01*
Y-9901D01*
G01X1208269Y3233D02*
X1208267D01*
Y-692D01*
X1208785Y-1210D01*
Y-2090D01*
X1208267Y-2608D01*
Y-3700D01*
G01X1204923Y-14877D02*
X1204921D01*
Y-9901D01*
G01X1178151Y3233D02*
X1178149D01*
Y-2008D01*
X1177763Y-4100D01*
G01X1174805Y-14877D02*
X1174803D01*
Y-9901D01*
G01X1201576Y3233D02*
X1201575Y3232D01*
Y-600D01*
X1202095Y-1120D01*
Y-1980D01*
X1201575Y-2500D01*
Y-3699D01*
X1201574Y-3700D01*
G01X1198230Y-14877D02*
X1198228D01*
Y-9901D01*
G01X1218309Y-14877D02*
X1218307D01*
Y-9901D01*
G01X1214962Y3233D02*
X1214960D01*
Y-2008D01*
X1214574Y-4100D01*
G01X1211616Y-14877D02*
X1211614D01*
Y-9901D01*
G01X1187989Y-7050D02*
X1188064D01*
X1188809Y-6305D01*
X1189629D01*
X1190621Y-7297D01*
Y-8268D01*
X1189889Y-9000D01*
Y-9914D01*
X1191535Y-11560D01*
Y-14877D01*
X1191537D01*
G01Y3233D02*
X1191535D01*
Y-755D01*
X1190489Y-1801D01*
Y-4686D01*
X1193063Y-7260D01*
G01X1188191Y-14877D02*
X1188189D01*
Y-12449D01*
X1186472Y-10732D01*
X1186139Y-10008D01*
Y-6787D01*
X1186460Y-5904D01*
X1187963Y-4401D01*
G01X1193063Y-4651D02*
X1194141Y-5729D01*
X1194912D01*
X1195754Y-4887D01*
Y-1965D01*
X1194881Y-1092D01*
Y3233D01*
X1194883D01*
G01X1171458Y78833D02*
X1171456D01*
Y74908D01*
X1171974Y74390D01*
Y73510D01*
X1171456Y72992D01*
Y71900D01*
G01X1168112Y60723D02*
X1168110D01*
Y65699D01*
G01X1164763Y71900D02*
X1164764Y71901D01*
Y73100D01*
X1165284Y73620D01*
Y74480D01*
X1164764Y75000D01*
Y78832D01*
X1164765Y78833D01*
G01X1161419Y60723D02*
X1161417D01*
Y65699D01*
G01X1184844Y78833D02*
X1184842D01*
X1184524Y75500D01*
X1184142Y71500D01*
G01X1181498Y60723D02*
X1181496D01*
Y65699D01*
G01X1208269Y78833D02*
X1208267D01*
Y74908D01*
X1208785Y74390D01*
Y73510D01*
X1208267Y72992D01*
Y71900D01*
G01X1204923Y60723D02*
X1204921D01*
Y65699D01*
G01X1178151Y78833D02*
X1178149D01*
Y73592D01*
X1177763Y71500D01*
G01X1174805Y60723D02*
X1174803D01*
Y65699D01*
G01X1201574Y71900D02*
X1201575Y71901D01*
Y73100D01*
X1202095Y73620D01*
Y74480D01*
X1201575Y75000D01*
Y78832D01*
X1201576Y78833D01*
G01X1198230Y60723D02*
X1198228D01*
Y65699D01*
G01X1218309Y60723D02*
X1218307D01*
Y65699D01*
G01X1214962Y78833D02*
X1214960D01*
Y73592D01*
X1214574Y71500D01*
G01X1211616Y60723D02*
X1211614D01*
Y65699D01*
G01X1187989Y68550D02*
X1188064D01*
X1188809Y69295D01*
X1189629D01*
X1190621Y68303D01*
Y67332D01*
X1189889Y66600D01*
Y64942D01*
X1191535Y63296D01*
Y60723D01*
X1191537D01*
G01Y78833D02*
X1191535D01*
Y74605D01*
X1190031Y73101D01*
Y71401D01*
X1191332Y70100D01*
X1192214D01*
X1193063Y70949D01*
G01X1188191Y60723D02*
X1188189D01*
Y63151D01*
X1186472Y64868D01*
X1186139Y65592D01*
Y68813D01*
X1186460Y69696D01*
X1187963Y71199D01*
G01X1193063Y68340D02*
X1194071D01*
X1195031Y69300D01*
Y74700D01*
X1194882Y74849D01*
Y78832D01*
X1194883Y78833D01*
G01X1171458Y41033D02*
X1171456D01*
Y37108D01*
X1171974Y36590D01*
Y35710D01*
X1171456Y35192D01*
Y34100D01*
G01X1164763D02*
X1164764Y34101D01*
Y35300D01*
X1165284Y35820D01*
Y36680D01*
X1164764Y37200D01*
Y41032D01*
X1164765Y41033D01*
G01X1184844D02*
X1184842D01*
X1184266Y35000D01*
X1184218Y34500D01*
X1184142Y33700D01*
G01X1208269Y41033D02*
X1208267D01*
Y37108D01*
X1208785Y36590D01*
Y35710D01*
X1208267Y35192D01*
Y34100D01*
G01X1178151Y41033D02*
X1178149D01*
Y35792D01*
X1178003Y35000D01*
X1177911Y34500D01*
X1177763Y33700D01*
G01X1201574Y34100D02*
X1201575Y34101D01*
Y35300D01*
X1202095Y35820D01*
Y36680D01*
X1201575Y37200D01*
Y41032D01*
X1201576Y41033D01*
G01X1214962D02*
X1214960D01*
Y35792D01*
X1214814Y35000D01*
X1214722Y34500D01*
X1214574Y33700D01*
G01X1166050Y130500D02*
Y128823D01*
X1165400Y128173D01*
X1164450D01*
X1163800Y127523D01*
Y126150D01*
X1164450Y125500D01*
X1167275D01*
X1167925Y124850D01*
Y122549D01*
X1167275Y121899D01*
X1164750D01*
X1164100Y121249D01*
Y119899D01*
X1164750Y119249D01*
X1167275D01*
X1167925Y118599D01*
Y112357D01*
G01X1170660Y117000D02*
Y112360D01*
X1172700Y110320D01*
Y108943D01*
X1170721Y106964D01*
G01X1158500Y122500D02*
Y117800D01*
X1161632Y114668D01*
Y112357D01*
G01X1161100Y133000D02*
Y119299D01*
X1164289Y116110D01*
Y112337D01*
X1162300Y110348D01*
Y107600D01*
X1162936Y106964D01*
X1164428D01*
G01X1184142D02*
Y104092D01*
X1182250Y102200D01*
X1179750D01*
X1179100Y102850D01*
Y105400D01*
X1181300Y107600D01*
Y109500D01*
X1183300Y111500D01*
Y113200D01*
X1182811Y113689D01*
Y119500D01*
G01X1207300Y133500D02*
Y130399D01*
X1208299Y129400D01*
Y122900D01*
X1207799Y122400D01*
X1206259D01*
X1205759Y122900D01*
Y126200D01*
X1205259Y126700D01*
X1203857D01*
X1203219Y126062D01*
Y114059D01*
X1204921Y112357D01*
G01X1209819Y140500D02*
Y131443D01*
X1210818Y130444D01*
Y120201D01*
X1207000Y116383D01*
Y111701D01*
X1205500Y110201D01*
Y108442D01*
X1206628Y107314D01*
X1208267D01*
G01X1174742Y112357D02*
X1174000Y113099D01*
Y132500D01*
G01X1177849Y107314D02*
X1175874Y109289D01*
Y110574D01*
X1177581Y112281D01*
Y114719D01*
X1176519Y115781D01*
Y125000D01*
G01X1196936Y120500D02*
Y115265D01*
X1198228Y113973D01*
Y112357D01*
G01X1204755Y139000D02*
Y131355D01*
X1200700Y127300D01*
Y111800D01*
X1199779Y110879D01*
Y109109D01*
X1201574Y107314D01*
G01X1190600Y141000D02*
Y139023D01*
X1188269Y136692D01*
Y133458D01*
X1190600Y131127D01*
Y129275D01*
X1189225Y127900D01*
X1187182D01*
X1186480Y127198D01*
Y125452D01*
X1187182Y124750D01*
X1189325D01*
X1190700Y123375D01*
Y120918D01*
X1189325Y119543D01*
X1186980D01*
X1186480Y119043D01*
Y115820D01*
X1187300Y115000D01*
X1189299D01*
X1189756Y114543D01*
Y112307D01*
X1187963Y110514D01*
G01X1193267Y126500D02*
Y119922D01*
X1191314Y117969D01*
Y109404D01*
X1193063Y107655D01*
G01X1187119Y135500D02*
Y132981D01*
X1189450Y130650D01*
Y129752D01*
X1188748Y129050D01*
X1186705D01*
X1185330Y127675D01*
Y124975D01*
X1186705Y123600D01*
X1188848D01*
X1189550Y122898D01*
Y121395D01*
X1188848Y120693D01*
X1186503D01*
X1185330Y119520D01*
Y115343D01*
X1186000Y114673D01*
Y109854D01*
X1187989Y107865D01*
G01X1194417Y135000D02*
Y119445D01*
X1192464Y117492D01*
Y116036D01*
X1194900Y113600D01*
Y111061D01*
X1194103Y110264D01*
X1193089D01*
G01X1182850Y427082D02*
X1185168Y429400D01*
X1186700D01*
X1187825Y430525D01*
Y432225D01*
X1188849Y433249D01*
X1190549D01*
X1191573Y434273D01*
Y435973D01*
X1192597Y436997D01*
X1194297D01*
X1195321Y438021D01*
Y439721D01*
X1196345Y440745D01*
X1198045D01*
X1200304Y443004D01*
Y471904D01*
X1201128Y472728D01*
X1203728D01*
X1205259Y474259D01*
Y475834D01*
X1204481Y476612D01*
X1203716D01*
X1203066Y477262D01*
Y479202D01*
X1203716Y479852D01*
X1204481D01*
X1205131Y480502D01*
Y488019D01*
X1204630Y488520D01*
X1204500D01*
X1204000Y489020D01*
Y492844D01*
X1203500Y493344D01*
X1200974D01*
G01X1168112Y523900D02*
X1168110Y523923D01*
Y528899D01*
G01X1161419Y523900D02*
X1161417Y523923D01*
Y528899D01*
G01X1181498Y523900D02*
X1181496Y523923D01*
Y528899D01*
G01X1204923Y523900D02*
X1204921Y523923D01*
Y528899D01*
G01X1174805Y523900D02*
X1174803Y523923D01*
Y528899D01*
G01X1198230Y523900D02*
X1198228Y523923D01*
Y528899D01*
G01X1218309Y523900D02*
X1218307Y523923D01*
Y528899D01*
G01X1211616Y523900D02*
X1211614Y523923D01*
Y528899D01*
G01X1191537Y523900D02*
X1191535Y523923D01*
Y526496D01*
X1189889Y528142D01*
Y529800D01*
X1190621Y530532D01*
Y531503D01*
X1189629Y532495D01*
X1188809D01*
X1188064Y531750D01*
X1187989D01*
G01X1188191Y523900D02*
X1188189Y523923D01*
Y526351D01*
X1186472Y528068D01*
X1186223Y528610D01*
X1186139Y528792D01*
Y532013D01*
X1186460Y532896D01*
X1187963Y534399D01*
G01X1202961Y464997D02*
Y468161D01*
X1207788Y472988D01*
Y491038D01*
X1206400Y492426D01*
Y496608D01*
X1204521Y498487D01*
X1204400D01*
G01X1190650Y466472D02*
Y480351D01*
X1191024Y480725D01*
Y491790D01*
X1189874Y492940D01*
Y494013D01*
X1187978Y495909D01*
G01X1194970Y474489D02*
Y477546D01*
X1195374Y477950D01*
X1196745D01*
X1197918Y479123D01*
Y481727D01*
X1196745Y482900D01*
X1195574D01*
X1194924Y483550D01*
Y484924D01*
X1196324Y486324D01*
Y492920D01*
X1193063Y496181D01*
Y496209D01*
G01X1171458Y542010D02*
X1171456D01*
Y538108D01*
X1171974Y537590D01*
Y536710D01*
X1171456Y536192D01*
Y535100D01*
G01X1164765Y542010D02*
X1164764D01*
Y538200D01*
X1165284Y537680D01*
Y536820D01*
X1164764Y536300D01*
Y535101D01*
X1164763Y535100D01*
G01X1184844Y542010D02*
X1184842Y542033D01*
X1184142Y534700D01*
G01X1208269Y542010D02*
X1208267D01*
Y538108D01*
X1208785Y537590D01*
Y536710D01*
X1208267Y536192D01*
Y535100D01*
G01X1178151Y542010D02*
X1178149D01*
Y536792D01*
X1177763Y534700D01*
G01X1201576Y542010D02*
X1201575D01*
Y538200D01*
X1202095Y537680D01*
Y536820D01*
X1201575Y536300D01*
Y535101D01*
X1201574Y535100D01*
G01X1214962Y542010D02*
X1214960D01*
Y536792D01*
X1214574Y534700D01*
G01X1191537Y542010D02*
X1191535D01*
Y537805D01*
X1190031Y536301D01*
Y534601D01*
X1191332Y533300D01*
X1192214D01*
X1193063Y534149D01*
G01X1194883Y542010D02*
X1194882D01*
Y538049D01*
X1195031Y537900D01*
Y532500D01*
X1194071Y531540D01*
X1193063D01*
G01X1171458Y579810D02*
X1171456D01*
Y575908D01*
X1171974Y575390D01*
Y574510D01*
X1171456Y573992D01*
Y572900D01*
G01X1168112Y561700D02*
X1168110Y561723D01*
Y566699D01*
G01X1164765Y579810D02*
X1164764D01*
Y576000D01*
X1165284Y575480D01*
Y574620D01*
X1164764Y574100D01*
Y572901D01*
X1164763Y572900D01*
G01X1161419Y561700D02*
X1161417Y561723D01*
Y566699D01*
G01X1184844Y579810D02*
X1184842Y579833D01*
X1184142Y572500D01*
G01X1181498Y561700D02*
X1181496Y561723D01*
Y566699D01*
G01X1208269Y579810D02*
X1208267D01*
Y575908D01*
X1208785Y575390D01*
Y574510D01*
X1208267Y573992D01*
Y572900D01*
G01X1204923Y561700D02*
X1204921Y561723D01*
Y566699D01*
G01X1177763Y572500D02*
X1178149Y574592D01*
Y579810D01*
X1178151D01*
G01X1174805Y561700D02*
X1174803Y561723D01*
Y566699D01*
G01X1201576Y579810D02*
X1201575D01*
Y576000D01*
X1202095Y575480D01*
Y574620D01*
X1201575Y574100D01*
Y572901D01*
X1201574Y572900D01*
G01X1198230Y561700D02*
X1198228Y561723D01*
Y566699D01*
G01X1218309Y561700D02*
X1218307Y561723D01*
Y566699D01*
G01X1214962Y579810D02*
X1214960D01*
Y574592D01*
X1214574Y572500D01*
G01X1211616Y561700D02*
X1211614Y561723D01*
Y566699D01*
G01X1191537Y561700D02*
X1191535Y561723D01*
Y564296D01*
X1189889Y565942D01*
Y567600D01*
X1190621Y568332D01*
Y569303D01*
X1189629Y570295D01*
X1188809D01*
X1188064Y569550D01*
X1187989D01*
G01X1191537Y579810D02*
X1191535D01*
Y575605D01*
X1190031Y574101D01*
Y572401D01*
X1191332Y571100D01*
X1192214D01*
X1193063Y571949D01*
G01X1188191Y561700D02*
X1188189Y561723D01*
Y564151D01*
X1186472Y565868D01*
X1186139Y566592D01*
Y569813D01*
X1186460Y570696D01*
X1187963Y572199D01*
G01X1194883Y579810D02*
X1194882D01*
Y575849D01*
X1195031Y575700D01*
Y570300D01*
X1194071Y569340D01*
X1193063D01*
G01X1171458Y617610D02*
X1171456D01*
Y613708D01*
X1171974Y613190D01*
Y612310D01*
X1171456Y611792D01*
Y610700D01*
G01X1168112Y599500D02*
X1168110Y599523D01*
Y604499D01*
G01X1164765Y617610D02*
X1164764D01*
Y613800D01*
X1165284Y613280D01*
Y612420D01*
X1164764Y611900D01*
Y610701D01*
X1164763Y610700D01*
G01X1161419Y599500D02*
X1161417Y599523D01*
Y604499D01*
G01X1184844Y617610D02*
X1184842Y617633D01*
X1184529Y614358D01*
X1184142Y610300D01*
G01X1181498Y599500D02*
X1181496Y599523D01*
Y604499D01*
G01X1208267Y610700D02*
Y611792D01*
X1208785Y612310D01*
Y613190D01*
X1208267Y613708D01*
Y617610D01*
X1208269D01*
G01X1204923Y599500D02*
X1204921Y599523D01*
Y604499D01*
G01X1178151Y617610D02*
X1178149D01*
Y612392D01*
X1177763Y610300D01*
G01X1174805Y599500D02*
X1174803Y599523D01*
Y604499D01*
G01X1201574Y610700D02*
X1201575Y610701D01*
Y611900D01*
X1202095Y612420D01*
Y613280D01*
X1201575Y613800D01*
Y617610D01*
X1201576D01*
G01X1198230Y599500D02*
X1198228Y599523D01*
Y604499D01*
G01X1218309Y599500D02*
X1218307Y599523D01*
Y604499D01*
G01X1214574Y610300D02*
X1214960Y612392D01*
Y617610D01*
X1214962D01*
G01X1211616Y599500D02*
X1211614Y599523D01*
Y604499D01*
G01X1191537Y599500D02*
X1191535Y599523D01*
Y602096D01*
X1189889Y603742D01*
Y605400D01*
X1190621Y606132D01*
Y607103D01*
X1189629Y608095D01*
X1188809D01*
X1188064Y607350D01*
X1187989D01*
G01X1191537Y617610D02*
X1191535D01*
Y613405D01*
X1190031Y611901D01*
Y610201D01*
X1191332Y608900D01*
X1192214D01*
X1193063Y609749D01*
G01X1188191Y599500D02*
X1188189Y599523D01*
Y601951D01*
X1186472Y603668D01*
X1186139Y604392D01*
Y607613D01*
X1186460Y608496D01*
X1187963Y609999D01*
G01X1194883Y617610D02*
X1194882D01*
Y613649D01*
X1195031Y613500D01*
Y608100D01*
X1194071Y607140D01*
X1193063D01*
G01X1241734Y22923D02*
X1241732D01*
Y27899D01*
G01X1235041Y22923D02*
X1235039D01*
Y27899D01*
G01X1224800Y30750D02*
X1224875D01*
X1225620Y31495D01*
X1226440D01*
X1227432Y30503D01*
Y29532D01*
X1226700Y28800D01*
Y27886D01*
X1228346Y26240D01*
Y22923D01*
X1228348D01*
G01X1229874Y30540D02*
X1227300Y33114D01*
Y35999D01*
X1228346Y37045D01*
Y41033D01*
X1228348D01*
G01X1225002Y22923D02*
X1225000D01*
Y25351D01*
X1223283Y27068D01*
X1222950Y27792D01*
Y31013D01*
X1223271Y31896D01*
X1224774Y33399D01*
G01X1229874Y33149D02*
X1230952Y32071D01*
X1231723D01*
X1232565Y32913D01*
Y35835D01*
X1231692Y36708D01*
Y41033D01*
X1231694D01*
G01X1221655Y3233D02*
X1221653D01*
X1220953Y-4100D01*
G01X1245080Y3233D02*
X1245078D01*
Y-692D01*
X1245596Y-1210D01*
Y-2090D01*
X1245078Y-2608D01*
Y-3700D01*
G01X1241734Y-14877D02*
X1241732D01*
Y-9901D01*
G01X1238387Y3233D02*
X1238386Y3232D01*
Y-600D01*
X1238906Y-1120D01*
Y-1980D01*
X1238386Y-2500D01*
Y-3699D01*
X1238385Y-3700D01*
G01X1235041Y-14877D02*
X1235039D01*
Y-9901D01*
G01X1224800Y-7050D02*
X1224875D01*
X1225620Y-6305D01*
X1226440D01*
X1227432Y-7297D01*
Y-8268D01*
X1226700Y-9000D01*
Y-9914D01*
X1228346Y-11560D01*
Y-14877D01*
X1228348D01*
G01X1229874Y-7260D02*
X1227300Y-4686D01*
Y-1801D01*
X1228346Y-755D01*
Y3233D01*
X1228348D01*
G01X1225002Y-14877D02*
X1225000D01*
Y-12449D01*
X1223283Y-10732D01*
X1222950Y-10008D01*
Y-6787D01*
X1223271Y-5904D01*
X1224774Y-4401D01*
G01X1229874Y-4651D02*
X1230952Y-5729D01*
X1231723D01*
X1232565Y-4887D01*
Y-1965D01*
X1231692Y-1092D01*
Y3233D01*
X1231694D01*
G01X1221655Y78833D02*
X1221653D01*
X1221335Y75500D01*
X1220953Y71500D01*
G01X1245080Y78833D02*
Y74910D01*
X1245078Y74908D01*
X1245596Y74390D01*
Y73510D01*
X1245078Y72992D01*
Y71900D01*
G01X1241734Y60723D02*
Y65697D01*
X1241732Y65699D01*
G01X1238385Y71900D02*
X1238386Y71901D01*
Y73100D01*
X1238906Y73620D01*
Y74480D01*
X1238386Y75000D01*
Y78832D01*
X1238387Y78833D01*
G01X1235041Y60723D02*
Y65697D01*
X1235039Y65699D01*
G01X1224800Y68550D02*
X1224875D01*
X1225620Y69295D01*
X1226440D01*
X1227432Y68303D01*
Y67332D01*
X1226700Y66600D01*
Y64942D01*
X1228346Y63296D01*
Y60723D01*
X1228348D01*
G01X1229874Y70949D02*
X1229025Y70100D01*
X1228143D01*
X1226842Y71401D01*
Y73101D01*
X1228346Y74605D01*
Y78833D01*
X1228348D01*
G01X1225002Y60723D02*
X1225000D01*
Y63151D01*
X1223283Y64868D01*
X1222950Y65592D01*
Y68813D01*
X1223271Y69696D01*
X1224774Y71199D01*
G01X1229874Y68340D02*
X1230882D01*
X1231842Y69300D01*
Y74700D01*
X1231693Y74849D01*
Y78832D01*
X1231694Y78833D01*
G01X1221655Y41033D02*
X1221653D01*
X1221077Y35000D01*
X1221029Y34500D01*
X1220953Y33700D01*
G01X1245080Y41033D02*
X1245078D01*
Y37108D01*
X1245596Y36590D01*
Y35710D01*
X1245078Y35192D01*
Y34100D01*
G01X1238385D02*
X1238386Y34101D01*
Y35300D01*
X1238906Y35820D01*
Y36680D01*
X1238386Y37200D01*
Y41032D01*
X1238387Y41033D01*
G01X1241734Y523900D02*
Y528897D01*
X1241732Y528899D01*
G01X1235041Y523900D02*
X1235039Y523923D01*
Y528899D01*
G01X1228348Y523900D02*
X1228346Y523923D01*
Y526496D01*
X1226700Y528142D01*
Y529800D01*
X1227432Y530532D01*
Y531503D01*
X1226440Y532495D01*
X1225620D01*
X1224875Y531750D01*
X1224800D01*
G01X1225002Y523900D02*
X1225000Y523923D01*
Y526351D01*
X1223283Y528068D01*
X1223034Y528610D01*
X1222950Y528792D01*
Y532013D01*
X1223271Y532896D01*
X1224774Y534399D01*
G01X1221655Y542010D02*
X1221653Y542033D01*
X1220953Y534700D01*
G01X1245080Y542010D02*
Y538110D01*
X1245078Y538108D01*
X1245596Y537590D01*
Y536710D01*
X1245078Y536192D01*
Y535100D01*
G01X1238387Y542010D02*
X1238386D01*
Y538200D01*
X1238906Y537680D01*
Y536820D01*
X1238386Y536300D01*
Y535101D01*
X1238385Y535100D01*
G01X1228348Y542010D02*
X1228346D01*
Y537805D01*
X1226842Y536301D01*
Y534601D01*
X1228143Y533300D01*
X1229025D01*
X1229874Y534149D01*
G01X1231694Y542010D02*
X1231693D01*
Y538049D01*
X1231842Y537900D01*
Y532500D01*
X1230882Y531540D01*
X1229874D01*
G01X1221655Y579810D02*
X1221653Y579833D01*
X1220953Y572500D01*
G01X1245078Y572900D02*
Y573992D01*
X1245596Y574510D01*
Y575390D01*
X1245078Y575908D01*
Y579810D01*
X1245080D01*
G01X1241734Y561700D02*
X1241732Y561723D01*
Y566699D01*
G01X1238387Y579810D02*
X1238386D01*
Y576000D01*
X1238906Y575480D01*
Y574620D01*
X1238386Y574100D01*
Y572901D01*
X1238385Y572900D01*
G01X1235041Y561700D02*
X1235039Y561723D01*
Y566699D01*
G01X1228348Y561700D02*
X1228346Y561723D01*
Y564296D01*
X1226700Y565942D01*
Y567600D01*
X1227432Y568332D01*
Y569303D01*
X1226440Y570295D01*
X1225620D01*
X1224875Y569550D01*
X1224800D01*
G01X1228348Y579810D02*
X1228346D01*
Y575605D01*
X1226842Y574101D01*
Y572401D01*
X1228143Y571100D01*
X1229025D01*
X1229874Y571949D01*
G01X1225002Y561700D02*
X1225000Y561723D01*
Y564151D01*
X1223283Y565868D01*
X1222950Y566592D01*
Y569813D01*
X1223271Y570696D01*
X1224774Y572199D01*
G01X1231694Y579810D02*
X1231693D01*
Y575849D01*
X1231842Y575700D01*
Y570300D01*
X1230882Y569340D01*
X1229874D01*
G01X1221655Y617610D02*
X1221653Y617633D01*
X1221340Y614358D01*
X1220953Y610300D01*
G01X1245080Y617610D02*
X1245078D01*
Y613708D01*
X1245596Y613190D01*
Y612310D01*
X1245078Y611792D01*
Y610700D01*
G01X1241734Y599500D02*
X1241732Y599523D01*
Y604499D01*
G01X1238385Y610700D02*
X1238386Y610701D01*
Y611900D01*
X1238906Y612420D01*
Y613280D01*
X1238386Y613800D01*
Y617610D01*
X1238387D01*
G01X1235041Y599500D02*
X1235039Y599523D01*
Y604499D01*
G01X1228348Y599500D02*
X1228346Y599523D01*
Y602096D01*
X1226700Y603742D01*
Y605400D01*
X1227432Y606132D01*
Y607103D01*
X1226440Y608095D01*
X1225620D01*
X1224875Y607350D01*
X1224800D01*
G01X1228348Y617610D02*
X1228346D01*
Y613405D01*
X1226842Y611901D01*
Y610201D01*
X1228143Y608900D01*
X1229025D01*
X1229874Y609749D01*
G01X1225002Y599500D02*
X1225000Y599523D01*
Y601951D01*
X1223283Y603668D01*
X1222950Y604392D01*
Y607613D01*
X1223271Y608496D01*
X1224774Y609999D01*
G01X1231694Y617610D02*
X1231693D01*
Y613649D01*
X1231842Y613500D01*
Y608100D01*
X1230882Y607140D01*
X1229874D01*
G54D353*
G01X1547975Y459540D02*
X1549925Y460446D01*
G01X1563575Y446020D02*
X1564844Y446610D01*
X1565192Y446771D01*
X1565525Y446926D01*
G01X1536275Y466300D02*
X1538212Y467200D01*
X1538225Y467206D01*
G54D272*
X1707500Y121230D03*
G54D35*
X24054Y21862D03*
X24143Y52374D03*
X19400Y562500D03*
X14700Y529100D03*
X138100Y208300D03*
X141900Y272900D03*
X138100Y241000D03*
X138800Y306100D03*
X140609Y337400D03*
X138410Y369674D03*
X786982Y368417D03*
X790099Y207600D03*
X793551Y240966D03*
X792787Y272898D03*
X790200Y336400D03*
X791970Y305000D03*
G54D62*
X28870Y503685D03*
X1377504Y62065D03*
X1776900Y86600D03*
G54D254*
X1567064Y522361D03*
X1576796Y523311D03*
X1572495Y598000D03*
G54D218*
X1421619Y461733D03*
X1412123Y465283D03*
G54D164*
X722567Y397000D03*
X741433D03*
G54D44*
X14487Y33945D03*
X14812Y65312D03*
X4387Y540601D03*
Y576601D03*
X128511Y221134D03*
Y253134D03*
Y285134D03*
Y317134D03*
Y349134D03*
Y381134D03*
X703613Y217399D03*
X778119Y221134D03*
Y253134D03*
Y317134D03*
Y285134D03*
Y349134D03*
X778069Y381134D03*
X1368702Y-3425D03*
X1369013Y28599D03*
X1371320Y387467D03*
X1373013Y575455D03*
Y606655D03*
G54D317*
X1887327Y532541D03*
X1929453Y511202D03*
G54D173*
X1265488Y322910D03*
X1264182Y315862D03*
X1260234Y328907D03*
X1251491Y327228D03*
G54D119*
X348000Y13200D03*
X353500D03*
X343142D03*
X337642D03*
X330142D03*
X324642D03*
X317942D03*
X312442D03*
X348000Y51000D03*
X353500D03*
X343142D03*
X337642D03*
X330142D03*
X324642D03*
X317942D03*
X312442D03*
X307693Y495595D03*
X313193D03*
X348000Y552000D03*
X353500D03*
X343142D03*
X337642D03*
X330142D03*
X324642D03*
X317872D03*
X312372D03*
X348000Y589800D03*
X353500D03*
X343142D03*
X337642D03*
X330142D03*
X324642D03*
X317942D03*
X312442D03*
X360792Y13078D03*
X366292D03*
X411650Y13200D03*
X417150D03*
X399200D03*
X404700D03*
X361178Y50492D03*
X366678D03*
X411650Y51000D03*
X417150D03*
X399200D03*
X404700D03*
X360292Y589800D03*
X365792D03*
X411650Y552000D03*
X417150D03*
X399200D03*
X404700D03*
X366692D03*
X361192D03*
X411650Y589800D03*
X417150D03*
X399200D03*
X404700D03*
X437008Y13200D03*
X442508D03*
X424650D03*
X430150D03*
X437008Y51000D03*
X442508D03*
X424650D03*
X430150D03*
X437008Y552000D03*
X442508D03*
X424650D03*
X430150D03*
X437008Y589800D03*
X442508D03*
X424650D03*
X430150D03*
X967550Y13200D03*
X962050D03*
X967550Y51000D03*
X962050D03*
X957301Y495595D03*
X962801D03*
X967450Y552000D03*
X961950D03*
X967450Y589800D03*
X961950D03*
X1010400Y13078D03*
X1015900D03*
X997608Y13200D03*
X1003108D03*
X992750D03*
X987250D03*
X979750D03*
X974250D03*
X1010900Y50800D03*
X1016400D03*
X997608Y51000D03*
X1003108D03*
X992750D03*
X987250D03*
X979750D03*
X974250D03*
X1009700Y589500D03*
X1015200D03*
X1016000Y551700D03*
X1010500D03*
X997608Y552000D03*
X1003108D03*
X992750D03*
X987250D03*
X979850D03*
X974350D03*
X997608Y589800D03*
X1003108D03*
X992750D03*
X987250D03*
X979750D03*
X974250D03*
X1086616Y13200D03*
X1092116D03*
X1074258D03*
X1079758D03*
X1061258D03*
X1066758D03*
X1048808D03*
X1054308D03*
X1086616Y51000D03*
X1092116D03*
X1074258D03*
X1079758D03*
X1061258D03*
X1066758D03*
X1048808D03*
X1054308D03*
X1086616Y552000D03*
X1092116D03*
X1074258D03*
X1079758D03*
X1061258D03*
X1066758D03*
X1048808D03*
X1054308D03*
X1086616Y589800D03*
X1092116D03*
X1074258D03*
X1079758D03*
X1061258D03*
X1066758D03*
X1048808D03*
X1054308D03*
G54D182*
X1247619Y353586D03*
G54D344*
X1965132Y477599D03*
X1973450D03*
X1965132Y506339D03*
X1973450D03*
G54D53*
X18228Y178386D03*
X-1969D03*
G54D146*
X724937Y-652D03*
X722968D03*
X721000D03*
X719031D03*
X717063D03*
Y10652D03*
X719031D03*
X721000D03*
X722968D03*
X724937D03*
X723980Y584050D03*
X722012D03*
X720043D03*
X718075D03*
X716106D03*
Y595354D03*
X718075D03*
X720043D03*
X722012D03*
X723980D03*
X1587610Y582396D03*
X1585641D03*
X1583673D03*
X1581704D03*
Y593700D03*
X1583673D03*
X1585641D03*
X1587610D03*
X1589578Y582396D03*
Y593700D03*
X1850700Y150348D03*
X1848732D03*
X1846763D03*
X1854637D03*
X1852669D03*
X1848732Y161652D03*
X1850700D03*
X1852669D03*
X1846763D03*
X1854637D03*
G54D80*
X72900Y168118D03*
X79900Y165559D03*
Y163000D03*
X72900D03*
X79900Y168118D03*
X104250Y327382D03*
X97250Y332500D03*
Y329941D03*
X104250Y332500D03*
X97250Y327382D03*
X652230Y485130D03*
Y487690D03*
X645230Y485130D03*
Y490250D03*
Y487690D03*
X652230Y490250D03*
X685268Y288147D03*
Y290706D03*
Y285588D03*
X678268D03*
Y288147D03*
Y290706D03*
X1446800Y368018D03*
X1453800Y362900D03*
Y365459D03*
X1446800Y362900D03*
X1453800Y368018D03*
X1528513Y322534D03*
X1521513Y325093D03*
Y327652D03*
X1528513D03*
X1521513Y322534D03*
X1646378Y202515D03*
Y205074D03*
X1639378Y202515D03*
Y207633D03*
Y205074D03*
X1646378Y207633D03*
X1649500Y329059D03*
Y326500D03*
Y323941D03*
Y318559D03*
Y313441D03*
X1656500Y323941D03*
Y329059D03*
Y316000D03*
Y318559D03*
Y313441D03*
X1737814Y576682D03*
Y571564D03*
X1730814D03*
Y574123D03*
Y576682D03*
X1828874Y-5980D03*
Y-8540D03*
X1835874Y-5980D03*
Y-11100D03*
Y-8540D03*
X1828874Y-11100D03*
X1793000Y130059D03*
X1800000Y127500D03*
X1793000Y124941D03*
X1800000Y130059D03*
Y124941D03*
X1788500Y620500D03*
X1795500D03*
X1788500Y617941D03*
X1795500Y615382D03*
X1788500D03*
X1795500Y617941D03*
X1911000Y546341D03*
Y548900D03*
Y543782D03*
X1904000D03*
Y546341D03*
Y548900D03*
G54D236*
X1481800Y582200D03*
Y553700D03*
G54D308*
X1861735Y96422D03*
G54D245*
X1586547Y-6702D03*
X1592531D03*
G54D263*
X1630534Y336594D03*
X1628566D03*
X1632503D03*
X1636440D03*
X1634472D03*
Y349698D03*
X1636440D03*
X1628566D03*
X1630534D03*
X1632503D03*
G54D335*
X1953740Y235551D03*
G36*
G01X24103Y622608D02*
G02Y598654I-10303J-11977D01*
G02X3767Y598425I-10304J11976D01*
G03X2702Y598731I-1068J-1710D01*
G01X-3D01*
G02X-11901Y610631I2J11900D01*
G02X-1Y622531I11901J-1D01*
G01X2709D01*
G03X3764Y622834I-1J1990D01*
G02X24103Y622608I10035J-12202D01*
G37*
G36*
G01X701268Y4104D02*
G02Y-19850I-10303J-11977D01*
G02X680932Y-20079I-10304J11976D01*
G03X679867Y-19773I-1068J-1710D01*
G01X677162D01*
G02X665264Y-7873I2J11900D01*
G02X677164Y4027I11901J-1D01*
G01X679874D01*
G03X680929Y4330I-1J1990D01*
G02X701268Y4104I10035J-12202D01*
G37*
G36*
G01Y622608D02*
G02Y598654I-10303J-11977D01*
G02X680932Y598425I-10304J11976D01*
G03X679867Y598731I-1068J-1710D01*
G01X677162D01*
G02X665264Y610631I2J11900D01*
G02X677164Y622531I11901J-1D01*
G01X679874D01*
G03X680929Y622834I-1J1990D01*
G02X701268Y622608I10035J-12202D01*
G37*
G36*
G01X1429615Y4104D02*
G02Y-19850I-10303J-11977D01*
G02X1409279Y-20079I-10304J11976D01*
G03X1408214Y-19773I-1068J-1710D01*
G01X1405509D01*
G02X1393611Y-7873I2J11900D01*
G02X1405511Y4027I11901J-1D01*
G01X1408221D01*
G03X1409276Y4330I-1J1990D01*
G02X1429615Y4104I10035J-12202D01*
G37*
G36*
G01Y622608D02*
G02Y598654I-10303J-11977D01*
G02X1409279Y598425I-10304J11976D01*
G03X1408214Y598731I-1068J-1710D01*
G01X1405509D01*
G02X1393611Y610631I2J11900D01*
G02X1405511Y622531I11901J-1D01*
G01X1408221D01*
G03X1409276Y622834I-1J1990D01*
G02X1429615Y622608I10035J-12202D01*
G37*
G36*
G01X1878434Y4104D02*
G02Y-19850I-10303J-11977D01*
G02X1858098Y-20079I-10304J11976D01*
G03X1857033Y-19773I-1068J-1710D01*
G01X1854328D01*
G02X1842430Y-7873I2J11900D01*
G02X1854330Y4027I11901J-1D01*
G01X1857040D01*
G03X1858095Y4330I-1J1990D01*
G02X1878434Y4104I10035J-12202D01*
G37*
G36*
G01Y622608D02*
G02Y598654I-10303J-11977D01*
G02X1858098Y598425I-10304J11976D01*
G03X1857033Y598731I-1068J-1710D01*
G01X1854328D01*
G02X1842430Y610631I2J11900D01*
G02X1854330Y622531I11901J-1D01*
G01X1857040D01*
G03X1858095Y622834I-1J1990D01*
G02X1878434Y622608I10035J-12202D01*
G37*
G54D281*
X1741609Y167494D03*
G54D26*
X30500Y-42250D03*
Y-52250D03*
X50500Y-42250D03*
X70500D03*
X90500D03*
X110500D03*
X50500Y-52250D03*
X70500D03*
X90500D03*
X110500D03*
X60512Y467244D03*
X130500Y-42250D03*
Y-52250D03*
X457246Y-52301D03*
Y-42301D03*
X477246Y-52301D03*
Y-42301D03*
X497246Y-52301D03*
Y-42301D03*
X517246Y-52301D03*
Y-42301D03*
X537246Y-52301D03*
Y-42301D03*
X557246Y-52301D03*
Y-42301D03*
X788984Y-52057D03*
Y-42057D03*
X808984Y-52057D03*
Y-42057D03*
X828984Y-52057D03*
Y-42057D03*
X848984Y-52057D03*
Y-42057D03*
X868984Y-52057D03*
Y-42057D03*
X888984Y-52057D03*
Y-42057D03*
X1125583Y-52285D03*
Y-42285D03*
X1145583Y-52285D03*
Y-42285D03*
X1382258Y-52257D03*
Y-42257D03*
X1402258Y-52257D03*
Y-42257D03*
X1422258Y-52257D03*
Y-42257D03*
X1442258Y-52257D03*
Y-42257D03*
X1891086Y592105D03*
X1904100Y493000D03*
X1968000Y568500D03*
Y554500D03*
Y590000D03*
Y576000D03*
Y597500D03*
Y611500D03*
G54D227*
X1526871Y23968D03*
X1809665Y618663D03*
X1819665D03*
X1829665D03*
X1881595Y23968D03*
G54D128*
X476672Y220096D03*
Y235696D03*
X483432Y216196D03*
X480052Y210346D03*
X483432Y212296D03*
X531871Y202547D03*
X525111D03*
X483432Y231797D03*
X480052Y225947D03*
X483432Y239596D03*
X501452Y337096D03*
X538631Y331247D03*
Y327347D03*
X535251Y340996D03*
Y337096D03*
X528491Y340996D03*
X531871Y339047D03*
Y331247D03*
X538631Y323446D03*
X525111Y319547D03*
X518352Y335147D03*
X521731Y333196D03*
Y329296D03*
X525111Y331247D03*
X528491Y333196D03*
X521731Y340996D03*
X525111Y323446D03*
X528491Y325396D03*
Y329296D03*
Y321496D03*
X531871Y323446D03*
X525111Y327347D03*
X521731Y337096D03*
X487932Y356596D03*
X491312Y342947D03*
Y354647D03*
X511592Y389747D03*
Y401447D03*
X508212Y383896D03*
X504832Y401446D03*
X535251Y348796D03*
Y344896D03*
X538631Y346847D03*
Y342947D03*
X535251Y360496D03*
X531871Y358547D03*
X535251Y364396D03*
Y368296D03*
X525111Y346847D03*
X528491Y348796D03*
X531871Y342947D03*
X528491Y344896D03*
Y352696D03*
X538631Y354647D03*
Y358547D03*
Y362447D03*
X531871D03*
Y366347D03*
X535251Y372197D03*
X538631Y350747D03*
X535251Y379996D03*
X538631Y374146D03*
X531871Y378047D03*
X514972Y376096D03*
X528491Y387796D03*
X521731D03*
Y391696D03*
X518352Y393647D03*
X514972Y395597D03*
X528491Y379996D03*
Y383896D03*
X525111Y385847D03*
X521731Y383896D03*
X525111Y389747D03*
X521731Y395597D03*
X514972Y391696D03*
Y387796D03*
X528491Y376096D03*
X531871Y381947D03*
X494692Y387796D03*
X514972Y364396D03*
X518352Y350747D03*
X504832Y374146D03*
X508212Y368296D03*
X514972Y360496D03*
X508212Y372197D03*
X511592Y354647D03*
X498072Y378047D03*
Y381947D03*
X518352Y354647D03*
X511592Y366347D03*
X494692Y379996D03*
X501452Y376096D03*
X511592Y362447D03*
X508212Y364396D03*
X514972Y368296D03*
X511592Y358547D03*
X498072Y374146D03*
X521731Y352696D03*
X494692Y383896D03*
X518352Y346847D03*
X484552Y374146D03*
X487932Y383896D03*
X491312Y393647D03*
X494692Y399496D03*
X484552Y389747D03*
X552151Y331247D03*
Y335147D03*
X548771Y333196D03*
X552151Y339047D03*
X555531Y340996D03*
X542011D03*
Y337096D03*
X545391Y327347D03*
Y339047D03*
X542011Y333196D03*
Y329296D03*
Y325396D03*
X562591Y340996D03*
X558911Y339047D03*
X562591Y337096D03*
X555531D03*
X552151Y342947D03*
X548771Y344896D03*
X552151Y346847D03*
X542011Y344896D03*
Y356596D03*
X559211Y366347D03*
X558911Y354647D03*
X552151Y362447D03*
X545391Y350747D03*
X548771Y348796D03*
X555531Y352696D03*
Y348796D03*
X552151Y354647D03*
X558911Y350747D03*
X555531Y344896D03*
X548771Y387796D03*
X552151Y385847D03*
X555531Y379996D03*
X552151Y381947D03*
X937747Y322209D03*
X930987D03*
X947887Y324160D03*
X941127D03*
G54D191*
X1261528Y438443D03*
X1253007Y431370D03*
G54D209*
X1462000Y-5000D03*
Y-15000D03*
X1452000Y-5000D03*
Y-15000D03*
X1442000Y-5000D03*
X1525000Y-15000D03*
X1515000D03*
X1482000D03*
X1472000Y-5000D03*
Y-15000D03*
X1492000Y-5000D03*
Y-15000D03*
X1482000Y-5000D03*
X1575000Y-15000D03*
X1565000D03*
X1555000D03*
X1545000D03*
X1535000D03*
X1713503Y-5000D03*
Y-15000D03*
X1703503Y-5000D03*
X1743503Y-15000D03*
X1733503Y-5000D03*
Y-15000D03*
X1723503Y-5000D03*
Y-15000D03*
X1753503Y-5000D03*
Y-15000D03*
X1743503Y-5000D03*
X1769504D03*
X1809504Y-15000D03*
X1799504Y-5000D03*
Y-15000D03*
X1789504Y-5000D03*
Y-15000D03*
X1779504Y-5000D03*
Y-15000D03*
X1819504Y-5000D03*
Y-15000D03*
X1809504Y-5000D03*
G54D290*
X1724041Y590805D03*
Y594742D03*
Y592773D03*
Y596711D03*
Y598679D03*
X1889300Y164242D03*
Y162273D03*
Y172116D03*
Y176053D03*
Y160305D03*
Y178021D03*
Y170147D03*
Y181958D03*
Y185895D03*
Y183927D03*
Y158336D03*
Y166210D03*
Y168179D03*
Y187864D03*
Y174084D03*
Y179990D03*
G54D326*
X1933849Y132626D03*
Y134594D03*
Y138531D03*
Y140500D03*
X1931550Y132626D03*
Y134594D03*
Y138531D03*
Y140500D03*
G54D17*
X-15300Y255000D03*
X13700D03*
G54D137*
X652400Y266849D03*
X681500Y260248D03*
G54D155*
X699300Y36012D03*
X1357000Y96213D03*
X1557500Y350500D03*
X1552400D03*
X1547300Y350658D03*
X1620827Y95153D03*
X1624188Y96700D03*
X1634977Y96860D03*
X1615749Y96720D03*
X1590991Y202378D03*
X1658500Y179742D03*
X1874600Y140762D03*
G54D363*
G01X-14722Y452578D02*
Y453312D01*
X-17014Y455604D01*
G01X-14000Y512300D02*
X-15000D01*
X-16000Y513300D01*
X-17200D01*
G01D02*
Y510800D01*
G01X-16500Y489500D02*
X-17900D01*
X-20600Y492200D01*
Y507400D01*
X-17200Y510800D01*
G01X-13400Y499300D02*
X-15960D01*
X-16766Y500106D01*
G01X-17302Y506798D02*
X-16804Y506300D01*
X-14000D01*
G01X-16700Y497400D02*
X-17500D01*
X-18900Y498800D01*
Y500454D01*
X-17585Y501769D01*
X-15431D01*
X-14400Y502800D01*
X-13400D01*
G01X-11685Y495700D02*
X-15400D01*
X-16500Y494600D01*
Y493000D01*
G01X148901Y-50423D02*
X445470D01*
G02Y-53848I0J-1712D01*
G01X147382D01*
X144980Y-56250D01*
X44500D01*
X40500Y-52250D01*
G01X34719Y19455D02*
X37688Y22424D01*
X45981D01*
X46550Y21855D01*
Y20464D01*
G01X34719Y16717D02*
Y19455D01*
G01X37739Y19501D02*
Y16712D01*
G01Y13212D02*
X37138Y12611D01*
Y8675D01*
G01X43819Y17401D02*
Y20431D01*
X43960Y20572D01*
G01X43819Y13901D02*
Y13789D01*
X40287Y10257D01*
Y8675D01*
G01X40796Y17406D02*
Y19954D01*
X40530Y20220D01*
G01X40796Y13906D02*
Y13276D01*
X38713Y11193D01*
Y8675D01*
G01X31599Y14409D02*
Y17909D01*
G01X25060Y16214D02*
X26865Y14409D01*
X28099D01*
G01D02*
Y12593D01*
X32017Y8675D01*
X32413D01*
G01X41862D02*
Y10162D01*
X43790Y12090D01*
X46180D01*
X46845Y12755D01*
Y13942D01*
G01X49880Y13915D02*
Y13360D01*
X47580Y11060D01*
X44152D01*
X43437Y10345D01*
Y8675D01*
G01X-1347Y27309D02*
X136D01*
X5873Y33046D01*
X8141D01*
G01X34719Y13217D02*
Y11797D01*
X35563Y10953D01*
Y8675D01*
G01X37037Y138425D02*
Y136897D01*
X38142Y135792D01*
Y96986D01*
X47828Y87300D01*
X74069D01*
X76106Y89337D01*
G01X88500Y118000D02*
Y120940D01*
X91160Y123600D01*
Y128990D01*
X82298Y137852D01*
Y152702D01*
X79600Y155400D01*
X61800D01*
X56700Y150300D01*
X44616D01*
X30341Y136025D01*
X7225D01*
X6299Y135099D01*
Y132717D01*
G01X28740Y140591D02*
X29641D01*
X36333Y147283D01*
Y154477D01*
X43056Y161200D01*
X71900D01*
G01X11811Y132717D02*
Y128755D01*
X13338Y127228D01*
X19418D01*
X19835Y127645D01*
Y129585D01*
X20252Y130002D01*
X20843D01*
X21260Y129585D01*
Y127645D01*
X21677Y127228D01*
X22268D01*
X22685Y127645D01*
Y129585D01*
X23102Y130002D01*
X23693D01*
X24110Y129585D01*
Y127645D01*
X24527Y127228D01*
X25118D01*
X25535Y127645D01*
Y129585D01*
X25952Y130002D01*
X26543D01*
X26960Y129585D01*
Y127645D01*
X27377Y127228D01*
X27968D01*
X28385Y127645D01*
Y129585D01*
X28802Y130002D01*
X29393D01*
X29810Y129585D01*
Y127645D01*
X30227Y127228D01*
X30818D01*
X31235Y127645D01*
Y129585D01*
X31652Y130002D01*
X32243D01*
X32660Y129585D01*
Y127645D01*
X33077Y127228D01*
X35758D01*
X36260Y127730D01*
Y134151D01*
X34558Y135853D01*
Y138457D01*
X36740Y140639D01*
X37330D01*
X39845Y138124D01*
X40435D01*
X40853Y138542D01*
Y139132D01*
X38338Y141647D01*
Y142237D01*
X38756Y142655D01*
X39346D01*
X41861Y140140D01*
X42451D01*
X42869Y140558D01*
Y141148D01*
X40354Y143663D01*
Y144253D01*
X44601Y148500D01*
X52100D01*
G01X48300Y157500D02*
X41708D01*
X39109Y154901D01*
G01D02*
Y146697D01*
X29682Y137270D01*
X3970D01*
X787Y134087D01*
Y132717D01*
G01X8120Y280500D02*
Y277620D01*
X8000Y277500D01*
Y275500D01*
G01X10680Y280500D02*
Y277320D01*
X11000Y277000D01*
Y275500D01*
G01X5000Y295500D02*
Y294000D01*
X5560Y293440D01*
Y290500D01*
G01X8120D02*
Y293380D01*
X8000Y293500D01*
Y295500D01*
G01X5000Y299000D02*
Y301153D01*
X3806Y302347D01*
G01X8000Y299000D02*
Y301153D01*
X6806Y302347D01*
G01X49091Y351509D02*
X46991D01*
X45800Y352700D01*
Y384300D01*
X59500Y398000D01*
G01X49017Y346509D02*
X46591D01*
X43225Y349875D01*
Y388725D01*
X52500Y398000D01*
G01X49117Y349009D02*
X49008Y348900D01*
X46400D01*
X44500Y350800D01*
Y386500D01*
X56000Y398000D01*
G01X49017Y344009D02*
X47091D01*
X42000Y349100D01*
Y391100D01*
X49000Y398100D01*
G01X46100Y416271D02*
X49800Y412571D01*
Y404200D01*
X52500Y401500D01*
G01X49000Y401600D02*
X47500Y403100D01*
Y412120D01*
X46100Y413520D01*
G01X-4488Y434094D02*
X-2358Y436224D01*
Y454906D01*
X787Y458051D01*
Y460837D01*
X6849Y466899D01*
Y476540D01*
X10259Y479950D01*
Y484809D01*
X13400Y487950D01*
X15200D01*
G01X5100Y478330D02*
X4530D01*
X3200Y477000D01*
X1000D01*
X-3000Y473000D01*
Y466750D01*
X-3400Y466350D01*
Y459150D01*
X-6650Y455900D01*
X-6700D01*
X-7310Y455290D01*
X-11620D01*
X-13802Y457472D01*
Y462160D01*
G01X2160Y479000D02*
X1500D01*
X-3950Y473550D01*
Y467150D01*
X-4350Y466750D01*
Y459549D01*
X-7069Y456830D01*
X-10095D01*
X-11242Y457977D01*
Y462160D01*
G01X-1278Y460571D02*
Y458122D01*
X-1950Y457450D01*
G01D02*
X-5722Y453678D01*
Y452578D01*
G01X2450Y460000D02*
X5950Y456500D01*
Y451000D01*
G01X-1093Y467071D02*
Y465693D01*
X-1278Y465508D01*
Y464071D01*
G01X-8990Y523040D02*
Y525091D01*
X-9600Y525701D01*
Y526100D01*
G01X-5680Y524570D02*
X-5500Y524390D01*
Y523593D01*
X-5590Y523503D01*
Y521840D01*
G01X-14000Y509300D02*
Y512300D01*
G01X6748Y517021D02*
X7313Y516456D01*
G01X-1550Y501438D02*
X-2862D01*
X-5000Y499300D01*
X-6660D01*
G01D02*
X-9900D01*
G01X-10500Y506300D02*
X-8300D01*
X-7400Y505400D01*
X-6200D01*
G01X-1550Y504587D02*
X-3590D01*
X-4403Y505400D01*
X-6200D01*
G01X-9900Y502800D02*
X-8900Y501800D01*
X-6676D01*
G01D02*
X-4200D01*
X-2987Y503013D01*
X-1550D01*
G01Y499863D02*
X-3137D01*
X-7300Y495700D01*
X-11685D01*
G01X-10500Y509300D02*
X-7405D01*
X-6703Y508598D01*
G01X-1550Y506162D02*
X-2762D01*
X-5200Y508600D01*
X-6700D01*
Y508598D01*
X-6703D01*
G01X-10500Y512300D02*
X-7660D01*
X-7360Y512000D01*
G01X-5590Y518340D02*
X-2390D01*
G01X-6712Y515731D02*
X-5870Y516573D01*
Y518060D01*
X-5590Y518340D01*
G01X710Y518390D02*
Y517016D01*
X2588Y515138D01*
Y513450D01*
G01X-2390Y518340D02*
X-1054D01*
X-1004Y518390D01*
X710D01*
G01X15200Y487950D02*
X18250D01*
X27074Y479126D01*
X50581D01*
X54289Y482834D01*
X74422D01*
X81476Y475780D01*
X82529D01*
X85865Y472444D01*
Y470975D01*
G01X-12690Y519590D02*
X-9040D01*
X-8990Y519540D01*
G01X-12690Y519590D02*
Y517126D01*
X-12264Y516700D01*
X-11202D01*
G01D02*
X-10444D01*
X-7583Y513839D01*
X-6126D01*
X-3174Y510887D01*
X-1550D01*
G01X1013Y513450D02*
X-1829D01*
X-2083Y513704D01*
G01X-13802Y478340D02*
Y476152D01*
X-11490Y473840D01*
G01X-1000Y479000D02*
X-6420Y473580D01*
X-8760D01*
X-11242Y476062D01*
Y478340D01*
G01X1483Y474017D02*
X2350Y473150D01*
Y469650D01*
G01X1483Y474017D02*
X-1093Y471441D01*
Y467071D01*
G01X-12500Y534300D02*
Y535704D01*
X-10404Y537800D01*
X-7335D01*
G01X-4520Y539702D02*
X-6422Y537800D01*
X-7335D01*
G01X-12500Y570300D02*
Y570650D01*
X-10110Y573040D01*
X-8150D01*
X-7383Y573807D01*
G01D02*
X-5488Y575702D01*
G01X55942Y17445D02*
X57812D01*
X62008Y13249D01*
G01X46845Y17442D02*
Y18405D01*
X46570Y18680D01*
Y18781D01*
X46550Y18801D01*
Y20464D01*
G01X63712Y2888D02*
Y1225D01*
X64355Y582D01*
Y-5240D01*
G01X46845Y17442D02*
X46872Y17415D01*
X49880D01*
G01X64355Y-5240D02*
Y-7105D01*
X71849Y-14599D01*
X80299D01*
X82300Y-16600D01*
G01X61994Y362D02*
X60353Y-1279D01*
X57732D01*
X54798Y1655D01*
X51398D01*
X51130Y1387D01*
X49150D01*
G01X62536Y-2379D02*
X62276Y-2639D01*
X57625D01*
X54323Y663D01*
X52216D01*
X51365Y-188D01*
X49150D01*
G01X70980Y97166D02*
X75440Y92706D01*
Y92560D01*
X87700Y80300D01*
Y2600D01*
X86600Y1500D01*
Y-15900D01*
X87091Y-16391D01*
G01X53704Y8216D02*
Y4716D01*
G01X49150Y4537D02*
X51362D01*
X51541Y4716D01*
X53704D01*
G01D02*
Y3053D01*
X54075Y2682D01*
X58343D01*
X58549Y2888D01*
X60212D01*
G01X63261Y8225D02*
X61689D01*
X59564Y10350D01*
X55060D01*
X53704Y8994D01*
Y8216D01*
G01X63261Y8225D02*
X64343D01*
X64769Y8651D01*
Y10693D01*
X64159Y11303D01*
G01X52906Y13926D02*
X52925Y13945D01*
X55942D01*
G01X52906Y13926D02*
Y13407D01*
X50879Y11380D01*
X49690D01*
X46985Y8675D01*
X46587D01*
G01X49150Y6112D02*
X50492D01*
X51090Y6710D01*
Y8080D01*
G01X55600Y148500D02*
X65600D01*
X70317Y143783D01*
Y119183D01*
X71300Y118200D01*
Y110100D01*
X69700Y108500D01*
Y102389D01*
X82046Y90043D01*
G01X104289Y124954D02*
X101458D01*
X100764Y124260D01*
X94443D01*
X93100Y125603D01*
Y129570D01*
X84033Y138637D01*
Y156267D01*
X81000Y159300D01*
X53600D01*
X51800Y157500D01*
G01X104500Y121500D02*
Y118000D01*
G01D02*
X104300Y117800D01*
Y110957D01*
X104424Y110833D01*
G01X104500Y121500D02*
Y123139D01*
X104289Y123350D01*
Y124954D01*
G01X81500Y118000D02*
Y120700D01*
X83700Y122900D01*
X87100D01*
X88500Y124300D01*
Y127000D01*
G01X81500Y118000D02*
X78400D01*
X74400Y122000D01*
X72500D01*
G01X79670Y132300D02*
Y128830D01*
X81500Y127000D01*
G01X87564Y105000D02*
X88500Y105936D01*
Y118000D01*
G01X89980Y145531D02*
X95190Y150741D01*
Y157410D01*
X91600Y161000D01*
Y162300D01*
G01X95500Y127500D02*
Y141051D01*
X99980Y145531D01*
G01X95500Y118500D02*
X98410D01*
X98910Y118000D01*
X101000D01*
G01X91600Y162300D02*
Y167149D01*
X90949Y167800D01*
X88600D01*
G01X86731Y189148D02*
X83184Y185601D01*
Y171563D01*
X83635Y171112D01*
Y166335D01*
X82859Y165559D01*
X79900D01*
G01X72900Y168118D02*
Y171700D01*
X72700Y171900D01*
G01X64187Y176332D02*
X68768D01*
X72700Y172400D01*
Y171900D01*
G01X72100Y321800D02*
Y318350D01*
X70800Y317050D01*
G01X48550Y301650D02*
Y297050D01*
X50300Y295300D01*
X50900D01*
G01X63000Y341500D02*
Y339000D01*
X62900D01*
G01X61000Y313250D02*
Y311801D01*
X61801Y311000D01*
X64225D01*
X64700Y310525D01*
G01X64605Y307250D02*
Y309006D01*
X64800Y309201D01*
Y310425D01*
X64700Y310525D01*
G01X66500Y313250D02*
X67850D01*
X69125Y311975D01*
Y310625D01*
G01D02*
X68025D01*
X66575Y309175D01*
Y307250D01*
G01X75000Y341500D02*
Y339050D01*
X74800Y338850D01*
G01X69000Y341800D02*
Y338800D01*
G01X72000Y341800D02*
Y338800D01*
G01X76425Y307250D02*
Y308625D01*
X77500Y309700D01*
Y312500D01*
G01X87500Y309500D02*
X85800Y307800D01*
Y307200D01*
X84300Y305700D01*
G01X80750Y302925D02*
X82025D01*
X84300Y305200D01*
Y305700D01*
G01X87500Y313500D02*
X84700Y310700D01*
X84300D01*
G01X80750Y304895D02*
X81527D01*
X82600Y305968D01*
Y309000D01*
X84300Y310700D01*
G01X62250Y304895D02*
X61406D01*
X60300Y306001D01*
Y307950D01*
X55500Y312750D01*
G01X91000Y306000D02*
Y303700D01*
X90297Y302997D01*
X88600D01*
G01X97250Y332500D02*
X100106D01*
X100673Y331933D01*
Y326960D01*
X101500Y326133D01*
Y324000D01*
X100000Y322500D01*
G01D02*
X99160D01*
X98337Y321677D01*
Y314413D01*
X100350Y312400D01*
X102450D01*
G01X102067Y338387D02*
X101339D01*
X97250Y334298D01*
Y332500D01*
G01X64000Y313900D02*
Y314100D01*
X61350Y316750D01*
X61000D01*
G01X64000Y316500D02*
X64250Y316750D01*
X66500D01*
G01X104250Y327382D02*
Y329140D01*
X103200Y330190D01*
G01X103500Y322500D02*
Y326632D01*
X104250Y327382D01*
G01X97250Y329941D02*
X95460D01*
X94570Y329051D01*
Y326324D01*
X97320Y323574D01*
Y316910D01*
X95632Y315222D01*
X86222D01*
X85209Y314209D01*
X80713D01*
X79100Y315822D01*
Y316400D01*
X77600Y317900D01*
Y320800D01*
G01D02*
X78820Y322020D01*
X80500D01*
G01X82450Y328000D02*
Y325770D01*
X80500Y323820D01*
Y322020D01*
G01X85467Y302966D02*
X83456Y300955D01*
X80750D01*
G01X87500Y306000D02*
Y304825D01*
X86674Y303999D01*
X86500D01*
X85467Y302966D01*
G01X70800Y313550D02*
Y312600D01*
X72600Y310800D01*
G01X70515Y307250D02*
Y308715D01*
X72600Y310800D01*
G01X50900Y298800D02*
Y301188D01*
X52412Y302700D01*
X53150D01*
X53250Y302800D01*
G01D02*
X53400D01*
X54600Y304000D01*
X56000D01*
G01X62250Y302925D02*
X61076D01*
X59501Y304500D01*
X57500D01*
X57000Y304000D01*
X56000D01*
G01X98500Y298500D02*
Y300300D01*
X98700Y300500D01*
Y303900D01*
G01X102322Y295478D02*
X101170Y296630D01*
X98950D01*
X98500Y297080D01*
Y298500D01*
G01X54500Y348400D02*
X54159D01*
X51923Y346164D01*
G01X47970Y359550D02*
Y359345D01*
X50480Y356835D01*
X54800D01*
X57800Y359835D01*
X62809D01*
X63037Y360063D01*
X65100D01*
G01X50510Y359240D02*
X51899Y357851D01*
X54425D01*
X57274Y360700D01*
X62500D01*
X63438Y361638D01*
X65100D01*
G01X75000Y345000D02*
Y346001D01*
X75126Y346127D01*
Y346526D01*
X76500Y347900D01*
G01D02*
X77287Y348687D01*
Y352600D01*
G01X74138D02*
Y348938D01*
X73200Y348000D01*
X72131D01*
G01D02*
X71100D01*
X69000Y345900D01*
Y345300D01*
G01X72000D02*
X73505Y346805D01*
X73805D01*
X75713Y348713D01*
Y352600D01*
G01X59500Y401500D02*
Y405200D01*
X60635Y406335D01*
Y412487D01*
X56644Y416478D01*
X54662D01*
G01X56000Y401500D02*
Y403800D01*
X59210Y407010D01*
Y412462D01*
X56977Y414695D01*
X53231D01*
X51645Y416281D01*
G01X60000Y345000D02*
X62120Y347120D01*
X62320D01*
X63800Y348600D01*
G01X69413Y352600D02*
Y351413D01*
X67900Y349900D01*
X65100D01*
X63800Y348600D01*
G01X58000Y354600D02*
Y351500D01*
G01Y348400D02*
Y351500D01*
G01Y354600D02*
X59198D01*
X59711Y354087D01*
X61089D01*
X62063Y355061D01*
Y356113D01*
X62863Y356913D01*
X65100D01*
G01X67839Y352600D02*
Y351900D01*
X67339Y351400D01*
X64000D01*
X60900Y348300D01*
G01D02*
X59300Y346700D01*
X58700D01*
X57000Y345000D01*
G01X63000D02*
X66000D01*
G01X70988Y352600D02*
Y351288D01*
X68700Y349000D01*
Y347937D01*
X66000Y345237D01*
Y345000D01*
G01X79100Y347000D02*
Y346800D01*
X78000Y345700D01*
Y344550D01*
G01X78862Y352600D02*
Y349038D01*
X79100Y348800D01*
Y347000D01*
G01X65100Y355339D02*
X64222D01*
X63410Y354527D01*
Y353371D01*
X61776Y351737D01*
X61041D01*
G01X106510Y351100D02*
X111600D01*
X113366Y349334D01*
Y348586D01*
G01X74600Y465511D02*
X74648Y465463D01*
Y461201D01*
G01X78100Y465511D02*
Y463200D01*
X78700Y462600D01*
Y460200D01*
G01X59731Y480066D02*
X61274Y481609D01*
X67132D01*
X69233Y479508D01*
Y476221D01*
X69658Y475796D01*
X73841D01*
X74266Y475371D01*
Y472113D01*
X74202Y472049D01*
Y469901D01*
X74266Y469837D01*
Y465845D01*
X74600Y465511D01*
G01X70525Y465138D02*
X72564D01*
X72937Y465511D01*
X74600D01*
G01X71050Y478670D02*
X71640Y478080D01*
X74820D01*
G01X76865Y470975D02*
Y468409D01*
X78100Y467174D01*
Y465511D01*
G01X120533Y109535D02*
X118935Y111133D01*
Y118861D01*
G01X111093D02*
X111350Y119118D01*
X112950D01*
X115014Y121182D01*
Y125587D01*
X115772Y126345D01*
X118935D01*
G01X111093Y118861D02*
Y116850D01*
X113331Y114612D01*
X114155D01*
X116124Y112643D01*
Y112393D01*
G01X112200Y247200D02*
X113588Y248588D01*
Y252322D01*
G01X112400Y277800D02*
X113100Y278500D01*
Y281000D01*
X114317Y282217D01*
Y283595D01*
G01X110198Y219572D02*
X113162D01*
X114120Y220530D01*
G01X122165Y284235D02*
X119835D01*
X118770Y283170D01*
X116830D01*
X116405Y283595D01*
X114317D01*
G01X121981Y405573D02*
Y404633D01*
X121261Y403913D01*
X119385D01*
X117972Y402500D01*
X116700D01*
G01Y405500D02*
Y402500D01*
G01X116910Y377860D02*
X116169D01*
X115319Y378710D01*
X113620D01*
G01X116910Y377860D02*
X117570D01*
X119945Y380235D01*
X122165D01*
G01X148409Y422239D02*
X148828Y422658D01*
X151314D01*
G01X151343Y418959D02*
X150228D01*
X148666Y417397D01*
G01X116600Y411700D02*
X119000D01*
X119100Y411600D01*
G01X116600Y414700D02*
X117099Y414201D01*
X119016D01*
G01X119398Y406348D02*
Y406802D01*
X117600Y408600D01*
X116700D01*
G01X276869Y205210D02*
X274619D01*
G01X273489Y207159D02*
X271239D01*
G01X270109Y209109D02*
X267859D01*
G01X280249Y199360D02*
X277999D01*
G01X276869Y201309D02*
X274619D01*
G01X273489Y203260D02*
X271239D01*
G01X276869Y209109D02*
X274619D01*
G01X276869Y271509D02*
X274619D01*
G01X293769Y273460D02*
X291519D01*
G01X280249D02*
X277999D01*
G01X293769Y320260D02*
X291519D01*
G01X287009D02*
X284759D01*
G01X290389Y322209D02*
X288139D01*
G01X283629D02*
X281379D01*
G01X293769Y324160D02*
X291519D01*
G01X280249D02*
X277999D01*
G01X276869Y400209D02*
X274619D01*
G01X283629D02*
X281379D01*
G01X273489Y394359D02*
X271239D01*
G01X270109Y392410D02*
X267859D01*
G01X273489Y398260D02*
X271239D01*
G01X280249D02*
X277999D01*
G01X276869Y396309D02*
X274619D01*
G01X307675Y22923D02*
Y28014D01*
G01Y-14877D02*
Y-7662D01*
X308157Y-7180D01*
G01X317714Y3233D02*
Y-4536D01*
G01X307675Y60723D02*
Y67549D01*
X307928Y67802D01*
G01X317714Y73757D02*
Y78833D01*
G01Y35957D02*
Y41033D01*
G01X344468Y216909D02*
X342218D01*
G01X297149Y197409D02*
X294899D01*
G01X337708Y205210D02*
X338838Y207158D01*
G01X341088Y207159D02*
X340292Y206363D01*
Y204712D01*
X338838Y203258D01*
G01X347848Y211060D02*
X345598D01*
G01X351228Y213009D02*
X348978D01*
G01X337708Y220809D02*
X335458D01*
G01X347848Y222760D02*
X345598D01*
G01X334328D02*
X332078D01*
G01X330948Y224709D02*
X328698D01*
G01X334328Y226660D02*
X332078D01*
G01X337708Y228610D02*
X335458D01*
G01X330948D02*
X328698D01*
G01X334328Y230559D02*
X332079D01*
X332078Y230560D01*
G01X337708Y232509D02*
X335459D01*
X335458Y232510D01*
G01X314048Y242260D02*
X311798D01*
G01X317428Y244209D02*
X315178D01*
G01X314048Y246160D02*
X311798D01*
G01X317428Y248109D02*
X315178D01*
G01X310668D02*
X308418D01*
G01X354607Y250060D02*
X352357D01*
G01X347848D02*
X345598D01*
G01X320808D02*
X318558D01*
G01X351228Y252009D02*
X348978D01*
G01X324188D02*
X321938D01*
G01X354607Y253960D02*
X352357D01*
G01X347848D02*
X345598D01*
G01X351228Y255909D02*
X348978D01*
G01X297149Y271509D02*
X294899D01*
G01X341088Y273460D02*
X338838D01*
G01X347848Y261760D02*
X345598D01*
G01X297149Y267609D02*
X294899D01*
G01X341088Y269560D02*
X338838D01*
G01X334328Y273460D02*
X332078D01*
G01X300529D02*
X298279D01*
G01X337708Y275409D02*
X335458D01*
G01X330948D02*
X328698D01*
G01X341088Y277360D02*
X338838D01*
G01X334328D02*
X332078D01*
G01X327568D02*
X325318D01*
G01X337708Y279310D02*
X335458D01*
G01X330948D02*
X328698D01*
G01X324188D02*
X321938D01*
G01X337708Y271509D02*
X335458D01*
G01X303909D02*
X301659D01*
G01X330948D02*
X328698D01*
G01X300529Y269560D02*
X298279D01*
G01X351228Y259809D02*
X348978D01*
G01X347848Y257860D02*
X345598D01*
G01X354607D02*
X352357D01*
G01X297149Y326110D02*
X294900D01*
X294899Y326109D01*
G01X297149Y330009D02*
X294899D01*
G01X354607Y339760D02*
X352357D01*
G01X317428Y349509D02*
X315178D01*
G01X317428Y353409D02*
X315178D01*
G01X314048Y355360D02*
X311798D01*
G01X314048Y347560D02*
X311798D01*
G01X314048Y351460D02*
X311798D01*
G01X310668Y349509D02*
X308418D01*
G01X344468D02*
X342218D01*
G01X347848Y347560D02*
X345598D01*
G01X297149Y400209D02*
X294899D01*
G01X317428Y384609D02*
X315178D01*
G01X351228D02*
X348978D01*
G01X317428Y380709D02*
X315178D01*
G01X337708Y376809D02*
X335458D01*
G01X334328Y374860D02*
X332078D01*
G01X347848D02*
X345598D01*
G01X330948Y372909D02*
X328698D01*
G01X334328Y370959D02*
X332078D01*
G01X330948Y369010D02*
X328698D01*
G01X337708D02*
X335458D01*
G01X334328Y367060D02*
X332078D01*
G01X337708Y365109D02*
X335458D01*
G01X341088Y363160D02*
X338838D01*
G01X354607Y347560D02*
X352357D01*
G01X354607Y343660D02*
X352357D01*
G01X324188Y341709D02*
X321938D01*
G01X324188Y345609D02*
X321938D01*
G01X307675Y523900D02*
Y528340D01*
X308198Y528863D01*
G01X307675Y561700D02*
Y566434D01*
X307984Y566743D01*
G01X317714Y542010D02*
Y536957D01*
G01Y579810D02*
Y574757D01*
G01X307675Y599500D02*
Y606738D01*
X308157Y607220D01*
G01X317714Y617610D02*
Y609864D01*
G01X411415Y3233D02*
Y-4536D01*
G01X421456Y73757D02*
X419473Y71774D01*
X395562D01*
X392892Y69104D01*
Y56918D01*
X394492Y55318D01*
Y54700D01*
G01X411415Y78833D02*
Y73858D01*
X411416Y73857D01*
Y73757D01*
G01X411415Y41033D02*
Y36058D01*
G01X394682Y68492D02*
Y60724D01*
X394683Y60723D01*
G01X401926Y211060D02*
X399676D01*
G01X398546Y244209D02*
X396296D01*
G01X398546Y240309D02*
X396296D01*
G01X401926Y242260D02*
X399676D01*
G01X364747Y248109D02*
X362497D01*
G01X361367Y250060D02*
X359117D01*
G01X357987Y252009D02*
X355737D01*
G01X361367Y253960D02*
X359117D01*
G01X357987Y255909D02*
X355737D01*
G01X391787Y240309D02*
X389537D01*
G01X385027D02*
X382777D01*
G01X395166Y242260D02*
X392916D01*
G01X388407D02*
X386157D01*
G01X381647D02*
X379397D01*
G01X391787Y244209D02*
X389537D01*
G01X385027D02*
X382777D01*
G01X378267D02*
X376017D01*
G01X395166Y246160D02*
X392916D01*
G01X388407D02*
X386157D01*
G01X381647D02*
X379397D01*
G01X374887D02*
X372637D01*
G01X368127D02*
X365877D01*
G01X371507Y248109D02*
X369257D01*
G01X368127Y250060D02*
X365877D01*
G01X364747Y252009D02*
X362497D01*
G01X405306Y244209D02*
X407706D01*
G01X401926Y246160D02*
X399676D01*
G01X401926Y359260D02*
X399676D01*
G01X408686D02*
X411340D01*
X411431Y359351D01*
G01X408686Y370959D02*
X409401D01*
X411547Y368813D01*
Y368260D01*
G01X408686Y355360D02*
X411086D01*
G01X408686Y363160D02*
X411447D01*
G01X405306Y353409D02*
X403056D01*
G01X408686Y367060D02*
X410086Y365660D01*
X411547D01*
G01X357987Y345609D02*
X355737D01*
G01X401926Y355360D02*
X399676D01*
G01X368127Y351460D02*
X365877D01*
G01X372637D02*
X374887D01*
G01X381647D02*
X379397D01*
G01X364747Y349509D02*
X362497D01*
G01X378267D02*
X376017D01*
G01X385027Y353409D02*
X382777D01*
G01X388407Y355360D02*
X386157D01*
G01X405306Y396309D02*
X403056D01*
G01X408686Y394359D02*
X411086D01*
G01X408686Y390460D02*
X411086D01*
G01X401926Y386560D02*
X399676D01*
G01X408686D02*
X411086D01*
G01X408686Y382660D02*
X411086D01*
G01X408686Y378760D02*
X411086D01*
G01X398546Y400209D02*
Y402900D01*
G01X385027Y357309D02*
X382777D01*
G01X381647Y355360D02*
X379397D01*
G01X401926Y398260D02*
X402892Y400400D01*
G01X364747Y345609D02*
X362497D01*
G01X368127Y347560D02*
X365877D01*
G01X361367Y343660D02*
X359117D01*
G01X357987Y341709D02*
X355737D01*
G01X361367Y347560D02*
X359117D01*
G01X394587Y529026D02*
X394683Y528930D01*
Y523900D01*
G01X411415Y542010D02*
Y537058D01*
X411416Y537057D01*
Y536957D01*
G01X411415Y579810D02*
Y574858D01*
X411416Y574857D01*
Y574757D01*
G01X394683Y599500D02*
Y591591D01*
X392792Y589700D01*
Y574100D01*
X394682Y572210D01*
Y569492D01*
G01X392892Y535600D02*
Y535200D01*
G01X394682Y569492D02*
X394683Y569491D01*
Y561723D01*
G01X411415Y617610D02*
Y609864D01*
G01X394682Y607292D02*
X394683Y607291D01*
Y599500D01*
G01X421455Y3233D02*
X421454Y-1817D01*
G01X421455Y46921D02*
Y41033D01*
G01X421456Y73757D02*
X421455Y73758D01*
Y78833D01*
G01X438187D02*
Y73759D01*
X438189Y73757D01*
G01X438187Y41033D02*
Y35959D01*
X438189Y35957D01*
G01X452865Y270081D02*
X449646Y273300D01*
X449100D01*
G01X439764Y263699D02*
X439664D01*
X439000Y264363D01*
Y265900D01*
X435100Y269800D01*
X433700D01*
X432000Y271500D01*
G01X449288Y266435D02*
X448561Y267162D01*
X446877D01*
X445400Y268639D01*
Y268800D01*
X442700Y271500D01*
G01X444408Y267305D02*
X443195D01*
X439500Y271000D01*
Y271500D01*
G01X440500Y266500D02*
X436000Y271000D01*
Y271500D01*
G01X464000Y294500D02*
Y295300D01*
X461800Y297500D01*
X461500D01*
G01X466066Y292452D02*
Y295934D01*
X461500Y300500D01*
G01X461400Y287500D02*
X461826Y287074D01*
X466734D01*
G01D02*
Y289166D01*
X464300Y291600D01*
X463400D01*
X461300Y293700D01*
G01X465100Y280300D02*
X463300Y282100D01*
Y282600D01*
X461400Y284500D01*
G01X463800Y289500D02*
X462800Y290500D01*
X461400D01*
G01X466100Y300021D02*
X462621Y303500D01*
X461500D01*
G01X453400Y293686D02*
X453586D01*
X453600Y293700D01*
X457800D01*
G01X428224Y358547D02*
X430474D01*
G01X431604Y356596D02*
X433854D01*
G01X468783Y342947D02*
X471033D01*
G01X434983Y378047D02*
X437233D01*
G01X438363Y376096D02*
X440613D01*
G01X441743Y374146D02*
X443992D01*
X443993Y374147D01*
G01X441743Y370247D02*
X443993D01*
G01X458643Y344896D02*
X460893D01*
G01X421455Y542010D02*
Y547921D01*
X421456Y547922D01*
G01Y585722D02*
X421455Y585721D01*
Y579810D01*
G01X438187Y542010D02*
Y536959D01*
X438189Y536957D01*
G01X438187Y579810D02*
Y574759D01*
X438189Y574757D01*
G01X421455Y617610D02*
X421454Y612560D01*
G01X482302Y210346D02*
X480052D01*
G01X485682Y212296D02*
X483432D01*
G01X539761Y204496D02*
X540300Y203958D01*
Y200956D01*
X542528Y198728D01*
X546800Y196958D01*
X547407Y196707D01*
X548269Y196350D01*
X568136D01*
X576428Y199784D01*
X578647Y202003D01*
X579497D01*
G01X509342Y268847D02*
X511592D01*
G01X512722Y255196D02*
X514972D01*
G01X512722Y274696D02*
X514972D01*
G01X516102Y257147D02*
X518352D01*
G01X505962Y274696D02*
X508212D01*
G01X502582Y268847D02*
X504832D01*
G01X489062Y272747D02*
X491312D01*
G01X509342D02*
X511592D01*
G01X502582Y276646D02*
X504831D01*
X504832Y276647D01*
G01X516102Y264947D02*
X518352D01*
G01X505962Y243496D02*
X508212D01*
G01X526241Y262996D02*
X528491D01*
G01X526241Y266896D02*
X528491D01*
G01X495822Y249347D02*
X498072D01*
G01X519481Y278596D02*
X521731D01*
G01X495822Y276646D02*
X498071D01*
X498072Y276647D01*
G01X489062Y276646D02*
X491311D01*
X491312Y276647D01*
G01X509342Y276646D02*
X511591D01*
X511592Y276647D01*
G01X502582Y272747D02*
X504832D01*
G01X522861Y276646D02*
X525111D01*
G01X516102D02*
X518352D01*
G01X495822Y272747D02*
X498072D01*
G01X529621Y253247D02*
X531871D01*
G01X526241Y251296D02*
X528491D01*
G01X522861Y241547D02*
X525111D01*
G01X526241Y239596D02*
X528491D01*
G01X501452Y278596D02*
X499202D01*
G01X485682Y239596D02*
X483432D01*
G01X519481Y262996D02*
X521731D01*
G01X522861Y264947D02*
X525111D01*
G01X478922Y321496D02*
X481172D01*
G01X485682Y313696D02*
X487932D01*
G01X478922Y325396D02*
X481172D01*
G01X489062Y315647D02*
X491312D01*
G01X482302Y319547D02*
X484551D01*
X484552Y319546D01*
G01X478922Y317596D02*
X481172D01*
G01X478922Y333196D02*
X481172D01*
G01X482302Y331247D02*
X484552D01*
G01X499202Y337096D02*
X501452D01*
G01X529621Y331247D02*
X531871D01*
G01X512722Y282496D02*
X514972D01*
G01X489062Y288347D02*
X491312D01*
G01X489062Y284447D02*
X491312D01*
G01X495822D02*
X498072D01*
G01X495822Y288347D02*
X498072D01*
G01X499202Y286396D02*
X501452D01*
G01X492442Y290296D02*
X494692D01*
G01X519481Y282496D02*
X521731D01*
G01X495822Y292247D02*
X498072D01*
G01X502582D02*
X504832D01*
G01X516102Y284447D02*
X518352D01*
G01X505962Y282496D02*
X508212D01*
G01X502582Y288347D02*
X504832D01*
G01X502582Y284447D02*
X504832D01*
G01X492442Y282496D02*
X494692D01*
G01X508212Y286396D02*
X505962D01*
G01X489062Y280547D02*
X491312D01*
G01X529621Y315647D02*
X531871D01*
G01X495822Y280547D02*
X498072D01*
G01X485682Y286396D02*
X487932D01*
G01X485682Y305896D02*
X487932D01*
G01X489062Y303947D02*
X491312D01*
G01X499202Y305896D02*
X501452D01*
G01X492442Y298096D02*
X494692D01*
G01X495822Y307847D02*
X498072D01*
G01X482302Y303947D02*
X484552D01*
G01X485682Y294196D02*
X487932D01*
G01X489062Y296147D02*
X491312D01*
G01X492442Y301996D02*
X494692D01*
G01X485682D02*
X487932D01*
G01X499202Y309797D02*
X501452D01*
G01X485682Y298096D02*
X487932D01*
G01X522861Y323446D02*
X525111D01*
G01X529621D02*
X531871D01*
G01X522861Y327347D02*
X525111D01*
G01X526241Y333196D02*
X528491D01*
G01X519481Y329296D02*
X521731D01*
G01X516102Y335147D02*
X518352D01*
G01X519481Y340996D02*
X521731D01*
G01X522861Y319547D02*
X525111D01*
G01X526241Y321496D02*
X528491D01*
G01X526241Y325396D02*
X528491D01*
G01X526241Y329296D02*
X528491D01*
G01X522861Y331247D02*
X525111D01*
G01X519481Y333196D02*
X521731D01*
G01X519481Y337096D02*
X521731D01*
G01X516102Y280547D02*
X518352D01*
G01X539761Y313696D02*
X542011D01*
G01X539761Y309797D02*
X542011D01*
G01X536381Y307847D02*
X538631D01*
G01X536381Y303947D02*
X538631D01*
G01X536381Y300047D02*
X538631D01*
G01X533001Y298096D02*
X535251D01*
G01X542011Y340996D02*
X539761D01*
G01X542011Y337096D02*
X539761D01*
G01X536381Y331247D02*
X538631D01*
G01X536381Y327347D02*
X538631D01*
G01X533001Y317596D02*
X535251D01*
G01X539761D02*
X542011D01*
G01X539761Y305896D02*
X542011D01*
G01X533001D02*
X535251D01*
G01X539761Y301996D02*
X542011D01*
G01X536381Y296147D02*
X538631D01*
G01X529621D02*
X531871D01*
G01X533001Y340996D02*
X535251D01*
G01X542011Y333196D02*
X539761D01*
G01X542011Y329296D02*
X539761D01*
G01X542011Y325396D02*
X539761D01*
G01X536381Y323446D02*
X538631D01*
G01X533001Y313696D02*
X535251D01*
G01X538631Y315647D02*
X536381D01*
G01X502582Y280547D02*
X504832D01*
G01X509342D02*
X511592D01*
G01X533001Y337096D02*
X535251D01*
G01X526241Y340996D02*
X528491D01*
G01X529621Y339047D02*
X531871D01*
G01X509342Y362447D02*
X511592D01*
G01X512722Y368296D02*
X514972D01*
G01X505962Y364396D02*
X508212D01*
G01X502582Y370247D02*
X504832D01*
G01X505962Y376096D02*
X508212D01*
G01X499202Y372197D02*
X501452D01*
G01X495822Y378047D02*
X498072D01*
G01X492442Y379996D02*
X494692D01*
G01X492442Y387796D02*
X494692D01*
G01X516102Y350747D02*
X518352D01*
G01X516102Y354647D02*
X518352D01*
G01X509342Y358547D02*
X511592D01*
G01X512722Y360496D02*
X514972D01*
G01X512722Y364396D02*
X514972D01*
G01X509342Y366347D02*
X511592D01*
G01X505962Y368296D02*
X508212D01*
G01X505962Y372197D02*
X508212D01*
G01X502582Y374146D02*
X504832D01*
G01X499202Y376096D02*
X501452D01*
G01X495822Y381947D02*
X498072D01*
G01X492442Y383896D02*
X494692D01*
G01X516102Y346847D02*
X518352D01*
G01X519481Y352696D02*
X521731D01*
G01X509342Y354647D02*
X511592D01*
G01X495822Y370247D02*
X498072D01*
G01X495822Y374146D02*
X498072D01*
G01X526241Y387796D02*
X528491D01*
G01X519481D02*
X521731D01*
G01X519481Y391696D02*
X521731D01*
G01X516102Y393647D02*
X518352D01*
G01X512722Y395597D02*
X514972D01*
G01X509342Y389747D02*
X511592D01*
G01X526241Y379996D02*
X528491D01*
G01X526241Y383896D02*
X528491D01*
G01X522861Y385847D02*
X525111D01*
G01X519481Y383896D02*
X521731D01*
G01X522861Y389747D02*
X525111D01*
G01X519481Y395597D02*
X521731D01*
G01X512722Y391696D02*
X514972D01*
G01X512722Y387796D02*
X514972D01*
G01X526241Y376096D02*
X528491D01*
G01X529621Y381947D02*
X531871D01*
G01X542011Y391696D02*
X539761D01*
G01X542011Y395597D02*
X539761D01*
G01Y387796D02*
X542011D01*
G01X539761Y399496D02*
X541500Y401235D01*
Y407300D01*
X548500Y414300D01*
X604900D01*
G01X536381Y401447D02*
X534600Y403228D01*
Y406008D01*
X544692Y416100D01*
X598500D01*
X601700Y419300D01*
X604900D01*
G01X533001Y348796D02*
X535251D01*
G01X533001Y344896D02*
X535251D01*
G01X542011D02*
X539761D01*
G01X536381Y346847D02*
X538631D01*
G01X536381Y342947D02*
X538631D01*
G01X536381Y354647D02*
X538631D01*
G01X536381Y358547D02*
X538631D01*
G01X536381Y362447D02*
X538631D01*
G01X529621D02*
X531871D01*
G01X529621Y366347D02*
X531871D01*
G01X533001Y372197D02*
X535251D01*
G01X533001Y376096D02*
X535251D01*
G01X533001Y379996D02*
X535251D01*
G01X536381Y350747D02*
X538631D01*
G01X542011Y356596D02*
X539761D01*
G01X533001Y360496D02*
X535251D01*
G01X529621Y358547D02*
X531871D01*
G01X533001Y364396D02*
X535251D01*
G01X533001Y368296D02*
X535251D01*
G01X536381Y374146D02*
X538631D01*
G01X529621Y378047D02*
X531871D01*
G01X522861Y346847D02*
X525111D01*
G01X526241Y348796D02*
X528491D01*
G01X529621Y342947D02*
X531871D01*
G01X526241Y344896D02*
X528491D01*
G01X526241Y352696D02*
X528491D01*
G01X485682Y356596D02*
X487932D01*
G01X489062Y342947D02*
X491312D01*
G01X489062Y354647D02*
X491312D01*
G01X509342Y401447D02*
X511592D01*
G01X505962Y383896D02*
X508212D01*
G01X512722Y376096D02*
X514972D01*
G01X509342Y405347D02*
X508733D01*
X504832Y401446D01*
G01X533001Y403396D02*
X533500Y403895D01*
Y407050D01*
X544150Y417700D01*
X598300D01*
X604900Y424300D01*
G01X633800Y119000D02*
X629600D01*
X620681Y127919D01*
X598077D01*
X592858Y122700D01*
X589650D01*
G01X563900Y213500D02*
Y212000D01*
X563300Y211400D01*
X560344D01*
X559272Y212472D01*
X557628D01*
X556661Y213439D01*
Y214247D01*
G01X560739Y207625D02*
X561347Y207017D01*
Y206308D01*
X560989Y205950D01*
X559300D01*
X558700Y206550D01*
Y207599D01*
X557699Y208600D01*
X555799D01*
X554147Y210252D01*
X552652D01*
X551400Y209000D01*
X550499D01*
X549901Y209598D01*
Y210346D01*
G01X556661D02*
Y210562D01*
X557621Y211522D01*
X558878D01*
X559950Y210450D01*
X563694D01*
X564481Y211237D01*
X565733D01*
X566051Y211555D01*
G01X562861Y205503D02*
X561886D01*
X561383Y205000D01*
X557091D01*
X552900Y206600D01*
X552620Y206796D01*
X550565Y208030D01*
X546800Y208372D01*
X546521Y208397D01*
G01X553281Y204496D02*
X552401D01*
X551900Y203995D01*
Y202999D01*
X553199Y201700D01*
X565460D01*
X566980Y202718D01*
X570653Y207195D01*
X574754Y217098D01*
X574780Y217124D01*
X575480Y218524D01*
X577559Y220603D01*
X579055D01*
X579652Y220006D01*
X581102D01*
G01X543141Y202547D02*
Y203197D01*
X542437Y203901D01*
X541801D01*
X541250Y203350D01*
Y201350D01*
X543067Y199534D01*
X548459Y197300D01*
X567947D01*
X575889Y200590D01*
X577375Y202076D01*
Y204125D01*
G01X549901Y202547D02*
X551008D01*
X552805Y200750D01*
X565749D01*
X567626Y202006D01*
X568201Y202708D01*
X568906Y202777D01*
X569477Y203474D01*
X569407Y204178D01*
X571477Y206701D01*
X572461Y209077D01*
X573115Y209348D01*
X573459Y210180D01*
X573189Y210834D01*
X573768Y212233D01*
X574423Y212503D01*
X574767Y213336D01*
X574497Y213989D01*
X575560Y216559D01*
X576261Y217961D01*
X577953Y219653D01*
X578661D01*
X578980Y219334D01*
Y217884D01*
G01X546521Y321496D02*
X548771D01*
G01X543141Y323446D02*
X545391D01*
G01X549901Y331247D02*
X552151D01*
G01X549901Y335147D02*
X552151D01*
G01X546521Y333196D02*
X548771D01*
G01X549901Y339047D02*
X552151D01*
G01X553281Y340996D02*
X555531D01*
G01X543141Y327347D02*
X545391D01*
G01X543141Y311747D02*
X545391D01*
G01X543141Y339047D02*
X545391D01*
G01X549901Y319547D02*
X552151D01*
G01X549901Y315647D02*
X552151D01*
G01X549901Y311747D02*
X552151D01*
G01X546521Y305896D02*
X548771D01*
G01X549901Y300047D02*
X552151D01*
G01X546521Y301996D02*
X548771D01*
G01X596600Y340900D02*
X594500D01*
X584700Y350700D01*
X561945D01*
X560041Y348796D01*
G01X562591Y340996D02*
X560041D01*
G01X556661Y339047D02*
X558911D01*
G01X559211Y331103D02*
X559067Y331247D01*
X556661D01*
G01X553281Y329296D02*
X555531D01*
G01X556661Y323446D02*
X559211D01*
G01X553281Y321496D02*
X555531D01*
G01X546521Y317596D02*
X548771D01*
G01X553281Y313696D02*
X555831D01*
G01X549901Y307847D02*
X552151D01*
G01X549901Y303947D02*
X552151D01*
G01X553281Y301996D02*
X555831D01*
G01X546521Y298096D02*
X548771D01*
G01X596600Y335900D02*
X594600D01*
X583700Y346800D01*
X556708D01*
X556661Y346847D01*
G01X560041Y337096D02*
X562591D01*
G01X553281D02*
X555531D01*
G01X556661Y327347D02*
X559211D01*
G01X549901D02*
X552151D01*
G01X553281Y325396D02*
X555531D01*
G01X555831Y317446D02*
X555681Y317596D01*
X553281D01*
G01X549901Y342947D02*
X552151D01*
G01X546521Y344896D02*
X548771D01*
G01X549901Y346847D02*
X552151D01*
G01X549901Y393647D02*
X552151D01*
G01X543141Y389747D02*
X545391D01*
G01X546521Y387796D02*
X548771D01*
G01X553281Y391696D02*
X554600Y393015D01*
Y394400D01*
X556200Y396000D01*
X579000D01*
X597400Y377600D01*
X610200D01*
G01X549901Y389747D02*
X553647D01*
X555700Y391800D01*
X580200D01*
X596500Y375500D01*
X603300D01*
X607900Y370900D01*
G01X546521Y391696D02*
X547900Y393075D01*
Y394400D01*
X549100Y395600D01*
X550600D01*
X552402Y397402D01*
X554101D01*
X554849Y398150D01*
X558105D01*
X561455Y401500D01*
X600681D01*
X601381Y400800D01*
G01X543141Y393647D02*
X545391D01*
G01X549901Y385847D02*
X552151D01*
G01X556661Y389747D02*
X559212D01*
G01X553281Y352696D02*
X555531D01*
G01X553281Y348796D02*
X555531D01*
G01X549901Y354647D02*
X552151D01*
G01X556661Y350747D02*
X558911D01*
G01X553281Y344896D02*
X555531D01*
G01X596600Y345900D02*
X595200D01*
X582553Y358547D01*
X556661D01*
G01X596600Y350900D02*
X594700D01*
X583153Y362447D01*
X556661D01*
G01Y366347D02*
X559211D01*
G01X549901D02*
X552151D01*
G01X549901Y370247D02*
X552151D01*
G01X596600Y365900D02*
X593000D01*
X582804Y376096D01*
X553281D01*
G01Y379996D02*
X555531D01*
G01X549901Y381947D02*
X552151D01*
G01X556661Y354647D02*
X558911D01*
G01X560041Y360496D02*
X561396D01*
X561400Y360500D01*
X563500D01*
G01X596600Y355900D02*
X594500D01*
X586004Y364396D01*
X553281D01*
G01X549901Y362447D02*
X552151D01*
G01X596600Y360900D02*
X593834D01*
X586438Y368296D01*
X553281D01*
G01Y372197D02*
X555531D01*
G01X596600Y370900D02*
X592300D01*
X585153Y378047D01*
X556661D01*
G01X553281Y383896D02*
X585004D01*
X595100Y373800D01*
X599500D01*
X602500Y370800D01*
G01X549901Y401447D02*
X554954Y406500D01*
X600681D01*
X601381Y405800D01*
G01X546521Y399496D02*
Y401151D01*
X544700Y402972D01*
Y404200D01*
X549300Y408800D01*
X596481D01*
G01X553281Y399496D02*
X555476D01*
X555750Y399770D01*
G01X549901Y397546D02*
Y399301D01*
X554400Y403800D01*
X596481D01*
G01X553281Y395597D02*
X554109D01*
X555562Y397050D01*
X560705D01*
X562455Y398800D01*
X596481D01*
G01X543141Y350747D02*
X545391D01*
G01X546521Y348796D02*
X548771D01*
G01X546521Y403396D02*
X548716D01*
X548990Y403670D01*
G01X543141Y405347D02*
X549094Y411300D01*
X600800D01*
X601300Y410800D01*
G01X648867Y31258D02*
X649600Y30525D01*
Y28500D01*
X645300Y24200D01*
Y5622D01*
X643959Y4281D01*
Y-2423D01*
X646309Y-4773D01*
X652492D01*
X654690Y-2575D01*
Y3070D01*
G01X652130D02*
Y-2134D01*
X650951Y-3313D01*
X646865D01*
X645459Y-1907D01*
Y3681D01*
X646800Y5022D01*
Y23684D01*
X651025Y27909D01*
Y30808D01*
X651442Y31225D01*
G01X605510Y-14877D02*
Y-9901D01*
G01Y22923D02*
Y27899D01*
G01X659747Y-12132D02*
X659843Y-12036D01*
Y-11343D01*
X659000Y-10500D01*
X656000D01*
X654690Y-11810D01*
Y-14930D01*
G01X605510Y3233D02*
Y-1743D01*
G01X652130Y-14930D02*
Y-11330D01*
X651400Y-10600D01*
X648500D01*
X647000Y-12100D01*
G01X615549Y22923D02*
Y27899D01*
G01Y-14877D02*
Y-9901D01*
G01X652000Y25500D02*
Y26145D01*
X653642Y27787D01*
Y30776D01*
X654016Y31150D01*
G01X658700Y25600D02*
Y23900D01*
X659700Y22900D01*
G01X655500Y25500D02*
X658600D01*
X658700Y25600D01*
G01X665396Y18406D02*
X663760D01*
X659700Y22466D01*
Y22900D01*
G01X605510Y60723D02*
Y65699D01*
G01Y41033D02*
Y36057D01*
G01Y78833D02*
Y73857D01*
G01X615549Y60723D02*
Y65699D01*
G01X636708Y277735D02*
X634264D01*
X633499Y278500D01*
X624501D01*
X618279Y272278D01*
Y251393D01*
G01X631250Y289650D02*
Y288604D01*
X635854Y284000D01*
X637300D01*
X638700Y282600D01*
Y276600D01*
X639320Y275980D01*
Y274550D01*
G01X646000Y265000D02*
X645100Y265900D01*
X644674D01*
X643591Y266983D01*
G01X646000Y272000D02*
Y272362D01*
X643500Y274862D01*
Y274868D01*
G01X646500Y268300D02*
X645140Y269660D01*
X642855D01*
G01X640566Y278324D02*
Y280040D01*
X641665Y281139D01*
G01X651500Y278100D02*
X655000D01*
G01D02*
X658500D01*
G01X660588Y272650D02*
Y274500D01*
X659739Y275349D01*
Y276861D01*
X658500Y278100D01*
G01X649500Y265000D02*
Y264200D01*
X651950Y261750D01*
G01D02*
X653062Y260638D01*
X656450D01*
G01X649500Y272000D02*
X651300D01*
X652700Y270600D01*
G01X656450Y263787D02*
X654913D01*
X654100Y264600D01*
Y269200D01*
X652700Y270600D01*
G01X656450Y262213D02*
X654187D01*
X652400Y264000D01*
Y266849D01*
G01D02*
Y267874D01*
X651974Y268300D01*
X650000D01*
G01X649500Y275300D02*
X650900D01*
X651200Y275600D01*
X652700D01*
G01D02*
X654000D01*
X654437Y275163D01*
Y273763D01*
X656450Y271750D01*
Y270087D01*
G01X659013Y272650D02*
Y274487D01*
X658000Y275500D01*
X656100D01*
G01X636708Y281235D02*
X628323D01*
X627529Y280441D01*
G01X628525Y287832D02*
X624668D01*
X624600Y287900D01*
G01X662200Y284800D02*
X663300Y283700D01*
Y281820D01*
G01X660128Y301548D02*
Y296830D01*
G01X658638Y291123D02*
Y294090D01*
X658853Y294305D01*
G01D02*
X660128Y295580D01*
Y296830D01*
G01X661730Y290008D02*
Y287819D01*
X661232Y287321D01*
G01X655500Y293500D02*
Y293900D01*
X657950Y296350D01*
Y296850D01*
G01X658159Y301548D02*
Y298647D01*
X657950Y298438D01*
Y296850D01*
G01X655000Y281600D02*
Y284600D01*
G01X649819Y307919D02*
X647481D01*
X646700Y308700D01*
Y308850D01*
G01X649819Y325640D02*
X647500D01*
X647040Y326100D01*
X646800D01*
G01X649819Y309888D02*
X647588D01*
X646700Y309000D01*
Y308850D01*
G01X658159Y335948D02*
Y338409D01*
X658900Y339150D01*
G01X660128Y335948D02*
Y337922D01*
X658900Y339150D01*
G01X649819Y327609D02*
X649077D01*
X646288Y328763D01*
X646272Y328800D01*
G01X640555Y346055D02*
X633384Y338884D01*
Y332516D01*
X636100Y329800D01*
G01X662097Y301548D02*
Y299980D01*
X661497Y299380D01*
Y297759D01*
X662238Y297018D01*
Y296146D01*
G01X661730Y293508D02*
Y295297D01*
X662238Y295805D01*
Y296146D01*
G01X732000Y380000D02*
X731180Y379180D01*
X722712D01*
X709646Y366114D01*
X695014D01*
X684378Y355478D01*
X644614D01*
X640555Y351419D01*
Y346055D01*
G01X612800Y466000D02*
X611325D01*
X608800Y463475D01*
G01X620400Y463990D02*
Y464323D01*
X619975Y464748D01*
X617552D01*
X616300Y466000D01*
G01X609191Y451454D02*
X611800Y448845D01*
Y445420D01*
X625507Y431713D01*
X644065D01*
X647277Y434925D01*
X648091D01*
G01X732000Y380000D02*
X731210Y380790D01*
X697935D01*
X697000Y381725D01*
Y384400D01*
X693900Y387500D01*
X691237D01*
X689298Y389439D01*
X682261D01*
X678100Y393600D01*
Y420600D01*
X671700Y427000D01*
X671367D01*
X671366Y427001D01*
X653201D01*
X652877Y427325D01*
X652875D01*
X651100Y429100D01*
Y434900D01*
X648900Y437100D01*
X647100D01*
X642800Y432800D01*
X629400D01*
X626600Y435600D01*
Y444700D01*
X629300Y447400D01*
X683800D01*
X686000Y449600D01*
Y457600D01*
X693700Y465300D01*
Y478300D01*
X686463Y485537D01*
Y499963D01*
X689200Y502700D01*
X701800D01*
X706900Y507800D01*
X709552D01*
X714669Y512917D01*
X715009D01*
G01X652230Y487690D02*
X655310D01*
X656100Y486900D01*
G01X645230Y487690D02*
X652230D01*
G01Y490250D02*
X655300D01*
X656050Y489500D01*
G01X641150Y484300D02*
Y489914D01*
X644036Y492800D01*
X645400D01*
X649200Y496600D01*
X653800D01*
G01X645230Y485130D02*
X641980D01*
X641150Y484300D01*
G01X670185Y492563D02*
X667137D01*
X663100Y496600D01*
X653800D01*
G01X612000Y484000D02*
X612490Y484490D01*
X616930D01*
G01X609284Y480055D02*
X611159Y481930D01*
X616930D01*
G01X605510Y523900D02*
Y528899D01*
G01X628700Y482000D02*
X631190Y484490D01*
X634930D01*
G01Y481930D02*
X630982D01*
X629389Y480337D01*
X626800D01*
X625569Y481568D01*
G01X612534Y472759D02*
X609516D01*
X608800Y473475D01*
G01X616034Y472759D02*
X617775Y474500D01*
X618800D01*
G01D02*
X620541Y472759D01*
X622000D01*
G01X612334Y469559D02*
X609884D01*
X608800Y468475D01*
G01X615834Y469559D02*
X617926D01*
X618197Y469830D01*
X619010D01*
X619390Y469450D01*
G01D02*
X619770Y469830D01*
X621329D01*
X622000Y469159D01*
G01X615549Y523900D02*
Y528899D01*
G01X639120Y475620D02*
X640000Y476500D01*
Y479000D01*
X639630Y479370D01*
X634930D01*
G01X679000Y517750D02*
X678250D01*
X677300Y516800D01*
Y506199D01*
X674259Y503158D01*
X670958D01*
X666400Y498600D01*
X648800D01*
X648000Y497800D01*
X642600D01*
G01D02*
X639197Y494397D01*
Y490367D01*
G01X605510Y561700D02*
Y566699D01*
G01Y542010D02*
Y537057D01*
G01Y579810D02*
Y574857D01*
G01X615549Y561700D02*
Y566699D01*
G01X659400Y587500D02*
X659500Y587600D01*
Y591500D01*
G01X665795Y582399D02*
X662475D01*
X659500Y585374D01*
Y587400D01*
X659400Y587500D01*
G01D02*
X661100D01*
X661800Y588200D01*
Y588800D01*
X662000Y589000D01*
G01X605510Y599500D02*
Y604499D01*
G01Y617610D02*
Y612657D01*
G01X615549Y599500D02*
Y604499D01*
G01X656000Y591500D02*
Y595023D01*
X656700Y595723D01*
Y609900D01*
X655100Y611500D01*
G01X704150Y19650D02*
Y16350D01*
X707600Y12900D01*
Y-14544D01*
X711389Y-18333D01*
X713824D01*
G01X710150Y-9450D02*
Y-11791D01*
X710327Y-11968D01*
G01X695300Y17900D02*
X695748Y18348D01*
Y19347D01*
X697901Y21500D01*
X706000D01*
X712000Y27500D01*
Y29000D01*
G01X695300Y17900D02*
X694000D01*
X692400Y19500D01*
Y20800D01*
G01X710551Y658D02*
X710150Y257D01*
Y-5950D01*
G01X713937Y-6048D02*
X710248D01*
X710150Y-5950D01*
G01X716921Y-6048D02*
Y-6100D01*
X713989D01*
X713937Y-6048D01*
G01X719031Y-652D02*
Y-1722D01*
X716921Y-3832D01*
Y-6048D01*
G01X702400Y23700D02*
Y31774D01*
X702826Y32200D01*
X704500D01*
G01D02*
Y37300D01*
X702453Y39347D01*
Y41350D01*
G01X708500Y32500D02*
X706463D01*
X706163Y32200D01*
X704500D01*
G01X712000Y32500D02*
X708500D01*
G01X712500Y17500D02*
X708900D01*
G01X711300Y12200D02*
X708900Y14600D01*
Y17500D01*
G01X717063Y10652D02*
X712848D01*
X711300Y12200D01*
G01X712500Y17500D02*
X713945D01*
X713993Y17452D01*
X715937D01*
G01X676700Y20374D02*
Y22610D01*
X677350Y23260D01*
Y27300D01*
G01X683900Y21500D02*
X680700Y24700D01*
G01X683900Y21500D02*
X683400Y21000D01*
Y17900D01*
G01X677350Y27300D02*
X678100D01*
X680700Y24700D01*
G01X675800Y30800D02*
Y34200D01*
G01X711791Y23716D02*
X711616D01*
X708900Y21000D01*
G01X670400Y26100D02*
X671600Y27300D01*
X673850D01*
G01X718916Y92446D02*
X717326Y90856D01*
X697356D01*
X697100Y90600D01*
G01X670227Y34277D02*
X670404Y34100D01*
X672900D01*
G01D02*
X673000Y34200D01*
X675800D01*
G01X688350Y43642D02*
Y41154D01*
X686387Y39191D01*
Y38635D01*
X685884Y38132D01*
X683077D01*
X681130Y36185D01*
Y36130D01*
X679300Y34300D01*
Y34200D01*
G01X711074Y92446D02*
X714176D01*
X716053Y94323D01*
G01X720596Y84030D02*
X723703Y87137D01*
Y92082D01*
X721462Y94323D01*
X716053D01*
G01X714700Y75690D02*
X720596Y81586D01*
Y84030D01*
G01X716053Y94323D02*
X715089Y95287D01*
Y99266D01*
X715753Y99930D01*
X718916D01*
G01X700400Y257200D02*
X702100Y258900D01*
X703700D01*
G01X717420Y249920D02*
Y250260D01*
X717000Y250680D01*
Y252500D01*
G01X663738Y272650D02*
Y276284D01*
X664456Y277002D01*
Y278867D01*
X663300Y280023D01*
Y281820D01*
G01X714100Y271063D02*
X712562D01*
X711096Y269597D01*
X703438D01*
G01X665313Y272650D02*
Y274970D01*
X665463Y275120D01*
Y278893D01*
X665451Y278905D01*
Y280697D01*
X665463Y280709D01*
Y284337D01*
X665000Y284800D01*
G01X714100Y272638D02*
X712898D01*
X710690Y270430D01*
X705320D01*
G01X720500Y252500D02*
Y250000D01*
X720450Y249950D01*
G01D02*
X720500Y249900D01*
Y247500D01*
G01X723400Y250000D02*
X723500Y249900D01*
Y247500D01*
G01Y252500D02*
Y250100D01*
X723400Y250000D01*
G01X723138Y263600D02*
Y260138D01*
X721921Y258921D01*
G01D02*
X720500Y257500D01*
Y256000D01*
G01X724713Y263600D02*
Y258685D01*
X723500Y257472D01*
Y256000D01*
G01X711000D02*
X713900Y258900D01*
X715200D01*
G01X718413Y263600D02*
Y262113D01*
X715200Y258900D01*
G01X675750Y257488D02*
X677212D01*
X678400Y256300D01*
Y254700D01*
X677800Y254100D01*
G01X701134Y253677D02*
X701757Y254300D01*
X704662D01*
X705837Y255475D01*
Y257274D01*
X706226Y257663D01*
X707002D01*
X707200Y257861D01*
Y258900D01*
G01X707000Y265500D02*
Y262000D01*
G01D02*
Y260700D01*
X707200Y260500D01*
Y258900D01*
G01X714100Y267913D02*
X712813D01*
X710400Y265500D01*
X707000D01*
G01X707500Y256000D02*
X708000D01*
X710500Y258500D01*
Y260000D01*
X710700Y260200D01*
G01X716839Y263600D02*
X715739Y262500D01*
X714500D01*
X712200Y260200D01*
X710700D01*
G01X717000Y256000D02*
Y257560D01*
X718246Y258806D01*
G01X717000Y256000D02*
X714000D01*
G01X719988Y263600D02*
Y261488D01*
X719200Y260700D01*
Y259760D01*
X718246Y258806D01*
G01X714100Y266339D02*
X713589D01*
X710675Y263425D01*
G01X678268Y285588D02*
X680012D01*
X683490Y282110D01*
G01X685268Y290706D02*
X688773D01*
X690680Y288799D01*
Y287080D01*
X686470Y282870D01*
Y282220D01*
G01X673500Y295000D02*
Y297656D01*
X673922Y298078D01*
G01X671942Y301548D02*
Y300058D01*
X673922Y298078D01*
G01X677849Y301548D02*
Y300321D01*
X678840Y299330D01*
X681748D01*
X683300Y297778D01*
X685658D01*
X686140Y298260D01*
G01X692470Y293640D02*
X687850Y298260D01*
X686140D01*
G01X684056Y295292D02*
X681088Y298260D01*
X677390D01*
X675880Y299770D01*
Y301548D01*
G01X685268Y285588D02*
X683162D01*
X682000Y286750D01*
Y292080D01*
X684056Y294136D01*
Y295292D01*
G01X673911Y301548D02*
Y300459D01*
X677395Y296975D01*
X679145D01*
X680624Y295496D01*
Y295168D01*
G01D02*
Y294374D01*
X678268Y292018D01*
Y290706D01*
G01X705000Y335500D02*
X702400Y338100D01*
X702000D01*
X701100Y339000D01*
G01X684219Y327609D02*
X686809D01*
X687400Y328200D01*
G01X675880Y335948D02*
Y338020D01*
X674700Y339200D01*
G01X673911Y335948D02*
Y338411D01*
X674700Y339200D01*
G01X698600Y338900D02*
Y337900D01*
X701000Y335500D01*
G01X684219Y307919D02*
X687569D01*
X688100Y308450D01*
Y308600D01*
G01X684219Y309888D02*
X686862D01*
X688100Y308650D01*
Y308600D01*
G01X684219Y325640D02*
X686860D01*
X687300Y325200D01*
G01X685268Y288147D02*
X688924D01*
G01X678268D02*
X675241D01*
X674469Y287375D01*
G01X692647Y379176D02*
Y384075D01*
X690647Y386075D01*
X690646D01*
X688707Y388014D01*
X680076D01*
X679385Y388705D01*
G01X686619Y392600D02*
X689050D01*
X692647Y396197D01*
Y402676D01*
G01X682407D02*
Y398093D01*
X683200Y397300D01*
X684700D01*
G01X684967Y402676D02*
Y397567D01*
X684700Y397300D01*
G01D02*
X683100Y395700D01*
Y392200D01*
G01X690087Y379176D02*
Y384618D01*
X688116Y386589D01*
X680304D01*
X679523Y385808D01*
G01X691240Y390039D02*
X691179Y390100D01*
X690653D01*
X689889Y390864D01*
X685393D01*
X684956Y391301D01*
Y394168D01*
X690087Y399299D01*
Y402676D01*
G01X678730Y362841D02*
X678772Y362799D01*
Y359140D01*
G01X679847Y379176D02*
Y375365D01*
X681796Y373416D01*
X683056D01*
X684126Y372346D01*
Y369876D01*
G01D02*
X681822D01*
X680498Y371200D01*
X679400D01*
G01X684967Y379176D02*
Y382959D01*
X686934Y384926D01*
X687427D01*
G01X682407Y379176D02*
Y383150D01*
X681457Y384100D01*
X678800D01*
X676900Y382200D01*
Y381800D01*
G01X687527Y379176D02*
Y373573D01*
X689900Y371200D01*
G01D02*
X693346D01*
X694662Y369884D01*
G01X733091Y454925D02*
X733100Y455000D01*
Y456251D01*
X719225Y470126D01*
Y482404D01*
X715845Y485784D01*
Y501934D01*
X718488Y504577D01*
Y509261D01*
X720565Y511338D01*
G01X710760Y488200D02*
Y485540D01*
X712441Y483859D01*
Y468446D01*
X718100Y462787D01*
Y455000D01*
X718091Y454925D01*
G01Y449925D02*
X718100Y450000D01*
Y452200D01*
X720600Y454700D01*
Y462702D01*
X713866Y469436D01*
Y483836D01*
X713015Y484687D01*
Y500486D01*
X707850Y505651D01*
Y505700D01*
G01X693091Y434925D02*
X695700Y432316D01*
Y425296D01*
X696400Y424596D01*
Y420275D01*
G01X713200Y505500D02*
X715000Y507300D01*
X715198D01*
X715211Y507313D01*
X716789D01*
X717563Y506539D01*
Y504961D01*
X714920Y502318D01*
Y485400D01*
X718300Y482020D01*
Y469035D01*
X725200Y462135D01*
Y452034D01*
X723091Y449925D01*
G01X693091Y429925D02*
Y424109D01*
X693200Y424000D01*
Y420275D01*
G01X723091Y454925D02*
Y462228D01*
X716100Y469219D01*
Y480260D01*
G01X684550Y492970D02*
Y490250D01*
X683700Y489400D01*
X679700D01*
G01D02*
X680525Y490225D01*
X681275D01*
X681990Y490940D01*
Y492970D01*
G01X670185Y492563D02*
X671363D01*
X678770Y499970D01*
X679430D01*
G01X682050Y503970D02*
Y500030D01*
X681990Y499970D01*
G01X733091Y449925D02*
X735300Y452134D01*
Y455701D01*
X720500Y470501D01*
Y482438D01*
X716808Y486130D01*
Y501588D01*
X719500Y504280D01*
Y507072D01*
X721414Y508986D01*
G01X720300Y485800D02*
X723775Y482325D01*
Y471226D01*
X738091Y456910D01*
Y454925D01*
G01X723792Y489148D02*
X727063Y485877D01*
Y472536D01*
X743091Y456508D01*
Y454925D01*
G01X721301Y488200D02*
X724056Y485445D01*
Y485344D01*
X725400Y484000D01*
Y471900D01*
X740700Y456600D01*
Y452316D01*
X743091Y449925D01*
G01X712100Y515250D02*
Y512700D01*
G01X670400Y497700D02*
X673000D01*
X676600Y501300D01*
G01X708500Y518750D02*
X712100D01*
G01X704500D02*
X708500D01*
G01X704500D02*
Y523900D01*
X702453Y525947D01*
Y527600D01*
G01X704500Y518750D02*
X702951D01*
X702300Y518099D01*
Y510000D01*
X702100Y509800D01*
G01X679000Y517750D02*
Y521250D01*
X678650Y521600D01*
G01X688350Y529892D02*
Y527349D01*
X686000Y524999D01*
Y524250D01*
X683350Y521600D01*
X682150D01*
G01X711339Y499478D02*
Y491039D01*
X710760Y490460D01*
Y488200D01*
G01X715900Y505650D02*
X713992Y503742D01*
Y485019D01*
X714791Y484220D01*
Y481569D01*
X716100Y480260D01*
G01X704655Y567556D02*
X703344D01*
X702100Y568800D01*
G01X702000Y571400D02*
X702538Y570862D01*
X704653D01*
G01X723980Y584050D02*
X724974D01*
X725400Y583624D01*
Y580900D01*
G01X686450Y591000D02*
Y587850D01*
X686500Y587800D01*
G01X677099Y584367D02*
Y589116D01*
X677880Y589897D01*
Y591560D01*
G01X693200Y575900D02*
X695600D01*
X698730Y579030D01*
Y585220D01*
X692950Y591000D01*
X689950D01*
G01X708155Y567556D02*
X712511Y563200D01*
X729980D01*
X736110Y557070D01*
Y547554D01*
X741589Y542075D01*
X744738D01*
X751056Y535757D01*
Y530153D01*
X745670Y524767D01*
X741259D01*
X729875Y513383D01*
Y512375D01*
X729000Y511500D01*
G01X731600Y511600D02*
X730802Y512398D01*
Y513001D01*
X741643Y523842D01*
X746054D01*
X751981Y529769D01*
Y535373D01*
X751982Y535374D01*
Y536140D01*
X745122Y543000D01*
X741973D01*
X737035Y547938D01*
Y557454D01*
X730364Y564125D01*
X714890D01*
X708153Y570862D01*
G01X722012Y595354D02*
Y598556D01*
X722406Y598950D01*
G01D02*
X723956Y600500D01*
X726800D01*
G01X682640Y591000D02*
X686450D01*
G01X677880Y591560D02*
X680150D01*
X680710Y591000D01*
X682640D01*
G01X765186Y218589D02*
X764289D01*
X762300Y216600D01*
G01X726328Y249979D02*
X726500Y250151D01*
Y252500D01*
G01X726287Y263600D02*
Y258979D01*
G01D02*
Y257985D01*
X726500Y257772D01*
Y256000D01*
G01X728291Y247500D02*
Y252966D01*
X730000Y254675D01*
G01X727862Y263600D02*
Y259098D01*
X728770Y258190D01*
Y255905D01*
X730000Y254675D01*
G01X761850Y279060D02*
Y282668D01*
X761942Y282760D01*
G01X761600Y249020D02*
X756879D01*
X756639Y248780D01*
G01X731012Y286400D02*
Y291412D01*
X732700Y293100D01*
G01D02*
X734200Y294600D01*
Y297650D01*
G01X771773Y284235D02*
X770435D01*
X768930Y282730D01*
X761972D01*
X761942Y282760D01*
G01X759900Y309188D02*
X762417Y311705D01*
Y316392D01*
G01X762350Y347230D02*
X763020D01*
X763912Y346338D01*
X765700D01*
X766236Y346874D01*
X768426D01*
X769787Y348235D01*
X771773D01*
G01X738091Y449925D02*
X738100Y450000D01*
X740015Y448085D01*
Y447483D01*
X739933Y447401D01*
G01X746151Y433077D02*
X744303Y434925D01*
X743091D01*
G01X746130Y430130D02*
X745930D01*
X745725Y429925D01*
X743091D01*
G01Y444925D02*
X744625D01*
X747950Y441600D01*
G01X743091Y439925D02*
X747475D01*
X748500Y438900D01*
G01X738648Y492050D02*
Y495153D01*
X737648Y496153D01*
X735758D01*
G01X726040Y506080D02*
X730709D01*
X733152Y503637D01*
X734056D01*
G01X735758D02*
X734056D01*
G01D02*
X732469Y502050D01*
Y498372D01*
X730250Y496153D01*
X727916D01*
G01X726500Y577500D02*
X730050D01*
X730100Y577450D01*
G01X725400Y580900D02*
X726500Y579800D01*
Y577500D01*
G01X732600Y573950D02*
X730100D01*
G01Y604000D02*
X733032D01*
G01X726800Y600500D02*
X730100D01*
G01X823206Y192202D02*
X818960Y196448D01*
Y202230D01*
G01X817821Y193049D02*
Y200310D01*
X814849Y203282D01*
Y205001D01*
G01X813248Y190338D02*
Y191904D01*
X816164Y194820D01*
Y199920D01*
X812555Y203529D01*
X808165D01*
G01X797717Y201907D02*
X797123Y201313D01*
Y194410D01*
X799224Y192309D01*
G01X792514Y201290D02*
X787572D01*
X786709Y200427D01*
G01X800610Y415000D02*
X800620Y415010D01*
Y416120D01*
X801500Y417000D01*
X803500D01*
G01X798500Y412600D02*
Y416500D01*
X802000Y420000D01*
X803500D01*
G01X957285Y22923D02*
X957283D01*
Y28014D01*
G01X957285Y-14877D02*
X957283D01*
Y-7662D01*
X957765Y-7180D01*
G01X967324Y3233D02*
X967322Y-4536D01*
G01X957285Y60723D02*
X957283D01*
Y67549D01*
X957536Y67802D01*
G01X967324Y78833D02*
X967322Y73757D01*
G01X967324Y41033D02*
X967322Y35957D01*
G01X926477Y205210D02*
X924227D01*
G01X923097Y207159D02*
X920847D01*
G01X919717Y209109D02*
X917467D01*
G01X929857Y199360D02*
X927607D01*
G01X926477Y201309D02*
X924227D01*
G01X946757Y197409D02*
X944507D01*
G01X926477Y209109D02*
X924227D01*
G01X923097Y203260D02*
X920847D01*
G01X963656Y242260D02*
X961406D01*
G01X967036Y244209D02*
X964786D01*
G01X963656Y246160D02*
X961406D01*
G01X967036Y248109D02*
X964786D01*
G01X960276D02*
X958026D01*
G01X970416Y250060D02*
X968166D01*
G01X973796Y252009D02*
X971546D01*
G01X946757Y267609D02*
X944507D01*
G01X950137Y269560D02*
X947887D01*
G01X953517Y271509D02*
X951267D01*
G01X950137Y273460D02*
X947887D01*
G01X943377D02*
X941127D01*
G01X929857D02*
X927607D01*
G01X973796Y279310D02*
X971546D01*
G01X946757Y271509D02*
X944507D01*
G01X926477D02*
X924227D01*
G01X943377Y320260D02*
X941127D01*
G01X936617D02*
X934367D01*
G01X939997Y322209D02*
X937747D01*
G01X933237D02*
X930987D01*
G01X943377Y324160D02*
X941127D01*
G01X929857D02*
X927607D01*
G01X946757Y326110D02*
X944507D01*
G01X946757Y330009D02*
X944507D01*
G01X967036Y349509D02*
X964786D01*
G01X967036Y353409D02*
X964786D01*
G01X963656Y355360D02*
X961406D01*
G01X963656Y347560D02*
X961406D01*
G01X963656Y351460D02*
X961406D01*
G01X926477Y400209D02*
X924227D01*
G01X933237D02*
X930987D01*
G01X923097Y394359D02*
X920847D01*
G01X919717Y392410D02*
X917467D01*
G01X946757Y400209D02*
X944507D01*
G01X967036Y384609D02*
X964786D01*
G01X967036Y380709D02*
X964786D01*
G01X923097Y398260D02*
X920847D01*
G01X929857D02*
X927607D01*
G01X960276Y349509D02*
X958026D01*
G01X973796Y341709D02*
X971546D01*
G01X926477Y396309D02*
X924227D01*
G01X973796Y345609D02*
X971546D01*
G01X957285Y523900D02*
X957283Y523923D01*
Y528340D01*
X957806Y528863D01*
G01X957285Y561700D02*
X957283Y561723D01*
Y566434D01*
X957592Y566743D01*
G01X967324Y542010D02*
X967322Y536957D01*
G01X967324Y579810D02*
X967322Y574757D01*
G01X957285Y599500D02*
X957283Y599523D01*
Y606738D01*
X957765Y607220D01*
G01X967324Y617610D02*
X967322Y609864D01*
G01X994076Y216909D02*
X991826D01*
G01X987316Y205210D02*
X988446Y207158D01*
G01X990696Y207159D02*
X989900Y206363D01*
Y204712D01*
X988446Y203258D01*
G01X997456Y211060D02*
X995206D01*
G01X1000836Y213009D02*
X998586D01*
G01X987316Y220809D02*
X985066D01*
G01X997456Y222760D02*
X995206D01*
G01X983936D02*
X981686D01*
G01X980556Y224709D02*
X978306D01*
G01X983936Y226660D02*
X981686D01*
G01X987316Y228610D02*
X985066D01*
G01X980556D02*
X978306D01*
G01X983936Y230559D02*
X981686D01*
G01X987316Y232509D02*
X985066D01*
G01X1014355Y248109D02*
X1012105D01*
G01X1010975Y250060D02*
X1008725D01*
G01X1004215D02*
X1001965D01*
G01X997456D02*
X995206D01*
G01X1007595Y252009D02*
X1005345D01*
G01X1000836D02*
X998586D01*
G01X1010975Y253960D02*
X1008725D01*
G01X1004215D02*
X1001965D01*
G01X997456D02*
X995206D01*
G01X1007595Y255909D02*
X1005345D01*
G01X1000836D02*
X998586D01*
G01X1004215Y257860D02*
X1001965D01*
G01X997456D02*
X995206D01*
G01X1000836Y259809D02*
X998586D01*
G01X997456Y261760D02*
X995206D01*
G01X990696Y269560D02*
X988446D01*
G01X987316Y271509D02*
X985066D01*
G01X980556D02*
X978306D01*
G01X990696Y273460D02*
X988446D01*
G01X983936D02*
X981686D01*
G01X987316Y275409D02*
X985066D01*
G01X980556D02*
X978306D01*
G01X990696Y277360D02*
X988446D01*
G01X983936D02*
X981686D01*
G01X977176D02*
X974926D01*
G01X987316Y279310D02*
X985066D01*
G01X980556D02*
X978306D01*
G01X1034635Y240309D02*
X1032385D01*
G01X1031255Y242260D02*
X1029005D01*
G01X1034635Y244209D02*
X1032385D01*
G01X1025625D02*
X1027875D01*
G01X1031255Y246160D02*
X1029005D01*
G01X1024495D02*
X1022245D01*
G01X1017735D02*
X1015485D01*
G01X1021115Y248109D02*
X1018865D01*
G01X1017735Y250060D02*
X1015485D01*
G01X1014355Y252009D02*
X1012105D01*
G01X1004215Y339760D02*
X1001965D01*
G01X1007595Y345609D02*
X1005345D01*
G01X1034635Y353409D02*
X1032385D01*
G01X1000836Y384609D02*
X998586D01*
G01X987316Y376809D02*
X985066D01*
G01X983936Y374860D02*
X981686D01*
G01X997456D02*
X995206D01*
G01X980556Y372909D02*
X978306D01*
G01X983936Y370959D02*
X981686D01*
G01X980556Y369010D02*
X978306D01*
G01X987316D02*
X985066D01*
G01X983936Y367060D02*
X981686D01*
G01X987316Y365109D02*
X985066D01*
G01X990696Y363160D02*
X988446D01*
G01X1034635Y357309D02*
X1032385D01*
G01X1031255Y355360D02*
X1029005D01*
G01X1017735Y351460D02*
X1015485D01*
G01X1022245D02*
X1024495D01*
G01X1031255D02*
X1029005D01*
G01X994076Y349509D02*
X991826D01*
G01X1014355D02*
X1012105D01*
G01X1025625D02*
X1027875D01*
G01X997456Y347560D02*
X995206D01*
G01X1004215D02*
X1001965D01*
G01X1004215Y343660D02*
X1001965D01*
G01X1010975D02*
X1008725D01*
G01X1014355Y345609D02*
X1012105D01*
G01X1017735Y347560D02*
X1015485D01*
G01X1007595Y341709D02*
X1005345D01*
G01X1010975Y347560D02*
X1008725D01*
G01X1071065Y3233D02*
X1071062Y-1817D01*
G01X1061025Y3233D02*
X1061023Y-4536D01*
G01X1044291Y56908D02*
X1044293Y56910D01*
Y60723D01*
G01X1071065Y41033D02*
X1071063D01*
Y46921D01*
X1071064Y46922D01*
G01Y73757D02*
X1071063Y73758D01*
Y78833D01*
X1071065D01*
G01X1044100Y54700D02*
X1042500Y56300D01*
Y70872D01*
X1043402Y71774D01*
X1069081D01*
X1071064Y73757D01*
G01X1087797Y78833D02*
X1087795D01*
Y73759D01*
X1087797Y73757D01*
G01Y41033D02*
X1087795D01*
Y35959D01*
X1087797Y35957D01*
G01X1061025Y78833D02*
X1061024Y73757D01*
G01X1061025Y41033D02*
X1061024Y35957D01*
G01X1044293Y60723D02*
Y68961D01*
X1044290Y68964D01*
G01X1051534Y211060D02*
X1049284D01*
G01X1048154Y244209D02*
X1045904D01*
G01X1048154Y240309D02*
X1045904D01*
G01X1094764Y271972D02*
X1096290D01*
X1097411Y270851D01*
Y267611D01*
X1095700Y265900D01*
G01X1080500Y272000D02*
X1082200Y270300D01*
X1083600D01*
X1087500Y266400D01*
Y266000D01*
X1089000Y264500D01*
X1089100D01*
G01X1092300Y267200D02*
X1088000Y271500D01*
Y272000D01*
G01X1095700Y268790D02*
X1095490Y269000D01*
X1093000D01*
X1091500Y270500D01*
Y272000D01*
G01X1089000Y267000D02*
X1084500Y271500D01*
Y272000D01*
G01X1051534Y242260D02*
X1049284D01*
G01X1041395Y240309D02*
X1039145D01*
G01X1044774Y242260D02*
X1042524D01*
G01X1038015D02*
X1035765D01*
G01X1041395Y244209D02*
X1039145D01*
G01X1044774Y246160D02*
X1042524D01*
G01X1038015D02*
X1035765D01*
G01X1054914Y244209D02*
X1057314D01*
G01X1051534Y246160D02*
X1049284D01*
G01X1076270Y335780D02*
X1075220Y336830D01*
Y342380D01*
X1076435Y343595D01*
G01X1051534Y359260D02*
X1049284D01*
G01X1058294D02*
X1060948D01*
X1061039Y359351D01*
G01X1058294Y370959D02*
X1060963D01*
G01X1058294Y355360D02*
X1060694D01*
G01X1058294Y363160D02*
X1061055D01*
G01X1054914Y353409D02*
X1052664D01*
G01X1058294Y367060D02*
X1064371D01*
G01X1038015Y355360D02*
X1035765D01*
G01X1054914Y396309D02*
X1052664D01*
G01X1058294Y394359D02*
X1060694D01*
G01X1058294Y390460D02*
X1060694D01*
G01X1051534Y386560D02*
X1049284D01*
G01X1058294D02*
X1060694D01*
G01X1058294Y382660D02*
X1060694D01*
G01X1058294Y378760D02*
X1060694D01*
G01X1048154Y400209D02*
Y402900D01*
G01X1084591Y378047D02*
X1086841D01*
G01X1087971Y376096D02*
X1090221D01*
G01X1091351Y374146D02*
X1093601D01*
G01X1091351Y370247D02*
X1093601D01*
G01X1051534Y355360D02*
X1049284D01*
G01X1077832Y358547D02*
X1080082D01*
G01X1081212Y356596D02*
X1083462D01*
G01X1051534Y398260D02*
X1051717Y398666D01*
X1052500Y400400D01*
G01X1044195Y529026D02*
X1044293Y528928D01*
Y523900D01*
G01X1071065Y579810D02*
Y585721D01*
X1071064Y585722D01*
G01X1071065Y542010D02*
Y547921D01*
X1071064Y547922D01*
G01X1087797Y542010D02*
X1087795D01*
Y536959D01*
X1087797Y536957D01*
G01Y579810D02*
Y574757D01*
G01X1061025Y542010D02*
X1061024Y536957D01*
G01X1061025Y579810D02*
X1061024Y574757D01*
G01X1044195Y529026D02*
X1042377Y530844D01*
Y554044D01*
X1044291Y555958D01*
Y561700D01*
G01X1044293D02*
X1044291D01*
G01X1044290Y569492D02*
Y572210D01*
X1042378Y574122D01*
Y589678D01*
X1044293Y591593D01*
Y599500D01*
G01X1044291Y561700D02*
Y569491D01*
X1044290Y569492D01*
G01X1071065Y617610D02*
X1071062Y612560D01*
G01X1061025Y617610D02*
X1061023Y609864D01*
G01X1044293Y599500D02*
X1044291D01*
Y607291D01*
G01X1046500Y623500D02*
X1043425D01*
X1042000Y622075D01*
Y612000D01*
X1044291Y609709D01*
Y607291D01*
G01D02*
X1044290Y607292D01*
G01X1131910Y210346D02*
X1129660D01*
G01X1133040Y212296D02*
X1135290D01*
G01X1148810Y255196D02*
X1151060D01*
G01X1148810Y251296D02*
X1151060D01*
G01X1138670Y261047D02*
X1136420D01*
G01X1133040Y262996D02*
X1135290D01*
G01X1155570Y274696D02*
X1157820D01*
G01X1152190Y268847D02*
X1154440D01*
G01X1138670Y272747D02*
X1140920D01*
G01X1152190Y276646D02*
X1154439D01*
X1154440Y276647D01*
G01X1105175Y277317D02*
X1107607D01*
X1108125Y276799D01*
G01X1145430Y249347D02*
X1147680D01*
G01X1145430Y276646D02*
X1147679D01*
X1147680Y276647D01*
G01X1138670Y276646D02*
X1140919D01*
X1140920Y276647D01*
G01X1152190Y272747D02*
X1154440D01*
G01X1145430Y253247D02*
X1147680D01*
G01X1145430Y257147D02*
X1147680D01*
G01X1155570Y243496D02*
X1157820D01*
G01X1145430Y272747D02*
X1147680D01*
G01X1148810Y278596D02*
X1151060D01*
G01X1133040Y239596D02*
X1135290D01*
G01X1142050Y274696D02*
X1144300D01*
G01X1130780Y321496D02*
X1128530D01*
G01X1135290Y313696D02*
X1137540D01*
G01X1130780Y325396D02*
X1128530D01*
G01X1138670Y315647D02*
X1140920D01*
G01X1131910Y319547D02*
X1134160D01*
G01X1130780Y317596D02*
X1128530D01*
G01X1130780Y333196D02*
X1128530D01*
G01X1131910Y331247D02*
X1134160D01*
G01X1148810Y337096D02*
X1151060D01*
G01X1152190Y280547D02*
X1154440D01*
G01X1138670Y288347D02*
X1140920D01*
G01X1138670Y284447D02*
X1140920D01*
G01X1145430D02*
X1147680D01*
G01X1145430Y288347D02*
X1147680D01*
G01X1148810Y286396D02*
X1151060D01*
G01X1142050Y290296D02*
X1144300D01*
G01X1145430Y292247D02*
X1147680D01*
G01X1152190D02*
X1154440D01*
G01X1155570Y282496D02*
X1157820D01*
G01X1154440Y288347D02*
X1152190D01*
G01Y284447D02*
X1154440D01*
G01X1142050Y282496D02*
X1144300D01*
G01X1155570Y286396D02*
X1157820D01*
G01X1138670Y280547D02*
X1140920D01*
G01X1110500Y288000D02*
X1111674Y286826D01*
X1116999D01*
G01X1147680Y280547D02*
X1145430D01*
G01X1110500Y299000D02*
X1112700D01*
X1113900Y297800D01*
G01X1135290Y286396D02*
X1137540D01*
G01X1109840Y322680D02*
X1112800Y322700D01*
X1113500Y323400D01*
G01X1110500Y295000D02*
X1113132Y292368D01*
Y291702D01*
G01X1114340Y280560D02*
Y281702D01*
X1113915Y282127D01*
X1112873D01*
X1110500Y284500D01*
G01X1115230Y289252D02*
X1112748D01*
X1110500Y291500D01*
G01X1142050Y298096D02*
X1144300D01*
G01X1135290Y301996D02*
X1137540D01*
G01X1116096Y295809D02*
Y298004D01*
X1111600Y302500D01*
X1110500D01*
G01X1106340Y322680D02*
Y323600D01*
X1107840Y325100D01*
X1109200D01*
G01X1155570Y364396D02*
X1157820D01*
G01X1152190Y370247D02*
X1154439D01*
X1154440Y370246D01*
G01X1155570Y376096D02*
X1157820D01*
G01X1148810Y372197D02*
X1151059D01*
X1151060Y372196D01*
G01X1145430Y378047D02*
X1147680D01*
G01X1142050Y379996D02*
X1144300D01*
G01X1142050Y387796D02*
X1144300D01*
G01X1157820Y368296D02*
X1155570D01*
G01Y372197D02*
X1157819D01*
X1157820Y372196D01*
G01X1154440Y374146D02*
X1152190D01*
G01X1148810Y376096D02*
X1151060D01*
G01X1145430Y381947D02*
X1147680D01*
G01X1142050Y383896D02*
X1144300D01*
G01X1145430Y370247D02*
X1147680D01*
G01Y374146D02*
X1145430D01*
G01X1120641Y342947D02*
X1118391D01*
G01X1138670D02*
X1140920D01*
G01X1138670Y354647D02*
X1140920D01*
G01X1155570Y383896D02*
X1157820D01*
G01X1135290Y356596D02*
X1137540D01*
G01X1108251Y344896D02*
X1110501D01*
G01X1158950Y405347D02*
X1156699Y403096D01*
Y401447D01*
G01X1217275Y127924D02*
Y129685D01*
X1218674Y131084D01*
X1223226D01*
X1225775Y133633D01*
Y136719D01*
G01X1218921Y119054D02*
X1217275Y120700D01*
Y127924D01*
G01X1226785Y210403D02*
X1225240Y211948D01*
X1207109D01*
X1202889Y212296D01*
G01X1226785Y213003D02*
X1207513D01*
X1206269Y214247D01*
G01X1221300Y208000D02*
X1220400D01*
X1219600Y207200D01*
X1218256D01*
X1216606Y205550D01*
X1211550D01*
X1211050Y206050D01*
X1210150D01*
X1209650Y205550D01*
X1208500D01*
X1208000Y206050D01*
Y207172D01*
X1206772Y208400D01*
X1205300D01*
X1203626Y210074D01*
X1202362D01*
X1201188Y208900D01*
X1200499D01*
X1199509Y209890D01*
Y210346D01*
G01X1196129Y208397D02*
X1199565Y208165D01*
X1200331Y207776D01*
X1203327Y206081D01*
X1203900Y205800D01*
X1205100Y204600D01*
X1217000D01*
X1218650Y206250D01*
X1219550D01*
X1220400Y205400D01*
X1221300D01*
G01X1210000Y192500D02*
X1209130Y193370D01*
X1204766D01*
X1199436Y198700D01*
X1192408D01*
X1190163Y200945D01*
Y203702D01*
X1189369Y204496D01*
G01X1226500Y202400D02*
X1225600D01*
X1224650Y201450D01*
X1223606D01*
X1222506Y200350D01*
X1217550D01*
X1217050Y200850D01*
X1216150D01*
X1215650Y200350D01*
X1214750D01*
X1214250Y200850D01*
X1213350D01*
X1212850Y200350D01*
X1211350D01*
X1210300Y201400D01*
X1203600D01*
X1202100Y202900D01*
Y203707D01*
X1202889Y204496D01*
G01X1210070Y195300D02*
X1209100D01*
X1208120Y194320D01*
X1205160D01*
X1204000Y195480D01*
Y196188D01*
X1203388Y196800D01*
X1202680D01*
X1199830Y199650D01*
X1192802D01*
X1191113Y201339D01*
Y203101D01*
X1191621Y203609D01*
X1192329D01*
X1192749Y203189D01*
Y202547D01*
G01X1199509D02*
X1201109D01*
X1203206Y200450D01*
X1209906D01*
X1210956Y199400D01*
X1222900D01*
X1224000Y200500D01*
X1224900D01*
X1225600Y199800D01*
X1226500D01*
G01X1158950Y268847D02*
X1161200D01*
G01X1162330Y255196D02*
X1164580D01*
G01X1169089Y270796D02*
X1171339D01*
G01X1162330Y274696D02*
X1164580D01*
G01X1167960Y257147D02*
X1165710D01*
G01X1158950Y272747D02*
X1161200D01*
G01X1175849Y266896D02*
X1178099D01*
G01X1165710Y264947D02*
X1162300D01*
G01X1172469Y241547D02*
X1174719D01*
G01X1175849Y239596D02*
X1178099D01*
G01X1169089Y278596D02*
X1171339D01*
G01X1158950Y276646D02*
X1161200D01*
G01X1175849Y262996D02*
X1178099D01*
G01X1172469Y276646D02*
X1174719D01*
G01X1167960D02*
X1165710D01*
G01X1179229Y253247D02*
X1181479D01*
G01X1175849Y251296D02*
X1178099D01*
G01X1169089Y262996D02*
X1171339D01*
G01X1172469Y264947D02*
X1174719D01*
G01X1179229Y331247D02*
X1181479D01*
G01X1162330Y282496D02*
X1164580D01*
G01X1167960Y280547D02*
X1165710D01*
G01X1169089Y282496D02*
X1171339D01*
G01X1167960Y284447D02*
X1165710D01*
G01X1196129Y321496D02*
X1198379D01*
G01X1194999Y323446D02*
X1192749D01*
G01X1181479Y315647D02*
X1179229D01*
G01X1172469Y323446D02*
X1174719D01*
G01X1179229D02*
X1181479D01*
G01X1172469Y327347D02*
X1174719D01*
G01X1175849Y333196D02*
X1178099D01*
G01X1169089Y329296D02*
X1171339D01*
G01X1167960Y335147D02*
X1165710D01*
G01X1169089Y340996D02*
X1171339D01*
G01X1172469Y319547D02*
X1174719D01*
G01X1175849Y321496D02*
X1178099D01*
G01X1175849Y325396D02*
X1178099D01*
G01X1175849Y329296D02*
X1178099D01*
G01X1172469Y331247D02*
X1174719D01*
G01X1169089Y333196D02*
X1171339D01*
G01X1169089Y337096D02*
X1171339D01*
G01X1158950Y280547D02*
X1161200D01*
G01X1158950Y362447D02*
X1161200D01*
G01X1162330Y368296D02*
X1164580D01*
G01X1167960Y350747D02*
X1165710D01*
G01X1167960Y354647D02*
X1165710D01*
G01X1158950Y358547D02*
X1161200D01*
G01X1162330Y360496D02*
X1164580D01*
G01X1162330Y364396D02*
X1164580D01*
G01X1158950Y366347D02*
X1161200D01*
G01X1167960Y346847D02*
X1165710D01*
G01X1169089Y352696D02*
X1171339D01*
G01X1158950Y354647D02*
X1161200D01*
G01X1158950Y401447D02*
X1161201D01*
G01X1164580Y376096D02*
X1162330D01*
G01X1194999Y350747D02*
X1192749D01*
G01X1196129Y348796D02*
X1198379D01*
G01X1198029Y405411D02*
X1197997D01*
X1196129Y403543D01*
Y403396D01*
G01X1192749Y405347D02*
X1195602Y408200D01*
X1197100D01*
G01X1255120Y22923D02*
X1255118D01*
Y27899D01*
G01X1255120Y-14877D02*
X1255118D01*
Y-9901D01*
G01X1255120Y3233D02*
X1255118D01*
Y-1743D01*
G01X1265159Y22923D02*
X1265157Y27899D01*
G01X1265159Y-14877D02*
X1265157Y-10240D01*
Y-9901D01*
G01X1255120Y60723D02*
X1255118D01*
Y65699D01*
G01X1255120Y78833D02*
X1255118D01*
Y73857D01*
G01X1255120Y41033D02*
X1255118D01*
Y36057D01*
G01X1265159Y60723D02*
X1265157Y65699D01*
G01X1263798Y133493D02*
X1264542Y132749D01*
X1277547D01*
X1278000Y133202D01*
Y134500D01*
G01Y141000D02*
Y145780D01*
G01X1267100Y134500D02*
X1265452D01*
X1264772Y135180D01*
X1262040D01*
X1260737Y133877D01*
G01X1268236Y141938D02*
Y140031D01*
X1267100Y138895D01*
Y138000D01*
G01X1271500Y122500D02*
Y122600D01*
X1271490Y122610D01*
Y127670D01*
G01X1268930D02*
Y122530D01*
X1268900Y122500D01*
G01D02*
X1266892Y120492D01*
X1263540D01*
X1260087Y123945D01*
G01X1271490Y104700D02*
Y109670D01*
G01X1268930D02*
Y105030D01*
X1268600Y104700D01*
G01X1261734Y108836D02*
X1263676D01*
X1264510Y109670D01*
X1266370D01*
G01X1228906Y140251D02*
X1228874Y140219D01*
X1225775D01*
G01X1228906Y140251D02*
Y144504D01*
X1231543Y147141D01*
X1233723D01*
X1237797Y143067D01*
Y141263D01*
X1242633Y136427D01*
X1242993D01*
X1245603Y133817D01*
X1248616D01*
G01X1237704Y148423D02*
X1237398D01*
X1234947Y150874D01*
X1230265D01*
X1221025Y141634D01*
Y136424D01*
G01X1237704Y148423D02*
X1244317D01*
X1249429Y143311D01*
X1254219D01*
X1255687Y141843D01*
X1257854D01*
G01D02*
X1261880D01*
X1262986Y142949D01*
X1263004D01*
X1265277Y145222D01*
X1271996D01*
X1274500Y142718D01*
Y141000D01*
G01Y138000D02*
Y134500D01*
G01Y141000D02*
Y138000D01*
G01X1230906Y119155D02*
Y121829D01*
X1234155Y125078D01*
X1243944D01*
X1247663Y128797D01*
X1249714D01*
X1252437Y131520D01*
Y140192D01*
G01X1250470Y137547D02*
Y141018D01*
X1251338Y141886D01*
X1253628D01*
X1256016Y139498D01*
X1261551D01*
X1263577Y141524D01*
X1263595D01*
X1265810Y143739D01*
X1269414D01*
X1269958Y143195D01*
Y141393D01*
X1270600Y140751D01*
Y138000D01*
G01Y134500D02*
Y138000D01*
G01X1250470Y137547D02*
X1251531Y136486D01*
Y134206D01*
X1249469Y132144D01*
X1245547D01*
X1245014Y132677D01*
X1241963D01*
G01D02*
Y131463D01*
X1240000Y129500D01*
G01X1232790Y144530D02*
X1233463Y143857D01*
Y136427D01*
G01D02*
X1230682D01*
X1230358Y136751D01*
X1228906D01*
G01X1255120Y523900D02*
Y518000D01*
G01X1269209Y501777D02*
Y505036D01*
X1268805Y505440D01*
G01X1272060Y513590D02*
Y512260D01*
X1271300Y511500D01*
Y510600D01*
G01D02*
X1269640Y508940D01*
X1268805D01*
G01X1271105Y498516D02*
X1271895Y499306D01*
X1273316D01*
X1276704Y502694D01*
Y504038D01*
G01X1287770Y501897D02*
X1283474D01*
X1277833Y507538D01*
X1276704D01*
G01X1273687Y503991D02*
Y502175D01*
X1272443Y500931D01*
X1271168D01*
X1269931Y499694D01*
X1267584D01*
G01X1274576Y510235D02*
X1275540Y511199D01*
Y513490D01*
G01X1273687Y507491D02*
Y509346D01*
X1274576Y510235D01*
G01X1265159Y523900D02*
X1265157Y528876D01*
G01X1255120Y561700D02*
Y555144D01*
G01Y542010D02*
Y537034D01*
G01Y579810D02*
Y574834D01*
G01X1265159Y561700D02*
X1265157Y566676D01*
G01X1255120Y599500D02*
Y593600D01*
G01Y612634D02*
Y617610D01*
G01X1265159Y599500D02*
X1265157Y604476D01*
G01X1330500Y80800D02*
Y83300D01*
X1330300Y83500D01*
G01X1330500Y58000D02*
X1328000D01*
X1327168Y58832D01*
Y61483D01*
G01X1330500Y74500D02*
Y71500D01*
G01Y74500D02*
X1329500D01*
X1326600Y77400D01*
G01X1327168Y61483D02*
X1325700Y62951D01*
Y73000D01*
X1326600Y73900D01*
Y77400D01*
G01X1327500Y65300D02*
Y64000D01*
X1330500Y61000D01*
G01X1336900Y61600D02*
X1336300Y61000D01*
X1334000D01*
G01X1347350Y58138D02*
X1340362D01*
X1336900Y61600D01*
G01X1327467Y70786D02*
X1328214D01*
X1330500Y68500D01*
Y68000D01*
G01X1347350Y61287D02*
X1344314D01*
X1338801Y66800D01*
X1338160D01*
G01D02*
X1337460D01*
X1336260Y68000D01*
X1334000D01*
G01X1330500Y64500D02*
Y65000D01*
X1327500Y68000D01*
G01X1347350Y59713D02*
X1342711D01*
X1341352Y61072D01*
G01D02*
X1337924Y64500D01*
X1334000D01*
G01X1347350Y62862D02*
X1345038D01*
X1341707Y66193D01*
Y67426D01*
X1338845Y70288D01*
X1335912D01*
X1334700Y71500D01*
X1334000D01*
G01Y74500D02*
X1335400D01*
X1337400Y72500D01*
Y72000D01*
G01X1347350Y64437D02*
X1345863D01*
X1338300Y72000D01*
X1337400D01*
G01X1317384Y81896D02*
Y84516D01*
X1317300Y84600D01*
G01X1334000Y77800D02*
X1335848D01*
X1336161Y78113D01*
X1337787D01*
X1340500Y75400D01*
Y74100D01*
X1341200Y73400D01*
G01X1334000Y77800D02*
Y80800D01*
G01X1347350Y67587D02*
X1346519D01*
X1345800Y68306D01*
Y72100D01*
X1344737Y73163D01*
X1341437D01*
X1341200Y73400D01*
G01X1341757Y96489D02*
X1341525D01*
X1339500Y94464D01*
Y93500D01*
G01D02*
X1337443D01*
X1334112Y90169D01*
X1330606D01*
X1324700Y84263D01*
Y82101D01*
X1322199Y79600D01*
X1308400D01*
G01X1339500Y93500D02*
X1343500D01*
G01X1349913Y70150D02*
Y72287D01*
X1347612Y74588D01*
X1343474D01*
X1340000Y78062D01*
Y83500D01*
G01X1345561Y84900D02*
X1342800D01*
X1341400Y83500D01*
X1340000D01*
G01X1347350Y56563D02*
X1337637D01*
X1336200Y58000D01*
X1334000D01*
G01X1337200Y292012D02*
X1333737Y288549D01*
Y284211D01*
X1336782Y281166D01*
X1339199D01*
X1341009Y279356D01*
G01X1570272Y234889D02*
X1562396Y227013D01*
X1543244D01*
X1533069Y237188D01*
X1525227D01*
X1523069Y235030D01*
X1520390D01*
X1518554Y236866D01*
X1504752D01*
X1503169Y238449D01*
X1487068D01*
X1477486Y248031D01*
X1443900D01*
X1437669Y241800D01*
X1436300D01*
X1432500Y245600D01*
Y252100D01*
X1431050Y253550D01*
Y258623D01*
X1414670Y275003D01*
X1411572D01*
X1407896Y271327D01*
X1378171D01*
X1376676Y269832D01*
X1353400D01*
X1348094Y275138D01*
X1345227D01*
X1341009Y279356D01*
G01X1572730Y235931D02*
Y234974D01*
X1563844Y226088D01*
X1542860D01*
X1532685Y236263D01*
X1525611D01*
X1523398Y234050D01*
X1519990D01*
X1518099Y235941D01*
X1504135D01*
X1502913Y237163D01*
X1486791D01*
X1481549Y242405D01*
X1476072D01*
X1474836Y241169D01*
X1468070D01*
X1463226Y246013D01*
X1443274D01*
X1438111Y240850D01*
X1435941D01*
X1431575Y245216D01*
Y245375D01*
X1431550Y245400D01*
Y251741D01*
X1430125Y253166D01*
Y258239D01*
X1414501Y273863D01*
X1411741D01*
X1408280Y270402D01*
X1378659D01*
X1377164Y268907D01*
X1353016D01*
X1347710Y274213D01*
X1340264D01*
X1334730Y279747D01*
G01X1448603Y317696D02*
X1447020Y319279D01*
X1444103D01*
X1443204Y318380D01*
X1439857D01*
X1433258Y311781D01*
Y296858D01*
X1418747Y282347D01*
X1408410D01*
X1405799Y279736D01*
X1398286D01*
X1390647Y287375D01*
X1377542D01*
X1371404Y281237D01*
X1351762D01*
X1347500Y285499D01*
Y287707D01*
X1338919Y296288D01*
X1327187D01*
X1323936Y293037D01*
X1311053D01*
X1307980Y296110D01*
X1305751D01*
X1304919Y296942D01*
X1302768D01*
G01X1334400Y292050D02*
X1332312Y289962D01*
Y283620D01*
X1334730Y281202D01*
Y279747D01*
G01X1386750Y278000D02*
X1380239D01*
X1377650Y275411D01*
X1349130D01*
X1342204Y282337D01*
X1337963D01*
X1335400Y284900D01*
G01X1330039Y279618D02*
Y290042D01*
X1333710Y293713D01*
X1337851D01*
X1338901Y292663D01*
Y286949D01*
X1349331Y276519D01*
X1376488D01*
X1380419Y280450D01*
X1392762D01*
X1399776Y273436D01*
X1406959D01*
X1410470Y276947D01*
X1416136D01*
X1423361Y269721D01*
X1423893Y269189D01*
X1436384D01*
X1440732Y273537D01*
Y275181D01*
X1443878Y278327D01*
G01X1376393Y280244D02*
X1374016Y277867D01*
X1349292D01*
X1339826Y287333D01*
Y293047D01*
X1338235Y294638D01*
X1333326D01*
X1323432Y284744D01*
X1315372D01*
X1314490Y283862D01*
G01X1402500Y276550D02*
X1399138D01*
X1393103Y282585D01*
X1375086D01*
X1372088Y279587D01*
X1348739D01*
X1342300Y286026D01*
Y291740D01*
X1338577Y295463D01*
X1331466D01*
X1322430Y286427D01*
X1314792D01*
G01X1483506Y326061D02*
X1480098D01*
X1479559Y326600D01*
X1476901D01*
X1471064Y332437D01*
X1469223D01*
X1462813Y326027D01*
X1461481Y325475D01*
X1458870Y324393D01*
X1458866Y324392D01*
X1457830Y323963D01*
X1456958Y323091D01*
X1448409D01*
X1445288Y326212D01*
X1442348D01*
X1429147Y313011D01*
Y298408D01*
X1419904Y289165D01*
X1406464D01*
X1405036Y287737D01*
X1400072D01*
X1399334Y288475D01*
X1377042D01*
X1376659Y288092D01*
Y288048D01*
X1370948Y282337D01*
X1352711D01*
X1349231Y285817D01*
Y287532D01*
X1339375Y297388D01*
X1328512D01*
X1315350Y310550D01*
G01X1302203Y314439D02*
X1311461D01*
X1315350Y310550D01*
G01X1297618Y434925D02*
X1298514D01*
X1300438Y433001D01*
G01X1342618Y434925D02*
X1342525D01*
X1340100Y432500D01*
G01X1335100Y505200D02*
Y507700D01*
G01D02*
X1335008Y507792D01*
Y510187D01*
G01X1343350Y514192D02*
X1341504D01*
X1338508Y511196D01*
Y510187D01*
G01X1314476Y619501D02*
X1311787Y616812D01*
X1307521D01*
X1306051Y615342D01*
X1299894D01*
X1296092Y611540D01*
Y585981D01*
X1293287Y583176D01*
X1289845Y580825D01*
X1284576D01*
X1283786Y581615D01*
X1283215D01*
X1282600Y581000D01*
G01X1311876Y619501D02*
X1312150Y619227D01*
Y618625D01*
X1311262Y617737D01*
X1307137D01*
X1305767Y616367D01*
X1299469D01*
X1295200Y612098D01*
Y611957D01*
X1295167Y611924D01*
Y586366D01*
X1292693Y583892D01*
X1289559Y581750D01*
X1284960D01*
X1284170Y582540D01*
X1283660D01*
X1282600Y583600D01*
G01X1375359Y29498D02*
X1377148D01*
X1382100Y34450D01*
Y36850D01*
X1387800Y42550D01*
Y43900D01*
G01X1375048Y-2526D02*
X1376220D01*
X1380038Y1292D01*
X1382050D01*
X1382926Y2168D01*
X1385818D01*
X1387497Y489D01*
G01X1347500Y80500D02*
Y83000D01*
G01X1355500D02*
X1357100Y81400D01*
Y80300D01*
X1356220Y79420D01*
Y78330D01*
G01D02*
Y76220D01*
X1354638Y74638D01*
Y70150D01*
G01X1359500Y83000D02*
X1358410Y81910D01*
Y76910D01*
X1356213Y74713D01*
Y70150D01*
G01X1362690Y82705D02*
X1362395Y83000D01*
X1359500D01*
G01X1347500Y77000D02*
X1351500D01*
G01X1344000D02*
X1347500D01*
G01X1351500D02*
X1351488Y76988D01*
Y74000D01*
G01D02*
Y70150D01*
G01X1372300Y86400D02*
X1371591Y87109D01*
Y88967D01*
G01X1364700Y92450D02*
X1368591D01*
G01X1364700D02*
Y96440D01*
G01X1368591Y92450D02*
X1371574D01*
X1371591Y92467D01*
G01X1349540Y85780D02*
X1348280D01*
X1347400Y84900D01*
X1345561D01*
G01X1353040Y85780D02*
X1356140D01*
X1357000Y86640D01*
G01X1387800Y43900D02*
Y47800D01*
X1383500Y52100D01*
G01X1362653Y101300D02*
Y99497D01*
X1364700Y97450D01*
Y96440D01*
G01X1345257Y96489D02*
Y100000D01*
G01X1348550Y103592D02*
X1346592D01*
X1345257Y102257D01*
Y100000D01*
G01X1345700Y285300D02*
X1350588Y280412D01*
X1371746D01*
X1377821Y286487D01*
X1390368D01*
X1397944Y278911D01*
X1406141D01*
X1408752Y281522D01*
X1418727D01*
X1420471Y279778D01*
G01X1466006Y265300D02*
Y265202D01*
X1472433Y258775D01*
Y256017D01*
X1472613Y255837D01*
Y252157D01*
X1471200Y250744D01*
X1450676D01*
X1448080Y253340D01*
X1447876D01*
X1447843Y253373D01*
X1446465D01*
X1446432Y253340D01*
X1444211D01*
X1443496Y254055D01*
Y259432D01*
X1437964Y264964D01*
X1426037D01*
X1414979Y276022D01*
X1410854D01*
X1407343Y272511D01*
X1398850D01*
X1393361Y278000D01*
X1386750D01*
G01X1447028Y284626D02*
X1445402Y283000D01*
X1443271D01*
X1439533Y279262D01*
Y273647D01*
X1436000Y270114D01*
X1424395D01*
X1416637Y277872D01*
X1410086D01*
X1406575Y274361D01*
X1400160D01*
X1393021Y281500D01*
X1377649D01*
X1376393Y280244D01*
G01X1402500Y276550D02*
X1404947D01*
X1409094Y280697D01*
X1415041D01*
X1424799Y270939D01*
X1435658D01*
X1438478Y273759D01*
Y280589D01*
X1442515Y284626D01*
X1443878D01*
G01X1408706Y286801D02*
X1406116D01*
X1405627Y286312D01*
X1401376D01*
X1400429Y285365D01*
Y283085D01*
X1398926Y281582D01*
G01X1359000Y284900D02*
X1359710D01*
X1369785Y294975D01*
X1400500D01*
G01D02*
X1419417D01*
X1424896Y300454D01*
Y337798D01*
X1413487Y349207D01*
Y354737D01*
X1414750Y356000D01*
X1416399D01*
X1426050Y365651D01*
Y418302D01*
X1426051Y418303D01*
Y419649D01*
X1418375Y427325D01*
X1399284D01*
X1397985Y428624D01*
Y434665D01*
X1395300Y437350D01*
X1391300D01*
X1390100Y438550D01*
Y447200D01*
X1389900Y447400D01*
G01X1352400Y285000D02*
X1366720Y299320D01*
X1419164D01*
X1421646Y301802D01*
Y336450D01*
X1410148Y347948D01*
Y349294D01*
X1410149Y349295D01*
Y355997D01*
X1410150Y355998D01*
Y356098D01*
X1413552Y359500D01*
X1415200D01*
X1422800Y367100D01*
Y418302D01*
X1417052Y424050D01*
X1395750D01*
X1390700Y429100D01*
Y430712D01*
X1392488Y432500D01*
X1395100D01*
G01X1355800Y285000D02*
X1367938Y297138D01*
X1405800D01*
G01X1443500Y327900D02*
X1436131D01*
X1427722Y319491D01*
Y298999D01*
X1419361Y290638D01*
X1405138D01*
X1404400Y289900D01*
X1402900D01*
G01D02*
X1374100D01*
X1368200Y284000D01*
G01X1389700Y391745D02*
X1388045D01*
X1386210Y389910D01*
G01X1384900Y389100D02*
X1382899D01*
G01X1382618Y454925D02*
X1385043Y452500D01*
X1385100D01*
G01X1382618Y449925D02*
X1383000Y449552D01*
X1385100Y447500D01*
G01X1387618Y454925D02*
Y455018D01*
X1390100Y457500D01*
G01X1389900Y447400D02*
X1387618Y449682D01*
Y449925D01*
G01X1390100Y452500D02*
X1392525Y454925D01*
X1392618D01*
G01X1395100Y432500D02*
X1392618Y434925D01*
G01Y449925D02*
X1395100Y447500D01*
G01X1405800Y297138D02*
X1419281D01*
X1423271Y301128D01*
Y337124D01*
X1411774Y348621D01*
Y355323D01*
X1411775Y355324D01*
Y355424D01*
X1414151Y357800D01*
X1415799D01*
X1424425Y366426D01*
Y418976D01*
X1417701Y425700D01*
X1396399D01*
X1395100Y426999D01*
Y427500D01*
G01D02*
X1392618Y429925D01*
G01X1372618Y449925D02*
X1375100Y447500D01*
G01X1367618Y454925D02*
X1370100Y452500D01*
G01X1372618Y454925D02*
X1375100Y452500D01*
G01X1392618Y444925D02*
X1396204D01*
X1401863Y450584D01*
X1415874D01*
X1420247Y446211D01*
Y439643D01*
X1433414Y426476D01*
Y414300D01*
X1436200Y411514D01*
Y377400D01*
X1435800Y377000D01*
G01X1367618Y449925D02*
X1367675D01*
X1370100Y447500D01*
G01X1392618Y439925D02*
Y441869D01*
X1394249Y443500D01*
X1396795D01*
X1402287Y448992D01*
X1415450D01*
X1418822Y445620D01*
Y439018D01*
X1432489Y425351D01*
Y413200D01*
X1434700Y410989D01*
Y386300D01*
X1433900Y385500D01*
G01X1342618Y429925D02*
X1342600D01*
Y419100D01*
X1342500Y419000D01*
G01X1436100Y535400D02*
Y528460D01*
X1434346Y526706D01*
Y521110D01*
X1431047Y517811D01*
X1405447D01*
X1403027Y520231D01*
G01X1392953Y509379D02*
Y518012D01*
X1395242Y520301D01*
G01X1392953Y505879D02*
X1396792D01*
X1396871Y505800D01*
G01X1363000Y500500D02*
Y502398D01*
X1364575Y503973D01*
X1372600D01*
G01D02*
X1376799D01*
X1378705Y505879D01*
X1392953D01*
G01X1363000Y500500D02*
X1361500D01*
X1360500Y501500D01*
Y507100D01*
X1357453Y510147D01*
Y511900D01*
G01X1379359Y576354D02*
X1380991D01*
X1381780Y577143D01*
X1384264D01*
X1385486Y578365D01*
G01X1389066Y583080D02*
X1385486Y579500D01*
Y578365D01*
G01X1379359Y607554D02*
X1380754D01*
X1381150Y607950D01*
X1384750D01*
X1385800Y609000D01*
G01X1521092Y21665D02*
X1516525Y17098D01*
X1510747D01*
X1494949Y1300D01*
X1480243D01*
X1479243Y300D01*
X1457300D01*
X1452000Y-5000D01*
G01X1413721Y17283D02*
Y13139D01*
G01X1416871Y33849D02*
Y30669D01*
G01Y17283D02*
Y13139D01*
G01X1407422Y17283D02*
Y13139D01*
G01X1446179Y70353D02*
X1451352D01*
X1453221Y72222D01*
Y73750D01*
G01X1455889Y73700D02*
Y74911D01*
X1454870Y75930D01*
X1451686D01*
X1451109Y75353D01*
X1446179D01*
G01Y80353D02*
X1450303D01*
X1453700Y83750D01*
G01X1446179Y85353D02*
X1450594D01*
X1451457Y86216D01*
X1453962D01*
X1456000Y84178D01*
Y83000D01*
X1457000Y82000D01*
G01X1455347Y92065D02*
X1453635Y90353D01*
X1446179D01*
G01X1420337Y42977D02*
Y45477D01*
G01X1416837Y42977D02*
Y45477D01*
G01X1445232Y148080D02*
X1449558D01*
X1451233Y146405D01*
G01X1445232Y143080D02*
X1450517D01*
X1451198Y143761D01*
G01X1452232Y109500D02*
Y107650D01*
X1449935Y105353D01*
X1446179D01*
G01X1453809Y94639D02*
X1453095Y95353D01*
X1446179D01*
G01X1451366Y165296D02*
X1448582Y168080D01*
X1445232D01*
G01Y178080D02*
X1448286D01*
X1449682Y176684D01*
Y175203D01*
X1451386Y173499D01*
G01X1489061Y231927D02*
X1480333Y240655D01*
X1476798D01*
X1475243Y239100D01*
X1456728D01*
X1452728Y243100D01*
Y243306D01*
G01X1442304Y273603D02*
X1443878Y275177D01*
G01X1448603Y276753D02*
X1450177Y278327D01*
G01X1461300Y270400D02*
X1459672Y272028D01*
X1459626D01*
G01X1433057Y257388D02*
X1441489Y248956D01*
X1471736D01*
X1474520Y251740D01*
G01X1448603Y267304D02*
X1450177Y268878D01*
G01X1467700Y255900D02*
Y254502D01*
X1466787Y253589D01*
Y252916D01*
X1465752Y251881D01*
X1464374D01*
X1463839Y252416D01*
X1460631D01*
G01X1467700Y255900D02*
Y257000D01*
X1464242Y260458D01*
Y270345D01*
X1465925Y272028D01*
G01X1451753Y267304D02*
X1453327Y268878D01*
G01X1451753Y273603D02*
X1453327Y275177D01*
G01X1433362Y278244D02*
Y274862D01*
X1431089Y272589D01*
X1425676D01*
X1424995Y273270D01*
Y287195D01*
X1435000Y297200D01*
Y308500D01*
X1439472Y312972D01*
X1443878D01*
G01X1441750Y236800D02*
X1443850D01*
X1452019Y244969D01*
X1453417D01*
X1458269Y240117D01*
X1475093D01*
X1476456Y241480D01*
X1480675D01*
X1485917Y236238D01*
X1502529D01*
X1506876Y231891D01*
X1534908D01*
X1541824Y224975D01*
X1565265D01*
X1574560Y234270D01*
Y237660D01*
G01X1448839Y255160D02*
X1450171D01*
X1450942Y255931D01*
Y259589D01*
X1449540Y260991D01*
Y263540D01*
X1450400Y264400D01*
X1455500D01*
X1456476Y265376D01*
Y268878D01*
G01X1464351Y276753D02*
X1465925Y278327D01*
G01X1420471Y279778D02*
X1422700Y277549D01*
Y274244D01*
X1425180Y271764D01*
X1435316D01*
X1437160Y273608D01*
Y281581D01*
X1441781Y286202D01*
X1445454D01*
G01X1461202Y276753D02*
X1462776Y278327D01*
G01X1451753Y270454D02*
X1453327Y272028D01*
G01X1426658Y274252D02*
Y287396D01*
X1441211Y301949D01*
X1442303D01*
X1443878Y300374D01*
G01X1458052Y276753D02*
X1459626Y278327D01*
G01X1458052Y273603D02*
X1459626Y275177D01*
G01Y268878D02*
X1458102Y270402D01*
G01X1445454Y267304D02*
X1447028Y268878D01*
G01X1464424Y273676D02*
X1462776Y272028D01*
G01X1454902Y270454D02*
X1456476Y272028D01*
G01X1415617Y284527D02*
X1408427D01*
X1405629Y281729D01*
X1404286D01*
G01X1415617Y284527D02*
X1419298D01*
X1431886Y297114D01*
X1431997Y297226D01*
Y311829D01*
X1440479Y320311D01*
X1447621D01*
Y320246D01*
X1448499Y319368D01*
X1456357D01*
X1457890Y320901D01*
X1464429Y323609D01*
X1467950Y327130D01*
X1470355D01*
X1471562Y325923D01*
Y325531D01*
G01X1408706Y286801D02*
X1419556D01*
X1430572Y297817D01*
Y312420D01*
X1439818Y321666D01*
X1457345D01*
X1457365Y321686D01*
X1457714Y321831D01*
X1458636Y322753D01*
X1463621Y324818D01*
X1467783Y328980D01*
X1471500D01*
X1475494Y324986D01*
X1478585D01*
X1479490Y324081D01*
X1485897D01*
X1491981Y330165D01*
X1501080D01*
X1503825Y332910D01*
X1507551D01*
X1508734Y334093D01*
X1516960D01*
X1517482Y333571D01*
X1528439D01*
X1536956Y325054D01*
X1538386D01*
X1542740Y320700D01*
X1543700D01*
X1547800Y316600D01*
X1549000D01*
G01X1461202Y305098D02*
X1462776Y303524D01*
G01X1451754Y283053D02*
X1453327Y284626D01*
G01X1440910Y316693D02*
Y316640D01*
X1442900Y314650D01*
X1445556D01*
X1447028Y316122D01*
G01X1458052Y298798D02*
X1459626Y297224D01*
G01X1445454Y279902D02*
X1447028Y281476D01*
G01X1458052Y305098D02*
X1459626Y303524D01*
G01X1454902Y301948D02*
X1456476Y300374D01*
G01X1461202Y314546D02*
X1462776Y312972D01*
G01X1458052Y289351D02*
X1459626Y290925D01*
G01X1448603Y289351D02*
X1450177Y290925D01*
G01X1442304Y292499D02*
X1443878Y290925D01*
G01X1454751Y292651D02*
X1453327Y294075D01*
G01X1443878D02*
X1445427Y295624D01*
G01X1447028Y294075D02*
X1448577Y295624D01*
G01X1450177Y294075D02*
X1451751Y295649D01*
G01X1451753Y301948D02*
X1453327Y300374D01*
G01X1464351Y311397D02*
X1465925Y309823D01*
G01X1461202Y311397D02*
X1462776Y309823D01*
G01X1458052Y308247D02*
X1459626Y306673D01*
G01X1461202Y279902D02*
X1462776Y281476D01*
G01X1442304Y289350D02*
X1443878Y287776D01*
G01X1458052Y279902D02*
X1459626Y281476D01*
G01Y294075D02*
X1458052Y295649D01*
G01X1448603Y301948D02*
X1450177Y300374D01*
G01X1445454Y289351D02*
X1447028Y290925D01*
G01X1451753Y311397D02*
X1453327Y309823D01*
G01X1458052Y314546D02*
X1459626Y312972D01*
G01X1462776Y316122D02*
Y318200D01*
G01X1451753Y314546D02*
X1453327Y312972D01*
G01X1448603Y308247D02*
X1450177Y306673D01*
G01X1461202Y283052D02*
X1462776Y284626D01*
G01X1430117Y287489D02*
Y289017D01*
X1432543Y291443D01*
G01D02*
X1435046Y293946D01*
X1440600D01*
X1443878Y297224D01*
G01X1450177Y284626D02*
X1450176D01*
X1448603Y283053D01*
G01X1460500Y382500D02*
X1461586D01*
X1464361Y385275D01*
G01X1479750Y370752D02*
Y369750D01*
X1476500Y366500D01*
Y363975D01*
X1476075Y363550D01*
X1469922D01*
X1469300Y362928D01*
Y362047D01*
X1469922Y361425D01*
X1476078D01*
X1476700Y360803D01*
Y359922D01*
X1476078Y359300D01*
X1466022D01*
X1465400Y358678D01*
Y357797D01*
X1466888Y356309D01*
Y350522D01*
X1467510Y349900D01*
X1468391D01*
X1469013Y350522D01*
Y356553D01*
X1469635Y357175D01*
X1476075D01*
X1476500Y356750D01*
Y353000D01*
X1474250Y350750D01*
X1472500D01*
G01X1453900Y390600D02*
X1454140D01*
X1456900Y387840D01*
Y387600D01*
G01X1453900Y390600D02*
Y394600D01*
G01D02*
X1451100D01*
X1450500Y394000D01*
X1446500D01*
G01X1456981Y384569D02*
X1456581D01*
X1456281Y384869D01*
X1455632D01*
X1455401Y385100D01*
X1453900D01*
G01D02*
Y383400D01*
X1453000Y382500D01*
Y381250D01*
G01D02*
X1450949D01*
X1450199Y382000D01*
X1446500D01*
G01X1446800Y368018D02*
Y373200D01*
X1445100Y374900D01*
G01X1461700Y395500D02*
X1463669Y393531D01*
X1467031D01*
X1468700Y395200D01*
X1470800D01*
G01X1480000Y379350D02*
X1474150D01*
X1473270Y378470D01*
X1471220D01*
X1469330Y380360D01*
X1464830D01*
X1458070Y373600D01*
X1457300D01*
G01D02*
X1456700Y373000D01*
X1454500D01*
G01X1453900Y353350D02*
X1452384D01*
X1451249Y352215D01*
X1449897D01*
X1447840Y354272D01*
X1437728D01*
X1428800Y363200D01*
Y422416D01*
X1412686Y438530D01*
X1410695D01*
X1408225Y441000D01*
G01X1439700Y370300D02*
Y361850D01*
X1440950Y360600D01*
X1453695D01*
X1456201Y358094D01*
X1459892D01*
X1460832Y357154D01*
Y355073D01*
X1462200Y353705D01*
Y352700D01*
X1467200Y347700D01*
Y345298D01*
X1469350Y343148D01*
Y339856D01*
X1471706Y337500D01*
X1472450D01*
G01X1439700Y370300D02*
X1441000Y371600D01*
X1444400D01*
G01X1456000Y360700D02*
X1456350Y361050D01*
Y362400D01*
X1455850Y362900D01*
X1453800D01*
G01X1463942Y359742D02*
X1465500Y361300D01*
Y363500D01*
X1463550Y365450D01*
X1458450D01*
G01X1453800Y365459D02*
X1458441D01*
X1458450Y365450D01*
G01X1464400Y390800D02*
X1462700Y392500D01*
X1460500D01*
G01X1431000Y406500D02*
Y403200D01*
X1430200Y402400D01*
Y363201D01*
X1437945Y355456D01*
X1449244D01*
X1450400Y354300D01*
G01X1432400Y398000D02*
X1433400Y399000D01*
Y410464D01*
X1431564Y412300D01*
Y424260D01*
X1417350Y438474D01*
Y438570D01*
X1412375Y443545D01*
G01X1460400Y353000D02*
X1459950Y353450D01*
X1457226D01*
X1455663Y355013D01*
X1452535D01*
X1451223Y356325D01*
X1438625D01*
X1431700Y363250D01*
Y390900D01*
X1432600Y391800D01*
Y397800D01*
X1432400Y398000D01*
G01X1435800Y377000D02*
Y363150D01*
X1439775Y359175D01*
X1453104D01*
X1455879Y356400D01*
X1458922D01*
X1459116Y356206D01*
Y356353D01*
X1459111D01*
G01X1427700Y361100D02*
Y360201D01*
X1434708Y353193D01*
X1446517D01*
X1447685Y352025D01*
G01X1408225Y438233D02*
X1409258Y437200D01*
X1412156D01*
X1427700Y421656D01*
Y361100D01*
G01X1433900Y385500D02*
X1433000Y384600D01*
Y364641D01*
X1439891Y357750D01*
X1452430D01*
X1453251Y356929D01*
Y356676D01*
G01X1472415Y389085D02*
X1470580Y387250D01*
X1463750D01*
X1462500Y386000D01*
X1460500D01*
G01X1478366Y389193D02*
X1477833Y388660D01*
X1476380D01*
X1475410Y387690D01*
Y386739D01*
X1476411Y385738D01*
Y384761D01*
X1474050Y382400D01*
X1464720D01*
X1464400Y382720D01*
G01X1460251Y428517D02*
X1459334Y427600D01*
X1455600D01*
G01X1451560Y424779D02*
X1452279D01*
X1453500Y426000D01*
X1454000D01*
X1455600Y427600D01*
G01X1451560Y424779D02*
X1449160D01*
X1448081Y423700D01*
X1442889D01*
X1439000Y427618D01*
G01X1461294Y426938D02*
X1456456Y422100D01*
X1455600D01*
G01D02*
X1455179Y421679D01*
X1451560D01*
G01D02*
X1450200D01*
X1447871Y419350D01*
X1445300D01*
G01X1412484Y440748D02*
X1430200Y423032D01*
Y411100D01*
X1431000Y410300D01*
Y406500D01*
G01X1432200Y524050D02*
Y522040D01*
X1431690Y521530D01*
G01X1417291Y528974D02*
X1416478Y528161D01*
Y522822D01*
X1417800Y521500D01*
G01X1414800Y521400D02*
X1415155Y521755D01*
Y523926D01*
X1414261Y524820D01*
G01X1415347Y534305D02*
Y530407D01*
X1415127Y530187D01*
Y525686D01*
X1414261Y524820D01*
G01X1478298Y493513D02*
Y494042D01*
X1476383Y495957D01*
Y496987D01*
X1475128Y498242D01*
Y505440D01*
X1473408Y507160D01*
X1472040D01*
X1470382Y508818D01*
X1464607D01*
X1464553Y508872D01*
G01D02*
X1464425Y509000D01*
X1459600D01*
G01X1436100Y535400D02*
Y538400D01*
G01Y535400D02*
X1438400D01*
X1439200Y534600D01*
G01X1416922Y534305D02*
Y532817D01*
X1416560Y532455D01*
Y529705D01*
X1417291Y528974D01*
G01X1436060Y548455D02*
X1436462D01*
X1439123Y545794D01*
Y545294D01*
G01X1424210Y546317D02*
X1425962D01*
X1428100Y548455D01*
X1429229D01*
G01D02*
X1432560D01*
G01X1436060Y541455D02*
X1437255D01*
X1438048Y540662D01*
Y539156D01*
X1439822Y537382D01*
G01X1432560Y541455D02*
X1429455D01*
X1429026Y541026D01*
G01X1424210Y543168D02*
X1426884D01*
X1429026Y541026D01*
G01X1436060Y544955D02*
X1436824D01*
X1438551Y543228D01*
Y543033D01*
X1438799Y542785D01*
G01X1432560Y544955D02*
X1431145D01*
X1429981Y546119D01*
X1428281D01*
G01X1424210Y544742D02*
X1426142D01*
X1427519Y546119D01*
X1428281D01*
G01X1424210Y541593D02*
X1426107D01*
X1429300Y538400D01*
X1432600D01*
G01Y535400D02*
X1428903D01*
X1428791Y535512D01*
G01D02*
Y536724D01*
X1425497Y540018D01*
X1424210D01*
G01X1425560Y527455D02*
X1423776D01*
X1423731Y527500D01*
X1422000D01*
G01X1420072Y534305D02*
Y531972D01*
X1419600Y531500D01*
G01D02*
Y529900D01*
X1422000Y527500D01*
G01X1428800D02*
X1430500D01*
X1430550Y527550D01*
X1432200D01*
G01X1428800Y527500D02*
Y529170D01*
X1427170Y530800D01*
X1426870D01*
G01D02*
Y531100D01*
X1425600Y532370D01*
Y536300D01*
X1425032Y536868D01*
X1424210D01*
G01X1421647Y534305D02*
X1423305D01*
X1423800Y534800D01*
G01X1424210Y547892D02*
X1425792D01*
X1427320Y549420D01*
Y550302D01*
X1428938Y551920D01*
X1430980D01*
X1431400Y551500D01*
X1432500D01*
G01X1524800Y3500D02*
Y-1200D01*
X1526100Y-2500D01*
X1527600D01*
G01X1520100D02*
X1522175D01*
X1522600Y-2075D01*
Y4250D01*
X1523513Y5163D01*
X1569729D01*
X1572692Y2200D01*
X1579154D01*
X1579985Y1369D01*
X1583398D01*
G01X1520100Y-2500D02*
X1516900D01*
G01D02*
X1513700D01*
G01D02*
X1510718D01*
X1509000Y-4218D01*
Y-6500D01*
G01X1520100Y1000D02*
Y3500D01*
G01X1516900Y1000D02*
Y3500D01*
G01X1485242Y4589D02*
X1485573D01*
X1487919Y2243D01*
X1494583D01*
X1510363Y18023D01*
X1514223D01*
X1521900Y25700D01*
Y27500D01*
G01X1506300Y-6600D02*
Y-2700D01*
X1510000Y1000D01*
X1513700D01*
G01X1542009Y30668D02*
X1525904D01*
X1524154Y28918D01*
G01X1516600Y-6500D02*
Y-9500D01*
X1515000Y-11100D01*
Y-15000D01*
G01X1512500Y-6500D02*
X1516600D01*
G01X1525000Y-15000D02*
Y-11200D01*
X1528500Y-7700D01*
Y-6500D01*
G01X1511900Y3500D02*
Y7900D01*
X1512950Y8950D01*
X1513000Y8900D01*
X1567548D01*
X1572517Y3931D01*
X1573898D01*
G01X1493750Y143900D02*
X1492206D01*
X1491386Y143080D01*
X1482832D01*
G01X1498985Y143065D02*
X1496945D01*
X1496110Y143900D01*
X1493750D01*
G01X1493200Y162700D02*
X1494091D01*
X1496602Y160189D01*
Y158778D01*
X1498867Y156513D01*
X1501445D01*
X1502626Y155332D01*
Y151098D01*
X1503051Y150673D01*
X1507076D01*
G01X1502000Y147500D02*
X1501689Y147811D01*
Y149301D01*
X1500597Y150393D01*
Y151573D01*
X1498499Y153671D01*
Y154476D01*
X1495496Y157479D01*
X1493472D01*
X1492013Y156020D01*
Y155610D01*
G01X1483779Y105353D02*
X1489313D01*
X1489780Y105820D01*
G01X1490674Y98787D02*
X1487240Y95353D01*
X1483779D01*
G01X1489053Y103325D02*
X1489205D01*
Y102134D01*
X1487424Y100353D01*
X1483779D01*
G01X1489088Y176680D02*
X1487688Y178080D01*
X1482832D01*
G01X1492500Y176887D02*
X1489852Y174239D01*
X1488039D01*
X1486880Y173080D01*
X1482832D01*
G01X1580377Y161368D02*
X1578394Y163351D01*
X1574500D01*
X1573119Y161970D01*
X1568224D01*
X1563555Y166639D01*
X1560190D01*
X1554935Y171894D01*
Y173437D01*
X1549619Y178753D01*
X1543947D01*
X1538693Y184007D01*
X1525625D01*
X1521000Y188632D01*
Y194026D01*
X1517006Y198020D01*
X1511781D01*
X1510837Y198964D01*
Y203237D01*
X1512700Y205100D01*
G01X1535000Y207200D02*
X1533700Y208500D01*
X1524550D01*
X1518775Y214275D01*
X1510875D01*
X1508025Y211425D01*
X1502219D01*
X1500004Y209210D01*
G01X1479000Y207225D02*
X1480344Y208569D01*
X1499363D01*
X1500004Y209210D01*
G01X1516600Y200200D02*
X1515300D01*
X1514700Y200800D01*
Y211875D01*
X1514275Y212300D01*
X1512226D01*
X1511800Y211874D01*
Y209669D01*
X1512525Y208944D01*
G01X1519200Y203200D02*
X1516761D01*
X1516598Y203037D01*
G01X1505000Y214000D02*
X1509173D01*
X1510373Y215200D01*
X1520300D01*
X1524580Y210920D01*
X1529699D01*
G01X1505000Y209000D02*
X1507617D01*
X1511842Y213225D01*
X1517775D01*
X1525080Y205920D01*
X1529699D01*
G01Y185920D02*
Y187700D01*
X1529199Y188200D01*
X1524199D01*
X1523595Y188804D01*
Y198104D01*
X1521499Y200200D01*
X1520100D01*
G01X1510800Y193330D02*
X1511970Y194500D01*
X1515931D01*
X1517092Y193339D01*
Y191021D01*
X1525031Y183082D01*
X1538193D01*
X1543447Y177828D01*
X1549235D01*
X1554010Y173053D01*
Y172278D01*
X1554009Y172277D01*
Y171511D01*
X1554010Y171510D01*
Y171498D01*
X1554022D01*
X1559944Y165576D01*
X1563309D01*
X1567841Y161044D01*
X1576646D01*
X1581995Y155695D01*
G01X1529699Y190920D02*
Y192574D01*
X1530425Y193300D01*
X1534400D01*
X1534950Y193850D01*
Y198078D01*
X1535572Y198700D01*
X1536453D01*
X1537075Y198078D01*
Y192322D01*
X1537697Y191700D01*
X1538578D01*
X1539200Y192322D01*
Y202700D01*
X1538500Y203400D01*
X1525195D01*
X1521895Y206700D01*
X1519200D01*
G01X1585099Y164538D02*
X1578516D01*
X1577634Y165420D01*
X1569478D01*
X1566939Y167959D01*
X1560179D01*
X1555935Y172203D01*
Y173851D01*
X1550033Y179753D01*
X1544256D01*
X1541000Y183009D01*
Y204410D01*
X1535301Y210109D01*
Y223699D01*
X1532622Y226378D01*
X1504590D01*
X1502089Y228879D01*
X1498608D01*
X1497687Y229800D01*
X1491188D01*
X1489061Y231927D01*
G01X1537972Y236000D02*
X1534322Y239650D01*
X1522613D01*
X1521102Y241161D01*
X1519677D01*
X1516944Y238428D01*
X1506564D01*
X1497076Y247916D01*
X1487008D01*
X1486926Y247834D01*
G01X1507003Y272249D02*
X1505768D01*
X1505547Y272028D01*
X1491122D01*
G01X1492753Y273724D02*
X1492529Y273500D01*
X1489649D01*
X1487972Y275177D01*
G01X1476948Y276753D02*
X1475374Y278327D01*
G01X1514500Y285000D02*
X1513000Y283500D01*
X1506500D01*
X1499324Y276324D01*
X1496393D01*
X1496386Y276331D01*
X1492276D01*
X1491122Y275177D01*
G01X1499559Y231173D02*
X1503040D01*
X1505541Y228672D01*
X1533573D01*
X1554548Y207697D01*
Y196376D01*
X1551718Y193546D01*
Y187714D01*
X1566053Y173379D01*
X1567609D01*
X1570687Y176457D01*
X1572671D01*
X1572672Y176456D01*
X1580443D01*
X1581993Y178006D01*
X1586006D01*
X1588500Y180500D01*
Y187229D01*
X1591361Y190090D01*
X1593960D01*
X1594350Y190480D01*
X1601565D01*
X1603504Y188541D01*
X1603934D01*
G01X1486397Y270454D02*
X1484823Y272028D01*
G01X1503946Y221770D02*
Y220346D01*
X1502850Y219250D01*
X1500672D01*
X1500346Y219576D01*
G01D02*
X1498022Y221900D01*
G01X1498478Y233675D02*
X1503783D01*
X1506492Y230966D01*
X1534524D01*
X1541440Y224050D01*
X1570540D01*
X1572245Y222345D01*
X1572271D01*
X1577096Y217520D01*
X1581275D01*
X1581700Y217095D01*
Y215770D01*
G01X1469075Y268878D02*
Y267663D01*
X1469829Y266909D01*
G01X1473798Y270454D02*
X1472224Y272028D01*
G01X1476948Y270454D02*
X1475374Y272028D01*
G01X1480098Y267304D02*
X1478524Y268878D01*
G01X1545802Y233529D02*
Y236303D01*
X1543717Y238388D01*
X1542212D01*
X1538014Y242586D01*
X1526263D01*
X1525263Y243586D01*
Y243589D01*
X1524289Y244563D01*
X1521183D01*
X1519206Y242586D01*
X1516090D01*
X1515102Y241598D01*
X1513642D01*
X1513150Y242090D01*
X1505048D01*
X1495209Y251929D01*
X1486276D01*
X1486147Y251800D01*
X1484700D01*
G01X1499472Y250370D02*
Y252819D01*
X1501210Y254557D01*
Y257714D01*
X1495378Y263546D01*
X1475146D01*
X1472224Y266468D01*
Y268878D01*
G01X1503842Y245678D02*
X1504374Y246210D01*
Y253362D01*
X1503619Y254117D01*
Y256861D01*
X1494880Y265600D01*
X1475799D01*
X1475374Y266025D01*
Y268878D01*
G01X1476948Y273603D02*
X1475374Y275177D01*
G01X1473798Y276753D02*
X1472224Y278327D01*
G01X1495300Y224000D02*
X1497678Y226378D01*
X1500622D01*
X1502800Y224200D01*
X1506500D01*
X1507446Y223254D01*
Y221770D01*
G01X1511000Y221750D02*
X1507466D01*
X1507446Y221770D01*
G01X1518000Y221750D02*
X1521250D01*
X1522080Y220920D01*
X1529699D01*
G01X1518000Y221750D02*
X1511000D01*
G01X1487972Y278327D02*
X1489335Y276964D01*
X1491686D01*
X1492022Y277300D01*
X1496395D01*
X1497082Y277987D01*
G01X1506396Y289741D02*
X1509479D01*
X1509566Y289654D01*
X1513046D01*
X1513600Y289100D01*
X1528900D01*
X1531726Y291926D01*
Y293926D01*
X1533829Y296029D01*
X1534400D01*
G01X1506396Y289741D02*
X1504041D01*
X1499865Y285565D01*
X1493333D01*
X1491122Y287776D01*
G01X1507476Y299289D02*
Y297892D01*
X1507001Y297417D01*
X1500832D01*
X1499723Y298526D01*
Y300106D01*
G01X1505935Y306674D02*
X1507459Y305150D01*
X1514150D01*
X1515803Y303497D01*
X1520972D01*
G01X1505923Y309510D02*
X1507792Y307641D01*
X1508455D01*
G01X1512733Y295817D02*
X1520972D01*
G01X1512182Y293317D02*
Y294217D01*
X1512733Y294768D01*
Y295817D01*
G01X1504453Y299289D02*
X1503172D01*
X1501145Y301316D01*
Y302555D01*
X1497328Y306372D01*
X1497179D01*
G01X1508455Y310641D02*
Y313041D01*
G01X1507476Y302789D02*
X1504453D01*
G01X1510476Y302816D02*
X1507503D01*
X1507476Y302789D01*
G01X1513476Y302816D02*
X1510476D01*
G01X1511955Y307641D02*
X1514416D01*
X1516000Y306057D01*
X1520972D01*
G01X1511955Y310641D02*
Y307641D01*
G01X1520972Y308617D02*
Y311578D01*
X1520750Y311800D01*
Y314300D01*
G01X1480098Y301948D02*
X1478524Y300374D01*
G01X1495651Y311350D02*
X1491122Y306821D01*
Y306673D01*
G01X1493400Y300800D02*
X1492974Y300374D01*
X1491122D01*
G01X1514067Y315626D02*
X1513145Y314704D01*
X1507766D01*
X1507569Y314507D01*
X1499393D01*
X1494697Y319203D01*
X1484754D01*
X1481673Y316122D01*
G01X1486397Y298798D02*
X1484823Y297224D01*
G01X1501550Y293750D02*
Y294550D01*
X1496900Y299200D01*
X1493069D01*
X1492669Y298800D01*
X1489900D01*
X1488324Y297224D01*
X1487972D01*
G01X1472500Y347250D02*
X1474250D01*
X1475000Y346500D01*
Y339326D01*
X1477253Y337073D01*
Y335993D01*
X1475820Y334560D01*
Y333480D01*
X1476443Y332857D01*
X1477123D01*
X1478856Y334590D01*
X1479736D01*
X1480359Y333967D01*
Y333087D01*
X1478726Y331454D01*
Y330574D01*
X1479349Y329951D01*
X1480229D01*
X1482550Y332272D01*
Y333600D01*
G01X1482585Y340856D02*
X1483000Y341271D01*
Y343750D01*
G01X1487000Y333300D02*
X1485337D01*
X1483374Y335263D01*
X1481133D01*
X1477000Y339396D01*
Y343750D01*
G01X1478524Y294075D02*
X1480098Y295649D01*
G01X1476948Y298798D02*
X1475374Y297224D01*
G01X1499681Y279910D02*
X1498850Y280741D01*
Y281850D01*
X1496700Y284000D01*
X1491748D01*
X1491122Y284626D01*
G01X1472500Y354250D02*
X1471438D01*
X1470837Y353649D01*
Y340385D01*
X1472059Y339163D01*
X1473139D01*
X1474300Y338002D01*
Y331700D01*
X1477975Y328025D01*
X1487825D01*
X1491390Y331590D01*
X1500397D01*
X1503142Y334335D01*
X1506960D01*
X1508143Y335518D01*
X1517551D01*
X1518073Y334996D01*
X1527580D01*
X1527581Y334997D01*
X1529029D01*
X1537547Y326479D01*
X1539597D01*
X1541476Y324600D01*
X1542200D01*
G01X1484823Y303524D02*
X1486397Y305098D01*
G01X1518006Y286706D02*
X1517818D01*
X1516112Y285000D01*
X1514500D01*
G01X1499987Y288487D02*
X1499974Y288500D01*
X1499300D01*
X1496000Y291800D01*
X1492400D01*
X1491800Y292400D01*
X1486800D01*
X1485325Y290925D01*
X1484823D01*
G01X1547882Y318942D02*
X1545375Y321449D01*
Y326625D01*
X1543875Y328125D01*
X1543000D01*
X1539224Y331901D01*
X1537836D01*
X1531687Y338050D01*
X1527751D01*
X1527301Y338500D01*
X1523250D01*
G01D02*
Y341100D01*
X1523000Y341350D01*
Y343750D01*
G01X1513476Y299316D02*
X1515222D01*
X1516161Y298377D01*
X1520972D01*
G01X1473798Y279902D02*
X1472224Y281476D01*
G01Y306673D02*
X1473798Y308247D01*
G01X1476948Y305098D02*
X1475374Y303524D01*
G01X1497509Y303120D02*
X1497430D01*
X1494426Y306124D01*
X1492500D01*
X1491626Y305250D01*
X1489700D01*
X1487974Y303524D01*
X1487972D01*
G01X1489546Y308247D02*
X1487972Y306673D01*
G01X1500840Y319870D02*
X1501850D01*
X1503910Y321930D01*
X1511460D01*
X1513043Y320347D01*
X1513193D01*
X1513411Y320129D01*
X1514789D01*
X1515763Y321103D01*
Y322793D01*
X1516910Y323940D01*
G01X1518060Y317520D02*
X1518864Y318324D01*
X1519360D01*
X1521778Y320742D01*
X1523812D01*
X1524710Y321640D01*
Y324270D01*
X1523887Y325093D01*
X1521513D01*
G01X1476948Y289351D02*
X1475374Y290925D01*
G01X1493700Y281476D02*
X1491122D01*
G01X1476948Y311397D02*
X1475374Y309823D01*
G01X1480098Y314546D02*
X1478524Y312972D01*
G01X1496600Y281400D02*
X1494900Y283100D01*
X1489498D01*
X1487972Y284626D01*
G01X1489546Y317696D02*
X1487972Y316122D01*
G01X1483247Y283052D02*
X1481673Y284626D01*
G01X1484823Y294075D02*
X1486397Y295649D01*
G01Y308247D02*
X1484823Y306673D01*
G01X1491122Y294075D02*
X1491254Y293943D01*
X1493268D01*
G01X1496900Y293900D02*
X1495800D01*
X1494100Y295600D01*
X1489497D01*
X1487972Y294075D01*
G01X1502000Y343750D02*
Y341340D01*
X1503246Y340094D01*
Y338578D01*
X1502142Y337474D01*
X1501274D01*
X1498600Y334800D01*
G01X1496400Y336376D02*
X1492993D01*
X1491960Y337409D01*
Y342710D01*
X1493000Y343750D01*
G01X1495445Y338724D02*
X1494776D01*
X1493680Y339820D01*
Y341430D01*
X1496000Y343750D01*
G01X1499000D02*
Y342079D01*
X1499829Y341250D01*
G01X1473798Y301948D02*
X1472224Y300374D01*
G01X1521513Y327652D02*
X1524176D01*
X1526881Y324947D01*
X1530573D01*
X1531565Y323955D01*
Y321192D01*
X1532357Y320400D01*
X1536805D01*
X1538642Y318563D01*
X1538685D01*
X1538711Y318537D01*
X1540089D01*
X1540252Y318700D01*
X1543082D01*
X1545662Y316120D01*
Y311775D01*
X1546999Y310438D01*
X1549145D01*
X1551425Y312718D01*
Y313984D01*
X1555061Y317620D01*
X1559980D01*
G01X1484823Y316122D02*
Y316123D01*
X1486396Y317696D01*
G01X1505869Y318669D02*
Y316398D01*
X1505044Y315573D01*
X1502028D01*
X1497194Y320407D01*
X1477900D01*
X1476750Y319257D01*
Y314348D01*
X1475374Y312972D01*
G01X1495699Y314546D02*
X1495846D01*
X1494272Y312972D01*
X1491122D01*
G01X1476948Y308247D02*
X1475374Y306673D01*
G01X1470649Y311397D02*
X1469075Y309823D01*
G01X1470649Y279902D02*
X1469075Y281476D01*
G01X1465925Y306673D02*
X1467712Y308460D01*
Y316686D01*
X1468594Y317568D01*
Y322618D01*
X1469568Y323592D01*
X1478556D01*
X1478992Y323156D01*
X1493016D01*
X1498910Y329050D01*
X1501274D01*
X1501514Y329290D01*
X1505240D01*
X1509118Y333168D01*
X1516552D01*
X1517074Y332646D01*
X1528055D01*
X1536572Y324129D01*
X1538002D01*
X1542356Y319775D01*
X1543316D01*
X1546587Y316504D01*
Y312159D01*
X1547383Y311363D01*
X1548761D01*
X1550500Y313102D01*
Y314575D01*
X1552913Y316988D01*
Y324987D01*
X1552000Y325900D01*
G01X1473798Y314546D02*
X1472224Y312972D01*
G01X1525051Y329553D02*
X1524606Y329108D01*
X1520970D01*
X1518313Y331765D01*
X1516754D01*
X1516176Y332343D01*
X1509506D01*
X1505573Y328410D01*
X1501801D01*
X1501616Y328225D01*
X1499252D01*
X1493358Y322331D01*
X1479598D01*
X1479124Y321857D01*
X1472565D01*
X1469845Y319137D01*
Y316892D01*
X1469075Y316122D01*
G01X1470649Y301948D02*
X1469075Y300374D01*
G01X1483247Y314546D02*
X1481673Y312972D01*
G01X1483247Y286202D02*
X1481673Y287776D01*
G01X1479678Y339778D02*
X1480000Y340100D01*
Y343750D01*
G01X1482386Y336926D02*
X1481210Y338102D01*
Y338116D01*
X1479678Y339648D01*
Y339778D01*
G01X1486397Y314546D02*
X1484823Y312972D01*
G01X1483247Y311397D02*
X1481673Y309823D01*
G01X1492700Y311376D02*
X1491147Y309823D01*
X1491122D01*
G01Y297224D02*
X1495224D01*
X1495300Y297300D01*
G01X1478524Y318900D02*
Y316122D01*
G01X1480098Y311397D02*
X1478524Y309823D01*
G01X1483247Y301948D02*
X1481673Y300374D01*
G01X1493500Y304400D02*
X1492624Y303524D01*
X1491122D01*
G01X1466970Y320235D02*
X1466823Y320088D01*
Y317020D01*
X1465925Y316122D01*
G01X1514100Y321792D02*
X1513882Y322010D01*
X1513140D01*
X1510987Y324163D01*
Y325669D01*
G01X1516910Y327440D02*
X1517115Y327645D01*
Y330005D01*
G01X1505075Y391940D02*
X1505300Y391836D01*
X1505500Y391743D01*
X1507025Y391034D01*
G01X1476732Y395098D02*
X1476434Y394800D01*
X1474113D01*
X1473083Y393770D01*
G01X1491425Y381800D02*
X1493375Y380894D01*
G01X1499000Y347250D02*
X1501140Y349390D01*
Y354070D01*
X1503700Y356630D01*
Y358850D01*
X1505536Y360686D01*
G01X1499225Y395320D02*
X1501175Y394414D01*
G01X1497275Y391940D02*
X1499225Y391034D01*
G01X1497275Y385180D02*
X1499225Y384274D01*
G01X1487525Y397794D02*
X1485575Y398700D01*
G01X1486000Y364500D02*
Y356500D01*
X1484212Y354712D01*
X1483211D01*
X1479251Y350752D01*
Y348914D01*
X1480000Y348165D01*
Y347250D01*
G01X1472500D02*
Y350750D01*
G01X1487000Y347250D02*
X1485771D01*
X1485051Y346530D01*
Y344533D01*
X1484268Y343750D01*
X1483000D01*
G01X1487000Y347250D02*
Y353593D01*
X1490339Y356932D01*
Y357611D01*
X1492824Y360096D01*
Y367530D01*
X1492067Y368287D01*
G01X1491615Y366913D02*
X1491999Y366529D01*
Y361287D01*
X1488479Y357767D01*
G01X1481500Y365500D02*
Y355017D01*
X1477000Y350517D01*
Y347250D01*
G01X1491425Y395320D02*
X1493375Y394414D01*
G01X1487525Y395320D02*
X1489475Y394414D01*
G01X1485575Y385180D02*
X1487525Y384274D01*
G01Y388560D02*
X1489475Y387654D01*
G01X1495552Y364865D02*
Y358280D01*
X1494950Y357678D01*
Y356500D01*
G01X1499225Y377514D02*
X1497275Y378420D01*
G01X1493375Y391940D02*
X1495325Y391034D01*
G01X1491425Y388560D02*
X1493375Y387654D01*
G01X1503125Y395320D02*
X1504600Y394635D01*
X1505075Y394414D01*
G01X1499225Y388560D02*
X1501175Y387654D01*
G01X1514000Y347250D02*
Y352678D01*
X1512520Y354158D01*
Y355283D01*
G01X1495325Y377514D02*
X1493375Y378420D01*
G01X1520313Y357069D02*
X1520158D01*
X1519889Y357338D01*
Y363635D01*
G01X1487525Y377514D02*
X1485575Y378420D01*
G01X1517000Y347250D02*
Y349597D01*
X1517367Y349964D01*
G01X1516960Y352580D02*
Y350371D01*
X1517367Y349964D01*
G01X1520425Y354379D02*
X1520248D01*
X1518690Y355937D01*
Y358847D01*
X1518942Y359099D01*
Y361258D01*
G01X1520429Y354379D02*
X1520425D01*
G01D02*
X1520000Y353954D01*
Y347250D01*
G01X1525561Y350253D02*
X1526000Y349814D01*
Y347250D01*
G01X1525561Y350253D02*
Y350851D01*
X1523034Y353378D01*
Y359903D01*
X1524114Y360983D01*
Y363985D01*
G01X1511000Y347250D02*
Y350627D01*
G01D02*
X1511614Y351241D01*
G01X1503125Y388560D02*
X1504600Y387875D01*
X1505075Y387654D01*
G01X1503125Y402080D02*
X1504600Y401395D01*
X1505075Y401174D01*
G01X1499225Y402080D02*
X1501175Y401174D01*
G01X1520675Y391940D02*
X1522625Y391034D01*
G01X1495325Y397794D02*
X1493375Y398700D01*
G01X1499225Y397794D02*
X1497275Y398700D01*
G01X1491425Y402080D02*
X1493375Y401174D01*
G01X1487525Y402080D02*
X1489475Y401174D01*
G01X1505075Y385180D02*
X1505300Y385076D01*
X1505500Y384983D01*
X1507025Y384274D01*
G01X1499225Y381800D02*
X1501175Y380894D01*
G01X1494481Y368540D02*
X1493756Y367815D01*
Y359825D01*
X1491814Y357883D01*
Y349528D01*
X1490000Y347714D01*
Y347250D01*
G01X1494950Y353000D02*
Y351050D01*
X1496000Y350000D01*
G01X1526525Y381800D02*
X1528475Y380894D01*
G01X1470800Y395200D02*
X1471300Y395700D01*
X1475535D01*
X1476902Y397067D01*
X1478366D01*
G01X1502000Y347250D02*
X1502063D01*
X1505400Y350587D01*
Y357732D01*
G01X1493000Y347250D02*
Y357595D01*
X1494656Y359251D01*
Y365457D01*
G01X1496000Y347250D02*
X1500165Y351415D01*
Y355015D01*
X1501900Y356750D01*
Y358500D01*
X1504509Y361109D01*
G01X1522625Y397794D02*
X1520675Y398700D01*
G01X1490098Y367202D02*
X1490826Y366474D01*
Y366473D01*
X1490927Y366372D01*
Y362815D01*
X1488479Y360367D01*
G01X1508000Y347250D02*
X1509200Y348450D01*
Y351601D01*
X1510807Y353208D01*
G01X1505000Y347250D02*
X1507154Y349404D01*
Y353100D01*
G01X1526525Y402080D02*
X1528475Y401174D01*
G01X1526525Y388560D02*
X1528475Y387654D01*
G01X1527500Y371555D02*
X1526934Y370989D01*
Y369538D01*
X1526336Y368940D01*
Y367548D01*
X1526657Y367227D01*
Y360842D01*
X1527145Y360354D01*
Y356616D01*
X1524746Y354217D01*
G01X1514825Y381800D02*
X1516775Y380894D01*
G01X1528475Y398700D02*
X1527275Y397500D01*
X1526659D01*
G01X1526525Y395320D02*
X1527500Y394868D01*
X1528475Y394415D01*
Y394414D01*
G01X1522625Y381800D02*
X1524575Y380894D01*
G01X1507025Y377514D02*
X1505075Y378420D01*
G01X1522625Y395320D02*
X1520675Y394414D01*
G01X1522625Y377514D02*
X1520675Y378420D01*
G01X1489609Y366524D02*
X1490001Y366132D01*
Y364489D01*
X1488479Y362967D01*
G01X1518725Y397794D02*
X1516775Y398700D01*
G01Y391940D02*
X1518725Y391034D01*
G01X1516775Y385180D02*
X1518725Y384274D01*
G01X1510925Y397794D02*
X1508975Y398700D01*
G01X1510925Y402080D02*
X1512875Y401174D01*
G01X1510925Y395320D02*
X1512875Y394414D01*
G01X1475098Y393130D02*
X1475768Y393800D01*
X1477250D01*
X1477843Y394393D01*
X1478889D01*
X1479629Y393653D01*
Y393349D01*
X1481178Y391800D01*
X1482300D01*
X1484600Y394100D01*
G01X1523000Y347250D02*
Y351739D01*
X1522043Y352696D01*
Y358009D01*
X1520865Y359187D01*
Y361500D01*
G01X1493375Y385180D02*
X1495325Y384274D01*
G01X1485575Y391940D02*
X1483868Y390233D01*
G01X1518725Y402080D02*
X1520675Y401174D01*
G01X1514825Y402080D02*
X1516775Y401174D01*
G01X1514825Y395320D02*
X1516775Y394414D01*
G01X1510925Y377514D02*
X1508975Y378420D01*
G01X1510925Y381800D02*
X1512875Y380894D01*
G01X1518725Y377514D02*
X1516775Y378420D01*
G01X1522625Y384274D02*
X1520675Y385180D01*
G01X1508975Y391940D02*
X1510925Y391034D01*
G01X1514825Y388560D02*
X1516775Y387654D01*
G01X1510925Y388560D02*
X1512875Y387654D01*
G01X1508975Y385180D02*
X1510925Y384274D01*
G01X1487525Y381800D02*
X1489475Y380894D01*
G01X1524575Y387654D02*
X1522625Y388560D01*
G01X1503878Y364717D02*
Y368287D01*
G01X1516960Y356080D02*
Y359819D01*
X1518111Y360970D01*
Y363949D01*
X1518000Y364060D01*
G01X1510925Y462920D02*
X1512875Y463826D01*
G01X1507025Y462920D02*
X1507600Y463187D01*
X1508975Y463826D01*
G01X1499225Y422360D02*
X1501175Y421454D01*
G01X1499225Y429120D02*
X1499904Y428804D01*
X1500246Y428646D01*
X1500559Y428500D01*
X1501175Y428214D01*
G01X1497275Y418980D02*
X1497162Y418928D01*
X1495325Y418074D01*
G01X1497275Y425740D02*
X1497319Y425719D01*
X1497791Y425500D01*
X1499225Y424834D01*
G01X1526525Y462920D02*
X1528475Y463826D01*
G01X1505075Y405460D02*
X1505300Y405356D01*
X1507025Y404554D01*
G01X1497275Y405460D02*
X1499225Y404554D01*
G01X1497275Y412220D02*
X1497749Y412000D01*
X1499225Y411314D01*
G01Y408840D02*
X1501175Y407934D01*
G01X1497275Y439260D02*
X1499225Y440166D01*
G01X1521800Y445100D02*
X1523375Y443525D01*
G01X1526525D02*
X1524950Y445100D01*
G01X1526525Y446675D02*
X1524950Y448250D01*
G01X1507625Y446675D02*
X1509200Y448250D01*
G01X1510775Y449825D02*
X1509200Y451400D01*
G01D02*
X1507625Y449825D01*
G01X1497275Y446020D02*
X1499225Y446926D01*
G01X1497275Y452780D02*
X1499225Y453686D01*
G01X1503125Y408840D02*
X1504600Y408155D01*
X1505075Y407934D01*
G01X1487525Y408840D02*
X1489475Y407934D01*
G01X1493375D02*
X1491425Y408840D01*
G01X1508975Y466300D02*
X1510912Y467200D01*
X1510925Y467206D01*
G01X1505075Y466300D02*
X1505300Y466404D01*
X1505500Y466497D01*
X1507012Y467200D01*
X1507025Y467206D01*
G01X1518725Y476440D02*
X1520675Y477346D01*
G01X1512875Y466300D02*
X1514812Y467200D01*
X1514825Y467206D01*
G01X1510925Y469680D02*
X1511183Y469800D01*
X1512875Y470586D01*
G01X1512969Y616398D02*
Y618291D01*
X1511204Y620056D01*
G01X1477431Y615130D02*
Y616974D01*
X1475837Y618568D01*
Y619171D01*
X1475883Y619217D01*
G01X1584447Y-6702D02*
X1586547D01*
G01X1583398Y-4537D02*
X1581062D01*
X1580599Y-5000D01*
X1568600D01*
X1566200Y-2600D01*
X1564400D01*
G01X1566800Y-6800D02*
X1565000D01*
X1562737Y-4537D01*
X1558737D01*
X1558000Y-3800D01*
Y-2600D01*
G01X1561200D02*
X1564400D01*
G01X1558000D02*
X1561200D01*
G01X1536500Y-6500D02*
Y-2926D01*
X1536074Y-2500D01*
X1534000D01*
G01D02*
X1530800D01*
G01D02*
X1527600D01*
G01X1557800Y-6200D02*
Y-5156D01*
X1557044Y-4400D01*
X1555400D01*
X1554800Y-3800D01*
Y-2600D01*
G01D02*
X1551600D01*
G01D02*
X1548400D01*
G01X1546800Y3400D02*
X1546599Y3199D01*
Y-2299D01*
X1546900Y-2600D01*
X1548400D01*
G01X1540000Y-2500D02*
X1543500D01*
G01X1540000D02*
Y-10000D01*
X1535000Y-15000D01*
G01X1558000Y900D02*
Y3400D01*
G01X1527600Y1000D02*
Y3500D01*
G01X1554800Y900D02*
Y3400D01*
G01X1564400Y900D02*
Y2200D01*
X1563200Y3400D01*
G01X1530800Y1000D02*
Y3500D01*
G01X1551600Y900D02*
Y2700D01*
X1552300Y3400D01*
G01X1543500Y1000D02*
Y3400D01*
G01X1540000Y1000D02*
Y3400D01*
G01X1573898Y-3069D02*
X1568669D01*
X1566300Y-700D01*
Y3100D01*
X1566000Y3400D01*
G01X1589000Y-16100D02*
X1586500D01*
G01X1581947Y-6702D02*
Y-10547D01*
X1584000Y-12600D01*
X1589000D01*
G01X1561200Y900D02*
Y2700D01*
X1560500Y3400D01*
G01X1534000Y1000D02*
Y3500D01*
G01X1548400Y900D02*
Y2000D01*
X1549800Y3400D01*
G01X1533000Y-6500D02*
X1528500D01*
G01X1570300Y-6800D02*
X1573300D01*
G01D02*
Y-9200D01*
X1575000Y-10900D01*
Y-15000D01*
G01X1554300Y-6200D02*
X1551300D01*
G01X1554300D02*
Y-9700D01*
X1555000Y-10400D01*
Y-15000D01*
G01X1573898Y431D02*
X1571969D01*
X1569000Y3400D01*
G01X1580398Y-600D02*
X1583398D01*
G01X1580398D02*
X1579367Y431D01*
X1577398D01*
G01X1586547Y5502D02*
X1580500D01*
X1580398Y5400D01*
G01X1577398Y-3069D02*
X1579400D01*
X1579900Y-2569D01*
X1583398D01*
G01X1571500Y-1406D02*
X1576972D01*
X1577398Y-1832D01*
Y-3069D01*
G01Y3931D02*
X1579270D01*
X1579864Y3337D01*
X1583398D01*
G01X1593200Y63075D02*
X1590356D01*
X1584192Y69239D01*
X1581761D01*
X1574309Y76691D01*
X1562162Y83695D01*
X1559481Y87705D01*
X1558145Y94418D01*
X1557679Y94800D01*
X1556200D01*
G01X1586500Y90500D02*
X1584500D01*
X1582500Y92500D01*
Y94500D01*
G01X1585500D02*
X1586500D01*
X1588021Y96021D01*
X1591478D01*
X1592850Y97393D01*
Y102720D01*
X1591460Y104110D01*
G01X1583374Y81319D02*
X1582157Y82536D01*
X1580823D01*
X1572978Y90381D01*
Y91190D01*
X1568702Y95466D01*
Y102851D01*
X1570023Y104172D01*
G01X1574780Y90992D02*
X1570923Y94849D01*
Y99475D01*
X1573506Y102058D01*
X1577928D01*
X1580890Y105020D01*
G01X1586500Y87000D02*
Y85207D01*
X1587359Y84348D01*
G01X1593420Y131800D02*
X1586048D01*
X1585310Y132538D01*
G01D02*
Y133790D01*
X1585000Y134100D01*
Y135538D01*
G01X1576731Y128410D02*
X1576891D01*
X1578441Y126860D01*
X1584070D01*
X1585310Y128100D01*
Y129538D01*
G01X1588510Y130663D02*
X1597837D01*
X1600199Y128301D01*
X1604504D01*
X1605867Y129664D01*
G01X1585310Y129538D02*
X1586435Y130663D01*
X1588510D01*
G01X1573874Y140959D02*
Y143959D01*
G01Y140959D02*
X1574538D01*
X1577273Y138224D01*
X1585824D01*
X1588150Y140550D01*
X1592816D01*
G01X1602717Y132814D02*
X1601655Y133876D01*
X1600374D01*
X1594725Y139525D01*
X1588575D01*
X1587664Y138614D01*
G01X1573892Y134959D02*
Y137921D01*
X1573854Y137959D01*
G01X1587664Y138614D02*
X1586349Y137299D01*
X1576692D01*
X1576032Y137959D01*
X1573854D01*
G01X1585500Y94500D02*
X1582500D01*
G01X1577200Y108590D02*
X1581190D01*
X1582500Y109900D01*
G01D02*
X1584183Y111583D01*
Y112179D01*
G01X1580920Y115685D02*
X1582502D01*
X1582508Y115679D01*
X1584183D01*
G01X1587222Y115669D02*
X1585856D01*
X1585846Y115679D01*
X1584183D01*
G01X1592800Y115710D02*
X1589841D01*
X1589800Y115669D01*
X1587222D01*
G01X1602717Y145412D02*
X1599270D01*
X1597474Y147208D01*
X1593192D01*
X1589700Y150700D01*
X1588859D01*
X1584963Y154596D01*
Y156782D01*
X1580377Y161368D01*
G01X1581810Y132538D02*
X1580365D01*
X1579292Y131465D01*
Y131104D01*
X1579290D01*
G01X1581810Y129538D02*
X1580244D01*
X1579310Y128604D01*
G01X1570374Y140959D02*
X1569333D01*
X1567981Y139607D01*
G01X1567968Y136682D02*
X1569245Y137959D01*
X1570354D01*
G01X1542685Y133321D02*
X1541453D01*
X1540820Y133954D01*
Y134581D01*
X1539492Y135909D01*
X1536801D01*
G01X1570023Y104172D02*
X1572395Y106544D01*
Y110754D01*
G01X1580890Y105020D02*
X1584900Y109030D01*
X1588930D01*
X1593217Y113317D01*
X1602118D01*
X1602717Y113916D01*
G01X1585750Y149600D02*
X1589305D01*
X1592553Y146352D01*
X1596248D01*
X1598796Y143804D01*
X1604325D01*
X1605867Y142262D01*
G01X1581995Y155695D02*
X1585750Y151940D01*
Y149600D01*
G01X1536801Y133941D02*
X1533021D01*
X1531678Y135284D01*
G01X1588439Y154572D02*
X1586547Y156464D01*
Y158923D01*
X1588501Y160877D01*
Y161362D01*
G01X1579410Y120760D02*
X1579680Y121030D01*
X1586100D01*
X1588683Y123613D01*
X1591439D01*
X1592617Y122435D01*
G01X1536801Y126067D02*
X1541821D01*
X1542000Y126246D01*
G01X1542100Y119200D02*
X1541068Y120232D01*
Y121408D01*
X1540346Y122130D01*
X1536801D01*
G01X1542900Y121700D02*
X1540502Y124098D01*
X1536801D01*
G01X1585099Y169038D02*
Y170698D01*
X1585201Y170800D01*
Y172162D01*
G01X1585099Y169038D02*
Y168737D01*
X1586461Y167375D01*
X1589325D01*
X1591800Y164900D01*
G01X1585001Y161362D02*
Y163002D01*
X1585099Y163100D01*
Y164538D01*
G01X1588176Y157600D02*
X1591736Y161160D01*
X1602717D01*
G01X1537972Y236000D02*
X1546034Y227938D01*
X1562012D01*
X1565762Y231688D01*
Y238542D01*
X1570051Y242831D01*
X1576038D01*
X1578005Y240864D01*
Y228302D01*
X1589274Y217033D01*
X1590525D01*
G01X1553000Y159400D02*
Y157500D01*
X1553500Y157000D01*
G01X1579000Y196750D02*
X1573750D01*
X1572920Y195920D01*
X1567299D01*
G01X1557979Y188844D02*
X1558160Y188663D01*
Y188500D01*
X1563630Y183030D01*
X1571716D01*
X1575996Y178750D01*
X1579000D01*
G01X1574900Y240900D02*
X1576580Y239220D01*
Y230402D01*
X1576155Y229977D01*
X1572878D01*
X1572300Y229399D01*
Y228374D01*
X1572822Y227852D01*
X1576215D01*
X1576837Y227230D01*
Y226349D01*
X1576215Y225727D01*
X1574422D01*
X1573800Y225105D01*
Y224224D01*
X1574422Y223602D01*
X1575608D01*
X1576000Y223210D01*
Y220993D01*
X1577323Y219670D01*
X1584621D01*
X1588000Y216291D01*
Y209200D01*
X1584632Y205832D01*
X1581068D01*
X1578200Y208700D01*
Y210770D01*
G01D02*
X1574930D01*
X1569780Y215920D01*
X1567299D01*
G01X1578200Y215770D02*
X1576830D01*
X1571680Y220920D01*
X1567299D01*
G01X1553500Y165400D02*
Y165000D01*
X1553000Y164500D01*
Y162900D01*
G01X1558000Y205100D02*
X1559700Y203400D01*
X1584700D01*
X1593020Y211720D01*
Y215129D01*
G01X1567299Y185920D02*
X1578330D01*
X1579000Y185250D01*
G01D02*
Y182250D01*
G01X1588599Y169038D02*
X1592122D01*
X1592450Y168710D01*
G01X1588501Y161362D02*
X1589686Y162547D01*
X1604480D01*
X1605867Y161160D01*
G01X1588701Y172162D02*
Y172998D01*
X1587874Y173825D01*
X1582437D01*
X1581548Y172936D01*
X1571578D01*
X1568902Y170260D01*
X1563378D01*
X1559512Y174126D01*
X1556776D01*
X1556760Y174142D01*
Y174193D01*
X1546022Y184931D01*
Y191601D01*
X1547663Y193242D01*
Y197631D01*
X1552063Y202031D01*
G01X1558042Y172448D02*
X1561055Y169435D01*
X1569244D01*
X1571665Y171856D01*
X1577311D01*
X1582667Y166500D01*
X1587900D01*
X1588599Y165801D01*
Y164538D01*
G01X1591500Y181000D02*
Y180255D01*
X1586555Y175310D01*
X1582690D01*
X1581542Y174162D01*
X1571637D01*
X1568560Y171085D01*
X1565102D01*
X1561538Y174649D01*
G01X1554400Y255300D02*
X1557400D01*
X1561000Y258900D01*
Y260400D01*
G01D02*
X1562080Y261480D01*
X1569590D01*
X1571876Y259194D01*
Y255800D01*
G01X1550750Y264531D02*
X1555480D01*
X1557500Y262511D01*
Y260400D01*
G01X1560400Y307683D02*
X1558217Y305500D01*
X1557250D01*
G01X1553750Y301500D02*
X1551600D01*
X1548477Y298377D01*
X1544472D01*
G01X1564400Y308383D02*
X1563882D01*
X1559500Y304001D01*
Y299000D01*
X1559000Y298500D01*
X1557250D01*
G01X1544472Y295817D02*
X1548017D01*
X1550700Y298500D01*
X1553750D01*
G01X1550619Y303087D02*
X1551028D01*
X1551405Y303464D01*
X1556599D01*
X1557250Y302813D01*
Y301500D01*
G01X1559997Y310317D02*
X1559914D01*
X1558506Y308909D01*
X1557525D01*
G01X1554025D02*
X1552456Y307340D01*
X1551672D01*
X1550389Y306057D01*
X1544472D01*
G01X1557534Y353400D02*
Y353326D01*
X1558760Y352100D01*
Y342242D01*
X1559213Y341789D01*
Y340411D01*
X1558640Y339838D01*
Y335661D01*
X1559301Y335000D01*
X1560500D01*
G01X1568581Y323426D02*
X1569917D01*
X1575613Y329122D01*
Y338739D01*
X1574290Y340062D01*
X1569638D01*
X1566850Y342850D01*
Y344350D01*
G01X1572336Y287063D02*
X1572377Y287104D01*
Y287507D01*
X1573300Y288430D01*
X1581597D01*
X1584200Y291033D01*
Y296452D01*
X1582989Y297663D01*
X1582637D01*
X1579400Y300900D01*
Y302045D01*
X1574497Y306948D01*
Y314870D01*
X1574081Y315286D01*
X1570688D01*
X1570124Y315850D01*
Y319243D01*
X1568581Y320786D01*
Y323426D01*
G01X1577500Y299500D02*
X1578600D01*
X1580600Y297500D01*
Y296832D01*
X1580277Y296509D01*
Y295131D01*
X1580600Y294808D01*
Y292730D01*
X1578790Y290920D01*
G01X1573000Y303500D02*
X1576000D01*
X1577500Y302000D01*
Y299500D01*
G01X1578790Y290920D02*
X1577911D01*
X1577107Y291724D01*
X1574447D01*
G01X1568524Y312885D02*
X1568970Y313331D01*
Y316730D01*
X1566918Y318782D01*
Y325950D01*
X1568422Y327454D01*
X1571232D01*
X1572331Y328553D01*
Y331926D01*
G01X1581077Y284825D02*
Y284824D01*
X1581370Y284531D01*
X1594084D01*
X1606163Y272452D01*
Y265711D01*
X1605189Y264737D01*
X1604790D01*
X1603898Y263845D01*
Y258242D01*
X1604604Y257536D01*
X1610436D01*
X1610892Y257992D01*
X1615512D01*
G01X1550800Y296200D02*
Y294392D01*
X1551527Y293665D01*
X1561335D01*
X1562070Y292930D01*
Y288439D01*
X1561432Y287801D01*
X1557667D01*
X1556710Y286844D01*
Y285090D01*
X1558730Y283070D01*
X1593513D01*
X1603741Y272842D01*
Y269978D01*
X1602473Y268710D01*
Y259736D01*
X1602150Y259413D01*
Y255500D01*
G01X1548024Y322145D02*
X1546200Y323969D01*
Y327400D01*
X1544650Y328950D01*
X1543578D01*
X1539802Y332726D01*
X1538274D01*
X1531864Y339136D01*
X1529344D01*
X1528337Y340143D01*
Y341837D01*
X1529000Y342500D01*
Y343750D01*
G01X1548000Y331361D02*
X1547561Y331800D01*
X1544760D01*
X1540900Y335660D01*
X1539683D01*
X1538500Y336843D01*
Y340900D01*
X1538000Y341400D01*
Y343750D01*
G01X1548199Y285830D02*
X1548400D01*
Y285800D01*
X1548000Y285400D01*
Y283250D01*
G01X1560500Y343750D02*
Y338500D01*
G01D02*
X1573500D01*
X1573950Y338050D01*
G01X1542500Y343750D02*
Y342524D01*
X1540957Y340981D01*
Y340823D01*
G01X1553750Y305500D02*
X1550999D01*
X1550598Y305099D01*
X1550068D01*
X1550065Y305096D01*
X1549830D01*
X1548231Y303497D01*
X1544472D01*
G01X1556500Y338250D02*
Y340050D01*
X1557550Y341100D01*
G01D02*
X1556500Y342150D01*
Y343750D01*
G01X1554800Y341100D02*
X1553500Y342400D01*
Y343750D01*
G01Y338250D02*
Y339800D01*
X1554800Y341100D01*
G01X1577500Y327750D02*
X1579250D01*
X1581000Y326000D01*
X1581941D01*
G01X1577500Y330750D02*
Y327750D01*
G01X1572588Y322014D02*
Y323742D01*
X1576596Y327750D01*
X1577500D01*
G01X1583794Y338767D02*
X1583884D01*
X1584218Y338433D01*
Y338157D01*
X1584500Y337875D01*
Y333000D01*
G01X1591500Y329250D02*
X1585250D01*
X1584500Y330000D01*
Y333000D01*
G01X1577500Y334250D02*
Y340400D01*
X1576500Y341400D01*
G01X1605819Y262829D02*
X1607600Y264610D01*
Y269192D01*
X1608025Y269617D01*
X1608407D01*
X1608832Y270042D01*
Y270892D01*
X1608407Y271317D01*
X1608025D01*
X1607600Y271742D01*
Y273072D01*
X1594607Y286065D01*
X1589795D01*
X1585982Y289878D01*
Y290480D01*
X1586583Y291081D01*
X1587185D01*
X1590369Y287897D01*
X1591071D01*
X1591622Y288448D01*
Y289050D01*
X1585125Y295547D01*
Y296836D01*
X1583373Y298588D01*
X1583021D01*
X1581800Y299809D01*
Y301374D01*
X1581375Y301799D01*
X1580953D01*
X1580528Y302224D01*
Y303074D01*
X1580953Y303499D01*
X1581375D01*
X1581800Y303924D01*
Y309024D01*
X1581119Y309705D01*
X1580503D01*
X1579462Y308664D01*
X1578860D01*
X1578259Y309265D01*
Y309867D01*
X1581323Y312931D01*
Y313533D01*
X1580722Y314134D01*
X1580120D01*
X1577056Y311070D01*
X1576454D01*
X1575853Y311671D01*
Y312273D01*
X1576897Y313317D01*
Y313919D01*
X1575645Y315171D01*
Y316650D01*
X1575220Y317075D01*
X1571649D01*
X1571224Y317500D01*
Y318299D01*
X1571649Y318724D01*
X1575220D01*
X1575645Y319149D01*
Y320664D01*
G01X1564427Y311083D02*
X1564436Y311074D01*
X1564616D01*
X1565940Y309750D01*
X1567500D01*
G01X1559980Y317620D02*
Y312810D01*
X1561706Y311084D01*
X1564426D01*
X1564427Y311083D01*
G01X1573000Y312500D02*
X1571914D01*
X1569164Y309750D01*
X1567500D01*
G01X1562000Y303000D02*
Y300500D01*
X1563034Y299466D01*
Y294020D01*
X1563664Y293390D01*
X1565450D01*
X1567230Y291610D01*
Y290130D01*
X1565947Y288847D01*
Y287974D01*
G01X1562000Y303000D02*
Y304500D01*
X1563750Y306250D01*
X1567500D01*
G01X1548334Y325497D02*
Y327466D01*
X1545815Y329985D01*
X1545806D01*
X1545416Y330375D01*
X1544169D01*
X1540392Y334152D01*
X1538864D01*
X1536100Y336916D01*
Y339000D01*
G01X1535000Y343750D02*
Y342200D01*
X1536100Y341100D01*
Y339000D01*
G01X1552000Y325900D02*
Y327513D01*
X1549900Y329613D01*
Y332438D01*
X1548515Y333823D01*
X1547398D01*
G01X1547651Y339746D02*
Y341751D01*
X1548100Y342200D01*
G01X1560024Y329200D02*
X1560923Y328301D01*
X1563902D01*
X1564831Y329230D01*
Y331926D01*
G01X1560565Y357023D02*
X1569413Y348175D01*
X1572655D01*
X1577048Y343782D01*
X1583491D01*
X1594006Y333267D01*
Y320427D01*
X1590667Y317088D01*
X1589523D01*
X1588549Y316114D01*
Y314970D01*
X1585300Y311721D01*
Y302701D01*
X1586385Y301616D01*
G01X1636684Y279815D02*
X1634815D01*
X1630303Y275303D01*
X1606856D01*
X1587400Y294759D01*
Y300601D01*
X1586385Y301616D01*
G01X1561163Y367021D02*
X1561353Y366831D01*
Y359065D01*
X1570619Y349799D01*
X1572442D01*
X1577634Y344607D01*
X1589545D01*
X1594831Y339321D01*
Y320085D01*
X1592146Y317400D01*
Y314720D01*
X1589517Y312091D01*
X1588322D01*
X1586125Y309894D01*
Y307475D01*
X1588600Y305000D01*
Y294726D01*
X1607198Y276128D01*
X1629720D01*
X1635070Y281478D01*
X1643320D01*
G01X1545500Y343750D02*
X1543957Y342207D01*
Y340823D01*
G01X1553825Y377514D02*
X1551875Y378420D01*
G01X1557360Y357190D02*
X1566850Y347700D01*
Y344350D01*
G01X1551875Y391940D02*
X1552944Y391444D01*
X1553300Y391278D01*
X1553825Y391034D01*
G01X1567475Y378420D02*
X1569584Y378002D01*
G01X1561625Y395320D02*
X1563575Y394414D01*
G01X1557725Y397794D02*
X1555775Y398700D01*
G01X1569425Y388560D02*
X1571375Y387654D01*
G01X1594750Y402000D02*
X1593330D01*
X1590563Y399233D01*
X1589502D01*
X1587683Y397414D01*
G01X1569425Y397794D02*
X1567475Y398700D01*
G01X1550500Y347250D02*
X1551434Y348184D01*
Y349405D01*
X1550639Y350200D01*
G01D02*
Y359958D01*
X1551964Y361283D01*
G01X1561625Y402080D02*
X1562960Y401460D01*
X1563575Y401174D01*
G01X1567475Y391940D02*
X1569425Y391034D01*
G01X1553825Y397794D02*
X1551875Y398700D01*
G01X1528475Y385180D02*
X1530425Y384274D01*
G01X1540175Y378420D02*
X1542300Y376717D01*
G01X1544075Y398700D02*
X1545000Y398270D01*
X1546025Y397794D01*
G01X1549925Y395320D02*
X1551875Y394414D01*
G01X1549925Y388560D02*
X1551875Y387654D01*
G01X1582903Y394591D02*
X1594014D01*
X1594451Y395028D01*
G01X1594201Y387566D02*
X1589134D01*
X1584270Y392430D01*
X1582382D01*
G01X1563575Y385180D02*
X1565525Y384274D01*
G01X1560500Y343750D02*
X1563650D01*
X1564200Y344300D01*
Y349099D01*
X1556350Y356949D01*
G01X1557725Y377514D02*
X1555775Y378420D01*
G01X1546406Y362312D02*
X1544907Y360813D01*
Y360234D01*
X1544539Y359866D01*
Y354655D01*
X1544014Y354130D01*
X1542622D01*
X1541921Y353429D01*
Y351896D01*
X1540980Y350955D01*
G01D02*
X1540254Y350229D01*
Y344745D01*
X1541249Y343750D01*
X1542500D01*
G01X1597800Y408400D02*
X1595600D01*
X1593200Y406000D01*
X1588327D01*
X1586302Y403975D01*
G01X1569425Y381800D02*
X1571585Y382230D01*
G01X1557500Y350500D02*
Y351001D01*
X1555577Y352924D01*
Y355142D01*
G01X1557500Y350500D02*
Y349400D01*
X1556500Y348400D01*
Y347250D01*
G01X1552400Y350500D02*
Y353400D01*
X1554069Y355069D01*
G01X1553500Y347250D02*
Y347647D01*
X1552400Y348747D01*
Y350500D01*
G01X1557725Y402080D02*
X1559675Y401174D01*
G01X1576500Y341400D02*
X1570550Y347350D01*
X1568859D01*
X1558477Y357732D01*
G01X1542125Y397794D02*
X1540175Y398700D01*
G01X1590581Y404170D02*
Y403058D01*
X1589586Y402063D01*
G01X1567475Y385180D02*
X1570289Y384368D01*
G01X1563575Y391940D02*
X1565192Y391189D01*
X1565525Y391034D01*
G01X1546025Y395320D02*
X1547975Y394414D01*
G01X1538225Y388560D02*
X1540175Y387654D01*
G01X1538225Y381800D02*
X1540175Y380894D01*
G01X1538225Y402080D02*
X1540175Y401174D01*
G01X1542932Y355740D02*
X1542834D01*
Y356516D01*
X1541750Y357600D01*
X1537693D01*
X1536593Y358700D01*
Y368863D01*
X1536080Y369376D01*
Y370475D01*
X1537343Y371738D01*
Y373189D01*
G01X1546025Y388560D02*
X1547975Y387654D01*
G01X1534325Y402080D02*
X1534400Y402045D01*
X1536275Y401174D01*
G01X1534325Y388560D02*
X1534400Y388525D01*
X1536275Y387654D01*
G01X1530425Y377514D02*
X1528475Y378420D01*
G01X1534325Y384274D02*
X1532375Y385180D01*
G01X1534325Y381800D02*
X1534400Y381765D01*
X1536275Y380894D01*
G01X1534325Y397794D02*
X1532375Y398700D01*
G01X1538225Y395320D02*
X1540175Y394414D01*
G01X1532375Y391940D02*
X1534325Y391034D01*
G01X1557725Y388560D02*
X1559675Y387654D01*
G01X1557725Y395320D02*
X1559626Y394437D01*
X1559675Y394414D01*
G01X1549925Y381800D02*
X1551875Y380894D01*
G01X1528475Y391940D02*
X1530425Y391034D01*
G01X1555775Y391940D02*
X1557725Y391034D01*
G01X1548343Y344926D02*
Y342443D01*
X1548100Y342200D01*
G01X1534325Y395320D02*
X1534400Y395285D01*
X1536275Y394414D01*
G01X1528042Y356063D02*
Y353342D01*
X1529869Y351515D01*
Y349163D01*
X1529000Y348294D01*
Y347250D01*
G01X1531852Y360960D02*
X1530760Y359868D01*
Y355691D01*
X1535557Y350894D01*
G01D02*
X1538000Y348451D01*
Y347250D01*
G01X1531177Y361628D02*
X1529857Y360308D01*
Y354996D01*
X1533993Y350860D01*
Y350010D01*
X1535000Y349003D01*
Y347250D01*
G01X1561625Y388560D02*
X1563575Y387654D01*
G01X1565525Y402080D02*
X1567475Y401174D01*
G01X1649692Y288502D02*
X1645994Y284804D01*
X1631018D01*
X1627702Y281488D01*
X1604441D01*
X1590300Y295629D01*
Y309740D01*
X1593796Y313236D01*
Y316716D01*
X1596481Y319401D01*
Y340005D01*
X1590229Y346257D01*
X1578318D01*
X1569049Y355526D01*
X1569048D01*
X1568224Y356350D01*
X1568223D01*
X1566499Y358074D01*
X1566257D01*
X1564735Y359596D01*
Y360626D01*
G01X1569395Y361101D02*
X1569707Y360789D01*
Y358540D01*
X1572721Y355526D01*
X1572722D01*
X1580341Y347907D01*
X1590913D01*
X1598131Y340689D01*
Y318717D01*
X1595726Y316312D01*
Y312424D01*
X1591950Y308648D01*
Y296313D01*
X1604963Y283300D01*
X1627180D01*
X1631691Y287811D01*
X1636655D01*
X1636800Y287956D01*
G01X1564925Y363696D02*
Y363141D01*
X1566553Y361513D01*
X1567362D01*
X1568726Y360149D01*
Y357911D01*
X1579555Y347082D01*
X1590571D01*
X1597306Y340347D01*
Y319059D01*
X1594621Y316374D01*
Y312652D01*
X1591125Y309156D01*
Y295971D01*
X1604783Y282313D01*
X1627360D01*
X1630677Y285630D01*
X1631359D01*
X1631360Y285629D01*
X1631538D01*
X1631539Y285630D01*
X1632221D01*
X1632222Y285629D01*
X1638530D01*
X1641594Y288693D01*
G01X1636861Y305091D02*
X1635061Y306891D01*
Y311369D01*
X1622081Y324349D01*
X1620489D01*
X1614424Y330414D01*
Y350343D01*
X1612485Y352282D01*
X1606965D01*
X1590815Y368432D01*
Y377785D01*
X1583984Y384616D01*
G01X1636922Y302588D02*
X1634236Y305274D01*
Y311027D01*
X1621739Y323524D01*
X1620147D01*
X1613599Y330072D01*
Y350001D01*
X1612143Y351457D01*
X1606623D01*
X1589990Y368090D01*
Y377210D01*
X1585101Y382099D01*
G01X1576634Y389193D02*
Y387072D01*
X1577745Y385961D01*
X1578791D01*
X1579249Y386419D01*
X1580568D01*
X1581268Y385719D01*
X1584180D01*
X1591640Y378259D01*
Y368774D01*
X1606986Y353428D01*
X1612506D01*
X1615249Y350685D01*
Y330756D01*
X1620831Y325174D01*
X1622423D01*
X1635886Y311711D01*
Y309914D01*
X1640025Y305775D01*
X1643675D01*
X1647050Y302400D01*
X1654900D01*
G01X1584409Y386690D02*
X1592500Y378599D01*
Y369699D01*
X1592519Y369680D01*
Y369062D01*
X1603061Y358520D01*
X1607610D01*
X1609160Y360070D01*
X1613930D01*
X1616074Y357926D01*
Y331098D01*
X1621173Y325999D01*
X1622765D01*
X1636711Y312053D01*
Y310288D01*
X1640399Y306600D01*
X1647900D01*
G01X1564003Y362600D02*
X1566922Y359681D01*
G01X1636822Y294946D02*
X1633654D01*
X1629150Y299450D01*
Y309850D01*
X1619500Y319500D01*
X1618000D01*
X1609500Y328000D01*
Y329500D01*
X1603725Y335275D01*
Y346127D01*
X1589789Y360063D01*
X1585985D01*
X1584107Y361941D01*
Y371593D01*
X1583400Y372300D01*
G01X1583276Y376206D02*
X1586215Y373267D01*
Y366524D01*
X1605150Y347589D01*
Y335350D01*
X1610500Y330000D01*
Y328500D01*
X1618500Y320500D01*
X1620000D01*
X1630700Y309800D01*
Y300400D01*
X1633656Y297444D01*
X1636925D01*
G01X1824300Y251800D02*
Y253941D01*
X1822558Y255683D01*
X1678916D01*
X1670675Y263924D01*
Y284463D01*
X1658908Y296230D01*
X1658142D01*
X1658141Y296229D01*
X1645868D01*
X1639293Y289654D01*
X1632079D01*
X1626650Y284225D01*
X1605496D01*
X1593375Y296346D01*
Y308733D01*
X1596871Y312229D01*
Y316148D01*
X1599056Y318333D01*
Y341780D01*
X1591504Y349332D01*
X1581552D01*
X1574200Y356684D01*
Y361365D01*
G01X1575790Y361260D02*
X1578040D01*
X1579400Y359900D01*
Y357375D01*
X1583921Y352854D01*
X1591482D01*
X1600188Y344148D01*
Y317988D01*
X1598296Y316096D01*
Y311637D01*
X1594800Y308141D01*
Y296615D01*
X1605972Y285443D01*
X1622352D01*
X1627583Y290674D01*
X1639004D01*
X1645484Y297154D01*
X1657757D01*
X1657758Y297155D01*
X1658524D01*
X1658525Y297156D01*
X1659291D01*
X1671600Y284847D01*
Y264308D01*
X1679300Y256608D01*
X1823395D01*
X1826287Y253716D01*
Y250000D01*
G01X1822638Y232106D02*
X1823581D01*
X1825416Y233941D01*
X1826344D01*
X1830103Y237700D01*
X1832300D01*
X1834400Y239800D01*
Y253218D01*
X1829948Y257670D01*
X1679547D01*
X1672525Y264692D01*
Y285231D01*
X1658604Y299152D01*
X1634248D01*
X1632125Y301275D01*
Y310269D01*
X1620894Y321500D01*
X1619000D01*
X1611500Y329000D01*
Y330999D01*
X1606575Y335924D01*
Y347473D01*
X1587140Y366908D01*
Y375988D01*
X1584876Y378252D01*
G01X1826662Y232191D02*
X1830471Y236000D01*
X1832616D01*
X1835825Y239209D01*
Y253809D01*
X1831039Y258595D01*
X1679931D01*
X1673450Y265076D01*
Y285615D01*
X1658988Y300077D01*
X1634762D01*
X1633311Y301528D01*
Y310643D01*
X1621454Y322500D01*
X1619500D01*
X1612500Y329500D01*
Y349084D01*
X1611552Y350032D01*
X1606032D01*
X1588565Y367499D01*
Y377052D01*
X1584712Y380905D01*
G01X1549925Y402080D02*
X1551875Y401174D01*
G01X1563575Y398700D02*
X1565192Y397949D01*
X1565525Y397794D01*
G01X1636684Y283141D02*
X1630522D01*
X1624881Y277500D01*
X1606993D01*
X1589463Y295030D01*
Y310338D01*
X1592971Y313846D01*
Y317058D01*
X1595656Y319743D01*
Y339663D01*
X1589887Y345432D01*
X1577976D01*
X1572259Y351149D01*
X1570850D01*
X1563240Y358759D01*
Y360670D01*
X1562266Y361644D01*
Y363959D01*
G01X1580049Y368496D02*
Y362499D01*
X1585811Y356737D01*
X1590531D01*
X1602300Y344968D01*
Y334132D01*
X1604439Y331993D01*
Y324600D01*
G01X1614400Y367400D02*
X1614139D01*
X1612146Y365407D01*
X1609785D01*
X1607761Y363383D01*
X1606381D01*
X1605316Y362318D01*
X1600430D01*
X1593344Y369404D01*
Y378956D01*
X1584676Y387624D01*
X1581876D01*
X1580307Y389193D01*
X1579902D01*
G01X1563575Y378420D02*
X1565192Y377669D01*
X1565525Y377514D01*
G01X1557725Y381800D02*
X1559675Y380894D01*
G01X1569425Y395320D02*
X1571375Y394414D01*
G01X1545500Y343750D02*
X1546000D01*
X1547300Y345050D01*
Y350658D01*
G01D02*
Y352975D01*
X1547872Y353547D01*
G01X1563575Y380894D02*
X1562669Y381800D01*
X1561625D01*
G01X1592808Y403018D02*
X1593990Y404200D01*
X1601800D01*
X1604563Y401437D01*
X1611500D01*
G01X1532375Y378420D02*
X1534325Y377514D01*
G01X1583804Y454935D02*
X1588541D01*
X1589106Y455500D01*
X1590500D01*
G01X1540175Y459540D02*
X1542125Y460446D01*
G01X1536275Y459540D02*
X1538225Y460446D01*
G01X1589292Y428180D02*
X1590571D01*
X1591140Y427611D01*
X1595729D01*
X1600641Y432523D01*
X1603050D01*
G01X1612250Y435500D02*
X1610530Y437220D01*
X1602368D01*
X1601337Y436189D01*
Y435837D01*
X1596000Y430500D01*
X1589386D01*
X1588800Y429914D01*
X1588099D01*
G01X1567475Y452780D02*
X1569425Y453686D01*
G01X1599320Y441900D02*
X1598112D01*
X1592780Y436568D01*
X1587942D01*
G01X1579902Y452185D02*
X1583208D01*
G01X1559675Y405460D02*
Y407934D01*
G01X1578268Y426594D02*
X1581939D01*
G01X1559675Y446020D02*
X1561625Y446926D01*
G01X1590817Y411114D02*
X1591262D01*
X1594551Y414403D01*
X1595929D01*
X1596446Y413886D01*
X1602881D01*
X1602961Y413806D01*
X1604339D01*
X1604419Y413886D01*
X1608165D01*
X1608963Y413088D01*
Y412787D01*
X1609750Y412000D01*
G01X1579902Y420689D02*
X1580289Y421076D01*
X1585312D01*
X1585560Y421324D01*
G01X1532825Y415175D02*
X1534400Y413600D01*
Y413500D01*
G01X1585394Y414937D02*
X1585776Y415319D01*
X1590819D01*
X1593361Y417861D01*
X1609139D01*
X1609750Y417250D01*
Y416000D01*
G01X1585480Y417348D02*
X1589142D01*
X1592642Y420848D01*
X1612952D01*
X1613300Y420500D01*
X1613400D01*
G01X1584706Y415675D02*
X1585354Y416323D01*
X1589909D01*
X1593186Y419600D01*
X1610400D01*
X1611800Y418200D01*
X1614900D01*
X1615537Y418837D01*
X1617347D01*
G01X1602520Y425800D02*
X1601001D01*
X1598901Y423700D01*
X1592200D01*
X1590698Y422198D01*
G01X1589184Y422545D02*
X1591400Y424761D01*
X1597400D01*
G01X1542125Y462920D02*
X1544075Y463826D01*
G01X1587324Y429036D02*
X1595845D01*
X1602262Y435453D01*
Y435500D01*
X1603000D01*
G01X1535975Y415175D02*
X1537550Y413600D01*
G01X1578268Y458091D02*
X1578591D01*
X1579200Y458700D01*
X1583414D01*
X1583957Y458157D01*
X1591828D01*
X1592707Y457278D01*
X1602741D01*
X1605306Y459843D01*
X1606791D01*
G01X1557725Y408840D02*
X1555775Y407934D01*
G01Y412220D02*
Y414694D01*
G01X1567475Y418980D02*
X1567300Y418899D01*
X1565525Y418074D01*
G01X1563575Y418980D02*
X1563404Y418900D01*
X1561625Y418074D01*
G01X1563575Y412220D02*
X1561625Y411314D01*
G01X1565525D02*
X1567475Y412220D01*
G01X1559675Y439260D02*
X1561625Y440166D01*
G01X1555775Y439260D02*
X1556000Y439365D01*
X1557725Y440166D01*
G01X1563575Y425740D02*
X1564091Y425500D01*
X1565192Y424989D01*
X1565525Y424834D01*
G01X1567475Y425740D02*
X1567991Y425500D01*
X1569425Y424834D01*
G01X1545425Y434075D02*
X1547000Y435650D01*
G01X1539125Y434075D02*
X1540700Y435650D01*
G01X1539125Y437225D02*
X1540700Y438800D01*
G01X1537550D02*
X1535975Y437225D01*
G01X1532825Y446675D02*
X1534400Y448250D01*
G01X1535975Y443525D02*
X1537550Y445100D01*
G01X1529675Y443525D02*
X1531250Y445100D01*
G01X1534400D02*
X1532825Y443525D01*
G01X1540700Y448250D02*
X1539125Y446675D01*
G01X1531250Y448250D02*
X1529675Y446675D01*
G01X1594108Y442158D02*
X1597575Y445625D01*
X1599925D01*
X1600400Y446100D01*
G01X1597800Y412000D02*
X1592800Y407000D01*
X1587954D01*
X1585674Y404720D01*
G01X1579902Y416752D02*
X1583208D01*
G01X1579902Y432500D02*
X1580262Y432860D01*
X1585232D01*
X1586572Y434200D01*
X1586599D01*
X1586627Y434228D01*
X1596238D01*
X1597930Y435920D01*
X1598130D01*
G01X1559675Y452780D02*
Y450875D01*
X1559600Y450800D01*
Y450631D01*
X1559595D01*
G01X1567475Y446020D02*
X1568298Y446402D01*
X1569425Y446926D01*
G01X1579902Y404941D02*
X1583208D01*
G01X1563575Y452780D02*
X1564844Y453370D01*
X1565192Y453531D01*
X1565525Y453686D01*
G01X1588066Y454000D02*
X1588241Y453825D01*
X1597245D01*
X1598229Y454809D01*
X1605669D01*
G01X1569425Y435880D02*
X1571375Y436786D01*
G01X1585598Y448248D02*
X1586255Y448905D01*
X1590933D01*
X1594528Y452500D01*
X1598000D01*
X1599023Y453523D01*
X1604018D01*
X1604445Y453096D01*
X1613796D01*
X1619400Y458700D01*
X1628867D01*
X1629583Y459416D01*
X1634784D01*
X1639100Y455100D01*
X1639236D01*
X1639249Y455087D01*
X1640751D01*
X1640764Y455100D01*
X1643300D01*
G01X1567475Y463826D02*
X1565525Y462920D01*
G01X1584330Y445781D02*
X1586371Y447822D01*
X1591528D01*
X1595187Y451481D01*
X1602329D01*
X1602450Y451360D01*
G01X1551875Y459540D02*
X1553825Y460446D01*
G01X1567475Y443546D02*
X1565525Y442640D01*
G01X1594580Y448580D02*
X1597147D01*
X1597885Y449318D01*
G01X1569425Y442640D02*
X1571375Y443546D01*
G01X1590208Y427243D02*
X1590665Y426786D01*
X1596360D01*
X1599194Y429620D01*
G01X1585800Y434600D02*
X1586338Y435138D01*
X1593484D01*
X1597346Y439000D01*
X1610552D01*
X1611640Y440088D01*
X1612256D01*
G01X1561625Y449400D02*
X1562894Y449990D01*
X1563575Y450306D01*
G01X1565525Y435880D02*
X1567475Y436786D01*
G01X1575000Y442343D02*
X1576482D01*
X1577745Y441080D01*
X1578813D01*
X1579270Y441537D01*
X1585841D01*
X1587864Y443560D01*
X1593570D01*
X1596560Y446550D01*
X1598498D01*
X1599711Y447763D01*
X1612937D01*
X1615100Y445600D01*
X1620652D01*
X1621226Y445026D01*
G01X1555775Y405460D02*
X1557725Y404554D01*
G01X1591841Y421531D02*
X1592810Y422500D01*
X1602001D01*
X1602472Y422971D01*
X1603000D01*
G01X1567475Y439260D02*
X1569425Y440166D01*
G01X1578268Y446280D02*
X1582120D01*
X1582300Y446100D01*
G01X1557725Y456160D02*
X1559675Y457066D01*
G01X1544075Y459540D02*
X1546025Y460446D01*
G01X1595200Y412700D02*
Y410937D01*
X1592096Y407833D01*
X1590764D01*
X1590752Y407845D01*
X1587389D01*
X1586068Y406524D01*
X1583945D01*
G01X1555775Y459540D02*
X1557725Y460446D01*
G01X1605260Y442230D02*
X1602140D01*
X1600083Y444287D01*
X1598437D01*
X1592162Y438012D01*
X1584628D01*
G01X1557725Y469680D02*
X1559675Y470586D01*
G01X1555775Y466300D02*
X1556000Y466405D01*
X1557712Y467200D01*
X1557725Y467206D01*
G01X1566870Y493445D02*
Y494966D01*
X1565700Y496136D01*
Y497382D01*
X1566207Y497889D01*
Y500631D01*
X1566948Y501372D01*
X1569460D01*
X1570932Y499900D01*
X1581570D01*
X1587970Y493500D01*
X1589399D01*
X1590100Y492799D01*
Y491500D01*
G01X1540175Y466300D02*
X1542112Y467200D01*
X1542125Y467206D01*
G01X1530425Y476440D02*
X1532375Y477346D01*
G01X1538225Y469680D02*
X1538483Y469800D01*
X1540175Y470586D01*
G01X1563575Y466300D02*
X1563622Y466322D01*
X1564844Y466890D01*
X1565192Y467051D01*
X1565525Y467206D01*
G01X1559675Y466300D02*
X1561625Y467206D01*
G01X1567475Y466300D02*
X1569425Y467206D01*
G01X1561625Y469680D02*
X1563575Y470586D01*
G01X1559675Y473060D02*
X1561625Y473966D01*
G01X1563575Y473060D02*
X1564844Y473650D01*
X1565192Y473811D01*
X1565525Y473966D01*
G01Y476440D02*
X1567475Y477346D01*
G01X1560562Y595850D02*
Y588364D01*
X1557361Y585163D01*
X1552415D01*
X1550990Y586588D01*
G01X1554358Y587258D02*
X1555394Y586222D01*
X1556788D01*
X1558987Y588421D01*
Y595850D01*
G01X1568212Y590831D02*
X1566631D01*
X1565500Y589700D01*
Y588300D01*
X1564000Y586800D01*
X1562500D01*
G01X1563712Y590349D02*
Y588912D01*
X1562500Y587700D01*
Y586800D01*
G01Y583300D02*
X1564300D01*
X1565389Y584389D01*
Y585721D01*
G01X1548550Y611012D02*
X1547188D01*
X1545613Y612587D01*
X1541813D01*
X1540700Y613700D01*
G01X1568212Y590831D02*
X1571324D01*
X1571493Y591000D01*
G01X1563712Y590349D02*
Y595850D01*
G01X1567850Y598413D02*
X1569386D01*
X1569799Y598000D01*
X1572495D01*
G01D02*
X1573900D01*
X1574560Y597340D01*
X1575790D01*
G01X1574500Y591000D02*
Y592400D01*
X1572950Y593950D01*
G01D02*
X1571050Y595850D01*
X1565287D01*
G01X1587490Y611299D02*
X1584971D01*
X1581522Y607850D01*
X1578800D01*
X1578010Y607060D01*
X1577000D01*
G01X1567850Y604713D02*
X1575653D01*
X1577000Y606060D01*
Y607060D01*
G01X1567850Y606287D02*
X1571377D01*
X1571383Y606293D01*
X1571416D01*
X1572213Y607090D01*
X1573520D01*
G01X1575790Y601040D02*
X1574526Y599776D01*
X1570200D01*
X1569987Y599989D01*
X1567851D01*
X1567850Y599988D01*
G01X1598602Y-600D02*
X1595602D01*
G01X1590431Y-6702D02*
X1592531D01*
G01X1595602Y-2569D02*
X1599133D01*
X1601102Y-600D01*
G01D02*
X1602100Y398D01*
Y5400D01*
X1601400Y6100D01*
X1596000D01*
X1595602Y5702D01*
Y3337D01*
G01X1592500Y-16100D02*
X1593758D01*
X1595004Y-17346D01*
G01X1598602Y3437D02*
Y2401D01*
X1597570Y1369D01*
X1595602D01*
G01X1592500Y-12600D02*
Y-9800D01*
X1595602Y-6698D01*
Y-4537D01*
G01X1605500Y-3600D02*
Y-11000D01*
X1603900Y-12600D01*
X1592500D01*
G01X1599000Y61500D02*
X1597425Y63075D01*
X1593200D01*
G01X1649900Y85250D02*
Y86600D01*
X1647588Y88912D01*
Y94322D01*
G01X1643662Y107617D02*
X1645088Y106191D01*
Y99141D01*
X1647588Y96641D01*
Y94322D01*
G01X1648276Y65221D02*
Y66573D01*
X1645837Y69012D01*
Y69963D01*
X1645500Y70300D01*
X1643900D01*
G01X1650876Y65237D02*
X1649300Y66813D01*
Y66950D01*
X1647500Y68750D01*
Y70300D01*
G01X1628500Y90000D02*
Y92000D01*
X1630000Y93500D01*
X1631006D01*
X1632006Y94500D01*
G01D02*
X1630405Y96101D01*
Y100237D01*
X1631064Y100896D01*
Y104467D01*
G01X1643900Y73800D02*
X1637989D01*
X1635815Y71626D01*
X1634874D01*
X1634663Y71837D01*
X1634648D01*
X1633674Y72811D01*
Y72826D01*
X1633663Y72837D01*
Y75236D01*
X1630411Y78488D01*
G01D02*
X1629500Y79399D01*
Y83500D01*
X1633874Y87874D01*
Y102732D01*
X1634213Y103071D01*
Y104467D01*
G01X1647500Y73800D02*
Y74590D01*
X1646426Y75664D01*
X1642694D01*
X1640607Y77751D01*
X1640578D01*
G01D02*
X1639292Y79037D01*
Y91149D01*
X1635960Y94481D01*
Y99013D01*
X1639148Y102201D01*
Y104270D01*
X1639149Y104271D01*
Y105202D01*
X1640512Y106565D01*
Y107617D01*
G01X1627498Y94000D02*
X1625500Y92002D01*
Y90250D01*
G01X1627498Y94000D02*
X1627040Y94458D01*
Y100080D01*
X1627914Y100954D01*
Y104467D01*
G01X1592500Y90500D02*
X1589500D01*
G01X1595500Y90750D02*
X1592750D01*
X1592500Y90500D01*
G01X1594480Y94610D02*
X1595500Y93590D01*
Y90750D01*
G01X1602000D02*
Y92130D01*
X1601067Y93063D01*
Y94620D01*
G01X1609016Y110766D02*
X1607345Y109095D01*
X1605362D01*
X1605347Y109080D01*
X1605261D01*
X1604349Y108168D01*
Y107180D01*
X1603269Y106100D01*
X1598913D01*
X1597867Y105054D01*
Y93900D01*
G01D02*
X1598849Y92918D01*
Y90788D01*
G01X1608750Y90500D02*
Y96250D01*
X1612166Y99666D01*
Y104467D01*
G01X1608750Y90500D02*
Y83898D01*
X1607419Y82567D01*
X1604067D01*
X1601150Y79650D01*
X1598137D01*
X1597987Y79500D01*
G01X1649900Y78600D02*
Y81750D01*
G01X1643478Y91473D02*
X1643629Y91322D01*
Y86808D01*
G01X1636500Y91000D02*
Y92651D01*
X1634977Y94174D01*
Y96860D01*
G01X1643629Y83308D02*
Y80529D01*
X1643500Y80400D01*
G01X1636500Y87500D02*
Y86124D01*
X1634000Y83624D01*
Y81000D01*
X1635302Y79698D01*
G01D02*
Y73535D01*
X1635337Y73500D01*
G01X1612166Y107617D02*
X1610750Y106201D01*
Y99792D01*
X1607958Y97000D01*
X1607075D01*
X1604000Y93925D01*
G01X1595500Y87250D02*
X1596900Y85850D01*
Y84500D01*
G01X1602000Y87250D02*
Y84500D01*
G01X1650800Y73800D02*
X1650700D01*
X1648625Y75875D01*
X1647552D01*
X1645578Y77849D01*
G01D02*
X1644745Y78682D01*
X1642808D01*
X1640391Y81099D01*
Y91501D01*
X1636785Y95107D01*
Y98671D01*
X1639973Y101859D01*
Y103928D01*
X1640512Y104467D01*
G01X1643662D02*
Y99353D01*
X1644824Y98191D01*
Y94108D01*
X1645475Y93457D01*
Y93447D01*
X1646000Y92922D01*
Y80487D01*
X1647991Y78496D01*
Y77775D01*
X1648866Y76900D01*
X1651000D01*
X1654100Y73800D01*
G01X1632000Y47500D02*
Y43360D01*
X1630386Y41746D01*
Y41448D01*
G01X1607051Y69691D02*
X1610941D01*
X1611311Y69321D01*
X1613650D01*
X1615115Y70786D01*
G01X1591600Y75700D02*
X1593599Y73701D01*
X1596189D01*
X1600199Y69691D01*
X1607051D01*
G01X1627489Y74960D02*
X1624655Y77794D01*
X1619139D01*
G01D02*
X1619124D01*
G01X1619139D02*
X1613334Y83599D01*
Y85216D01*
X1614366Y86248D01*
Y87329D01*
G01X1615316Y148562D02*
X1616891Y150137D01*
G01X1613741Y146987D02*
X1615316Y145412D01*
G01X1602717Y129664D02*
X1600286D01*
X1598150Y131800D01*
X1593420D01*
G01X1646812Y104467D02*
X1646113Y103768D01*
Y100116D01*
X1650931Y95298D01*
Y90182D01*
G01X1632574Y106107D02*
X1631064Y107617D01*
G01X1620100Y153300D02*
X1620026D01*
X1618465Y154861D01*
G01X1612166Y123365D02*
X1610591Y121790D01*
G01X1631064Y110766D02*
X1632615Y109215D01*
G01X1634213Y110766D02*
X1632638Y112341D01*
G01X1634213Y113916D02*
X1632638Y115491D01*
G01X1592816Y140550D02*
X1595150D01*
X1600799Y134901D01*
X1601655D01*
X1602717Y135963D01*
G01X1618465Y117066D02*
X1616848Y115449D01*
G01X1613741Y153286D02*
X1615316Y151711D01*
G01X1646812Y117066D02*
X1648387Y115491D01*
G01X1649961Y117066D02*
X1651536Y115491D01*
G01X1612166Y113916D02*
X1610591Y112341D01*
G01X1602717Y107617D02*
X1598666D01*
X1593675Y102626D01*
Y95415D01*
X1594480Y94610D01*
G01X1591460Y104110D02*
Y105020D01*
X1592080Y105640D01*
X1595339D01*
X1598779Y109080D01*
X1603230D01*
X1604916Y110766D01*
X1605867D01*
G01X1601067Y94620D02*
Y96818D01*
X1605867Y101618D01*
Y104467D01*
G01X1609016Y117066D02*
X1607441Y115491D01*
G01X1602717Y110766D02*
X1600490D01*
G01X1612166Y120215D02*
X1610591Y118640D01*
G01X1609016Y113916D02*
X1607441Y112341D01*
G01X1618465Y129664D02*
Y129663D01*
X1616891Y128089D01*
G01X1592800Y115710D02*
X1594890D01*
X1596300Y114300D01*
X1599951D01*
X1602717Y117066D01*
G01X1615316Y120215D02*
X1613741Y118640D01*
G01X1609016Y145412D02*
X1610645Y143783D01*
G01X1600148Y142262D02*
X1602717D01*
G01X1605867Y148562D02*
X1604292Y150137D01*
G01X1607401Y146947D02*
X1609016Y148562D01*
G01X1600182D02*
X1602717D01*
G01X1600148Y151711D02*
X1602717D01*
G01X1605867Y154861D02*
X1605715D01*
X1604169Y156407D01*
G01X1612166Y154861D02*
X1610591Y153286D01*
G01X1609016Y154861D02*
X1607441Y156436D01*
G01X1591950Y158250D02*
X1595339Y154861D01*
X1602717D01*
G01X1615316Y110766D02*
X1613741Y109191D01*
G01X1616900Y143880D02*
X1615316Y142296D01*
Y142262D01*
G01X1654406Y94104D02*
Y96471D01*
X1648175Y102702D01*
Y106254D01*
X1646812Y107617D01*
G01X1634977Y96860D02*
Y101944D01*
X1636000Y102967D01*
Y105830D01*
X1634213Y107617D01*
G01X1643662Y117066D02*
X1645237Y115491D01*
G01X1648000Y100597D02*
X1652051Y96546D01*
Y92579D01*
X1653763Y90867D01*
Y88185D01*
X1655948Y86000D01*
X1656500D01*
G01X1640512Y113916D02*
X1641770Y112658D01*
Y112340D01*
G01X1609016Y132814D02*
X1607441Y134389D01*
G01X1612166Y139113D02*
X1610591Y140688D01*
G01X1612166Y135963D02*
X1610591Y137538D01*
G01X1612166Y148562D02*
X1610591Y150137D01*
G01X1615316Y135963D02*
X1613741Y137538D01*
G01X1594452Y111377D02*
X1596224D01*
X1597265Y112418D01*
X1604369D01*
X1605867Y113916D01*
G01X1609016Y151711D02*
X1607441Y153286D01*
G01X1605867Y132814D02*
X1604388Y131335D01*
X1601465D01*
X1600900Y131900D01*
G01X1605867Y151711D02*
X1604024Y153554D01*
X1603337D01*
X1603281Y153498D01*
X1602153D01*
X1602097Y153554D01*
X1593353D01*
X1592263Y152464D01*
X1590569D01*
G01X1656600Y73614D02*
Y74660D01*
X1659809Y77869D01*
Y83957D01*
X1660813Y84961D01*
Y89747D01*
X1656519Y94041D01*
Y95525D01*
X1649961Y102083D01*
Y104467D01*
G01X1659100Y73614D02*
X1660900Y75414D01*
Y83739D01*
X1661738Y84577D01*
Y90131D01*
X1658371Y93498D01*
X1658370D01*
X1657425Y94443D01*
Y95786D01*
X1651598Y101613D01*
Y102867D01*
X1651599Y102868D01*
Y105979D01*
X1649961Y107617D01*
G01X1612166Y132814D02*
X1610591Y134389D01*
G01X1613690Y124990D02*
X1612166Y126514D01*
G01X1615316Y132814D02*
X1613741Y134389D01*
G01X1608000Y99400D02*
X1609016Y100416D01*
Y104467D01*
G01Y142262D02*
X1607441Y143837D01*
G01X1610591Y146987D02*
X1612166Y145412D01*
G01X1643662Y113916D02*
X1645237Y112341D01*
G01X1609016Y107617D02*
X1607441Y106042D01*
G01X1612166Y151711D02*
X1612167D01*
X1613741Y150137D01*
G01Y156436D02*
X1615316Y154861D01*
G01Y129664D02*
X1613741Y128089D01*
G01X1624764Y117066D02*
X1626339Y118641D01*
Y118651D01*
G01X1624764Y110766D02*
X1626339Y109191D01*
G01X1624764Y113916D02*
Y113836D01*
X1626300Y112300D01*
G01X1649961Y113916D02*
X1651536Y112341D01*
G01X1621615Y154861D02*
Y154685D01*
X1623200Y153100D01*
G01X1592617Y122435D02*
X1593082Y122900D01*
X1601255D01*
X1602153Y122002D01*
X1604504D01*
X1605867Y123365D01*
G01X1615316Y113916D02*
X1613741Y112341D01*
G01X1627914Y107617D02*
X1629400Y106131D01*
G01X1627914Y110766D02*
X1629400Y109280D01*
X1629487D01*
G01X1640512Y117066D02*
X1642084Y115494D01*
G01X1627914Y113916D02*
X1629489Y112341D01*
G01X1646812Y113916D02*
X1648387Y112341D01*
G01X1646812Y110766D02*
X1648387Y109191D01*
G01X1649961Y110766D02*
X1651536Y109191D01*
G01X1609016Y135963D02*
X1607441Y137538D01*
G01X1605867Y135963D02*
X1604292Y134388D01*
G01X1609016Y129664D02*
X1610591Y128089D01*
G01X1612166Y117066D02*
X1610591Y115491D01*
G01X1643662Y110766D02*
X1645237Y109191D01*
G01X1601142Y172185D02*
Y172184D01*
X1602717Y170609D01*
G01X1647852Y192729D02*
Y197374D01*
G01X1609016Y158010D02*
Y158011D01*
X1607442Y159585D01*
G01X1615316Y161160D02*
X1613741Y162735D01*
G01X1609016Y161160D02*
X1607441Y162735D01*
G01X1646812Y170609D02*
Y172060D01*
X1646808Y172064D01*
Y173316D01*
X1646812Y173320D01*
Y173712D01*
X1651000Y177900D01*
Y178628D01*
G01X1646812Y167459D02*
X1645237Y165884D01*
G01X1627914Y161160D02*
X1626339Y162735D01*
G01X1624764Y164310D02*
X1623276Y165798D01*
G01X1600490Y167459D02*
X1602717D01*
G01X1646812Y158010D02*
X1648387Y159585D01*
G01X1631064Y161160D02*
X1629489Y162735D01*
G01X1624966Y172936D02*
Y170811D01*
X1624764Y170609D01*
G01X1621942Y173237D02*
X1622265Y172914D01*
Y171259D01*
X1621615Y170609D01*
G01X1624972Y189256D02*
X1625871Y188357D01*
Y186510D01*
X1627326Y185055D01*
Y182759D01*
G01X1649961Y158010D02*
X1651536Y159585D01*
G01X1631064Y164310D02*
X1631063D01*
X1629489Y165884D01*
G01X1643662Y161160D02*
X1645151Y162649D01*
G01X1640512Y161160D02*
X1642101Y162749D01*
G01X1613053Y184949D02*
X1609934Y188068D01*
Y188291D01*
G01X1606934D02*
Y187661D01*
X1608033Y186562D01*
X1608869D01*
X1610554Y184877D01*
G01X1612166Y161160D02*
X1610591Y159585D01*
G01X1595800Y180300D02*
Y179022D01*
X1597822Y177000D01*
X1600001D01*
X1604277Y172724D01*
Y169927D01*
X1605215Y168989D01*
X1606584D01*
X1607381Y168192D01*
Y165945D01*
X1609016Y164310D01*
G01X1596427Y157975D02*
X1598206Y159754D01*
X1604123D01*
X1605867Y158010D01*
G01X1600490D02*
X1602717D01*
G01X1612166D02*
X1612165D01*
X1610591Y156436D01*
G01X1615553Y184908D02*
X1615487D01*
Y184997D01*
X1612934Y187550D01*
Y188291D01*
G01X1598750Y197000D02*
X1596386D01*
X1595629Y197757D01*
X1592074D01*
X1590991Y198840D01*
Y202378D01*
G01D02*
Y205477D01*
X1592514Y207000D01*
X1599200D01*
G01X1596000Y184350D02*
X1599000D01*
G01X1598950Y180300D02*
Y181913D01*
X1599000Y181963D01*
Y184350D01*
G01X1605867Y170609D02*
X1605719Y170757D01*
Y172732D01*
X1602185Y176266D01*
Y180709D01*
G01X1597642Y172184D02*
X1600712Y169114D01*
X1603188D01*
X1604843Y167459D01*
X1605867D01*
G01X1637363Y158010D02*
X1638938Y159585D01*
G01X1637363Y161160D02*
X1638938Y162735D01*
G01X1635788Y165885D02*
X1637363Y164310D01*
G01X1643662D02*
X1642088Y165885D01*
G01X1640512Y164310D02*
X1638938Y165884D01*
G01X1618465Y170609D02*
Y174336D01*
X1616286Y176515D01*
G01X1615900Y172800D02*
X1616970Y171730D01*
Y168954D01*
X1618465Y167459D01*
G01X1609016Y170609D02*
Y170995D01*
X1607552Y172459D01*
Y175658D01*
X1606879Y176331D01*
Y183115D01*
X1606390Y183604D01*
Y184861D01*
X1603934Y187317D01*
Y188541D01*
G01X1621615Y164310D02*
Y164311D01*
X1620041Y165885D01*
G01X1609222Y173389D02*
Y172472D01*
X1610320Y171374D01*
X1612166Y170609D01*
G01X1613650Y173750D02*
Y172275D01*
X1615316Y170609D01*
G01X1631064Y158010D02*
X1629489Y159585D01*
G01X1634213Y158010D02*
X1635788Y159585D01*
G01X1649961Y161160D02*
X1651536Y162735D01*
G01X1644290Y196383D02*
Y195495D01*
X1645136Y194649D01*
Y193307D01*
X1645220Y193223D01*
Y188598D01*
X1647130Y186688D01*
Y183877D01*
X1646530Y183277D01*
Y180158D01*
X1641336Y174964D01*
Y171712D01*
X1641875Y171173D01*
Y170045D01*
X1641090Y169260D01*
Y168037D01*
X1640512Y167459D01*
G01Y170609D02*
Y175495D01*
X1645599Y180582D01*
Y184301D01*
X1646236Y184938D01*
Y186269D01*
X1644395Y188110D01*
Y192881D01*
X1642318Y194958D01*
Y197488D01*
X1644330Y199500D01*
X1649509D01*
X1652927Y202918D01*
X1658311D01*
X1660440Y200789D01*
G01X1640512Y158010D02*
X1642087Y159585D01*
G01X1614250Y197000D02*
Y209500D01*
X1616750Y212000D01*
X1620800D01*
G01X1637441Y224000D02*
Y213140D01*
X1632500Y208199D01*
Y200051D01*
X1634069Y198482D01*
Y197454D01*
G01X1632128Y225472D02*
X1631347Y224691D01*
Y216141D01*
X1630154Y214948D01*
G01X1634882Y217000D02*
Y214334D01*
X1631996Y211448D01*
X1630154D01*
G01D02*
Y208148D01*
G01X1599200Y212000D02*
Y214150D01*
X1599650Y214600D01*
X1603115D01*
X1612202Y223687D01*
X1613837D01*
X1615064Y222460D01*
G01X1599200Y217000D02*
X1603987D01*
X1610819Y223832D01*
X1610820D01*
G01X1592450Y168710D02*
X1593218Y167942D01*
Y166058D01*
X1594966Y164310D01*
X1602717D01*
G01X1620040Y159585D02*
X1621615Y158010D01*
G01X1609016Y167459D02*
Y168540D01*
X1607330Y170226D01*
Y171223D01*
X1606550Y172003D01*
Y173732D01*
X1605500Y174782D01*
Y181506D01*
X1604766Y182240D01*
G01D02*
X1603160D01*
X1601110Y184290D01*
Y186681D01*
X1599941Y187850D01*
X1599000D01*
G01X1639378Y202515D02*
Y200544D01*
X1639583Y200339D01*
Y199922D01*
X1640824Y198681D01*
Y195285D01*
X1643570Y192539D01*
Y187373D01*
X1643145Y186948D01*
X1642457D01*
G01X1596000Y187850D02*
X1595500Y187350D01*
X1593160D01*
X1591500Y185690D01*
Y181000D01*
G01X1648143Y177339D02*
X1645988Y175184D01*
Y173662D01*
X1645984Y173658D01*
Y171722D01*
X1645988Y171718D01*
Y171712D01*
X1645449Y171173D01*
Y169246D01*
X1643662Y167459D01*
G01X1647852Y189229D02*
Y188371D01*
X1648739Y187484D01*
Y185304D01*
X1649983Y184060D01*
Y181710D01*
X1649980Y181707D01*
Y180977D01*
X1648739Y179736D01*
Y177935D01*
X1648143Y177339D01*
G01X1650852Y189229D02*
X1647852D01*
G01X1643662Y158010D02*
X1645237Y159585D01*
G01X1648320Y172690D02*
Y172250D01*
X1649961Y170609D01*
G01X1646812Y161160D02*
X1648326Y162674D01*
G01X1627914Y158010D02*
X1626339Y159585D01*
G01X1649961Y164310D02*
X1648386Y165885D01*
G01X1624764Y161160D02*
X1624701D01*
X1623250Y162611D01*
G01X1646378Y207633D02*
Y208786D01*
X1648795Y211203D01*
X1649814D01*
X1651319Y212708D01*
G01X1646378Y207633D02*
Y205074D01*
G01X1624764Y158010D02*
X1623189Y159585D01*
G01X1634350Y204800D02*
Y206988D01*
X1635621Y208259D01*
G01X1634350Y204800D02*
X1636226D01*
X1636500Y205074D01*
X1639378D01*
G01X1627914Y164310D02*
X1627913D01*
X1626339Y165884D01*
G01X1634213Y164310D02*
Y165115D01*
X1632724Y166604D01*
Y174600D01*
G01X1624972Y192756D02*
Y194419D01*
X1623600Y195791D01*
Y197580D01*
G01X1629473Y184962D02*
X1628789D01*
X1626801Y186950D01*
Y192027D01*
X1626072Y192756D01*
X1624972D01*
G01X1634213Y161160D02*
X1635788Y162735D01*
G01X1643106Y233913D02*
X1643519Y234326D01*
Y234992D01*
X1645827Y237300D01*
X1648500D01*
X1669064Y216736D01*
Y212158D01*
X1667697Y210791D01*
X1658458D01*
X1657996Y210329D01*
Y205420D01*
X1659471Y203945D01*
X1660040D01*
X1662269Y201716D01*
Y198975D01*
X1661353Y198059D01*
X1657534D01*
X1656235Y199358D01*
G01X1654015Y217239D02*
X1653313Y217941D01*
Y220137D01*
X1650250Y223200D01*
Y225150D01*
G01X1602150Y246500D02*
X1602039D01*
X1600560Y247979D01*
X1597927D01*
X1597887Y248019D01*
X1597441D01*
X1596725Y248735D01*
Y249895D01*
X1596300Y250320D01*
G01X1602150Y249500D02*
X1600699D01*
X1600557Y249642D01*
X1599201D01*
G01X1602150Y252500D02*
Y249500D01*
G01Y255500D02*
Y252500D01*
G01X1605819Y259329D02*
X1608752D01*
X1611352Y261929D01*
X1615512D01*
G01Y254055D02*
X1611945D01*
X1610100Y255900D01*
X1607500D01*
X1607100Y255500D01*
X1605650D01*
G01X1643700Y242800D02*
X1641750Y244750D01*
Y252500D01*
G01D02*
X1639300D01*
X1638887Y252087D01*
X1632112D01*
G01X1615512Y246181D02*
X1610821D01*
X1610480Y245840D01*
X1607927D01*
X1606924Y244837D01*
X1606847D01*
X1604610Y242600D01*
X1604400D01*
G01X1602418Y237218D02*
X1604400Y239200D01*
Y242600D01*
G01X1605650Y246500D02*
X1606520Y247370D01*
X1608910D01*
X1611658Y250118D01*
X1615512D01*
G01X1643775Y246137D02*
Y249035D01*
X1645250Y250510D01*
Y252500D01*
G01X1618564Y222460D02*
X1620232D01*
X1621164Y223392D01*
G01D02*
X1622900Y225128D01*
Y228600D01*
X1621500Y230000D01*
X1612998D01*
X1611225Y231773D01*
Y239575D01*
X1611650Y240000D01*
X1618800D01*
X1624504Y245704D01*
X1626122D01*
X1628568Y248150D01*
X1632112D01*
G01X1615512Y242244D02*
X1611645D01*
X1610200Y240799D01*
Y231488D01*
X1612713Y228975D01*
X1620739D01*
X1621164Y228550D01*
Y225910D01*
G01D02*
X1620714Y225460D01*
X1618564D01*
G01X1596600Y246350D02*
Y245701D01*
X1599701Y242600D01*
X1600900D01*
G01X1637441Y224000D02*
Y226941D01*
X1638000Y227500D01*
X1641530D01*
X1644850Y230820D01*
Y231500D01*
G01X1640000Y224000D02*
X1642400D01*
X1643450Y225050D01*
Y227150D01*
X1644650Y228350D01*
X1645400D01*
G01D02*
X1647550D01*
X1648600Y229400D01*
Y233800D01*
G01D02*
X1650000D01*
X1651575Y232225D01*
Y228176D01*
X1658351Y221400D01*
X1658750D01*
G01X1598028Y256422D02*
X1598376D01*
X1599201Y255597D01*
Y253142D01*
G01X1610820Y223832D02*
Y223833D01*
X1611719Y224732D01*
X1614336D01*
X1615064Y225460D01*
G01X1638216Y246021D02*
X1638773Y245464D01*
Y242818D01*
X1642841Y238750D01*
X1649450D01*
X1669990Y218210D01*
Y211303D01*
X1666545Y207858D01*
X1659985D01*
G01X1650400Y246500D02*
Y244005D01*
X1678815Y215590D01*
Y199986D01*
X1683642Y196758D01*
X1687781D01*
X1693923Y202900D01*
X1710586D01*
X1716191Y197295D01*
Y187891D01*
X1713300Y185000D01*
X1713000D01*
G01X1632112Y256024D02*
X1635724D01*
X1636000Y256300D01*
X1639200D01*
X1640000Y255500D01*
X1641750D01*
G01X1650400Y246500D02*
Y254505D01*
X1647105Y257800D01*
X1642550D01*
X1641750Y257000D01*
Y255500D01*
G01X1649666Y241434D02*
X1647900Y243200D01*
Y254148D01*
X1646548Y255500D01*
X1645250D01*
G01X1676750Y206050D02*
Y214350D01*
X1649666Y241434D01*
G01X1649500Y329059D02*
X1652991D01*
G01X1649500Y326500D02*
X1653091D01*
G01X1649500D02*
X1647000D01*
X1645500Y325000D01*
X1644500D01*
G01Y328500D02*
Y325000D01*
G01X1660700Y351600D02*
X1661700D01*
X1669063Y344237D01*
Y318664D01*
X1659338Y308939D01*
X1652354D01*
X1651115Y310178D01*
X1646892D01*
X1641772Y315298D01*
Y315978D01*
X1638086Y319664D01*
G01X1625951Y340193D02*
X1625607D01*
X1621700Y344100D01*
Y353850D01*
X1622550Y354700D01*
G01X1620000Y345750D02*
Y344100D01*
X1622950Y341150D01*
Y339050D01*
X1625406Y336594D01*
X1628566D01*
G01X1620159Y332004D02*
X1620905Y332750D01*
X1628100D01*
X1628566Y333216D01*
Y336594D01*
G01X1637450Y331300D02*
Y333050D01*
X1636440Y334060D01*
Y336594D01*
G01X1638063Y326504D02*
X1637450Y327117D01*
Y331300D01*
G01X1631015Y328350D02*
Y330237D01*
X1630534Y330718D01*
Y336594D01*
G01X1634472D02*
Y333544D01*
X1635200Y332816D01*
Y326482D01*
X1635791Y325891D01*
X1636044D01*
X1637018Y324917D01*
X1637408D01*
X1642697Y319628D01*
Y315682D01*
X1647276Y311103D01*
X1651966D01*
X1652659Y310410D01*
X1659211D01*
X1667638Y318837D01*
Y343747D01*
X1662435Y348950D01*
X1651550D01*
X1645900Y354600D01*
X1637040D01*
X1636198Y355442D01*
X1635342D01*
G01X1635355Y324228D02*
X1634200Y325383D01*
Y332649D01*
X1632503Y334346D01*
Y336594D01*
G01X1639413Y312735D02*
X1643385Y308763D01*
X1649542D01*
X1650735Y307570D01*
X1661114D01*
X1663764Y310220D01*
X1665142D01*
X1666257Y309105D01*
Y300311D01*
X1677437Y289131D01*
Y270611D01*
X1685177Y262871D01*
X1689384D01*
X1689455Y262800D01*
X1834049D01*
X1841382Y255467D01*
Y251346D01*
X1849616Y243112D01*
Y226701D01*
X1856874Y219443D01*
G01X1619897Y336136D02*
X1618496Y334735D01*
Y331315D01*
X1619470Y330341D01*
X1626252D01*
X1630194Y326399D01*
X1630840D01*
X1632537Y324702D01*
Y324694D01*
X1635437Y321794D01*
Y316711D01*
X1639413Y312735D01*
G01X1649500Y318559D02*
Y317236D01*
X1653500Y313236D01*
Y312026D01*
X1653925Y311601D01*
X1658500D01*
X1666713Y319814D01*
Y343363D01*
X1663576Y346500D01*
X1655600D01*
G01X1765945Y244105D02*
Y250268D01*
X1762280Y253933D01*
X1678190D01*
X1668925Y263198D01*
Y283737D01*
X1658183Y294479D01*
X1655669D01*
X1649692Y288502D01*
G01X1759646Y226756D02*
Y222123D01*
X1758766Y221243D01*
X1732957D01*
X1731620Y222580D01*
Y251445D01*
X1729957Y253108D01*
X1677848D01*
X1668100Y262856D01*
Y282652D01*
X1659864Y290888D01*
X1655198D01*
X1645788Y281478D01*
X1643320D01*
G01X1806890Y244105D02*
Y252926D01*
X1805058Y254758D01*
X1678532D01*
X1669750Y263540D01*
Y284079D01*
X1658525Y295304D01*
X1648205D01*
X1641594Y288693D01*
G01X1836900Y232700D02*
X1838075Y233875D01*
Y254058D01*
X1838076Y254059D01*
Y254412D01*
X1832143Y260345D01*
X1684194D01*
X1684193Y260346D01*
X1681573D01*
X1675200Y266719D01*
Y286341D01*
X1659263Y302278D01*
Y305189D01*
X1657852Y306600D01*
X1647900D01*
G01X1604439Y324600D02*
Y320339D01*
X1599512Y315412D01*
Y311137D01*
X1596225Y307850D01*
Y296876D01*
X1606733Y286368D01*
X1621968D01*
X1628046Y292446D01*
X1636822D01*
G01X1614400Y367400D02*
X1616899Y364901D01*
Y331745D01*
X1619128Y329516D01*
X1625903D01*
X1629944Y325475D01*
Y324236D01*
G01D02*
Y320356D01*
X1637671Y312629D01*
Y311977D01*
X1639413Y310235D01*
G01X1633400Y372900D02*
Y373100D01*
X1630900Y375600D01*
G01X1630337Y362600D02*
X1633337D01*
G01X1607495Y394433D02*
X1607403D01*
X1604514Y397322D01*
X1596826D01*
X1596151Y396647D01*
Y395567D01*
X1595612Y395028D01*
X1594451D01*
G01X1594201Y387566D02*
X1594644D01*
X1595843Y386367D01*
Y385697D01*
X1596234Y385306D01*
X1602359D01*
X1602859Y385806D01*
Y387678D01*
X1602404Y388133D01*
X1599227D01*
G01X1630400Y391800D02*
X1635813Y386387D01*
Y362952D01*
X1635803Y362942D01*
Y358650D01*
X1635813Y358640D01*
Y358030D01*
X1638293Y355550D01*
X1647886D01*
X1648881Y354555D01*
X1649005D01*
G01D02*
X1650523Y353037D01*
Y351411D01*
X1651497Y350437D01*
X1656209D01*
X1672413Y366641D01*
Y433732D01*
X1676828Y438147D01*
Y440535D01*
X1675715Y441648D01*
Y443838D01*
X1678008Y446131D01*
Y456617D01*
X1681172Y459781D01*
Y470072D01*
X1689943Y478843D01*
Y487203D01*
G01X1630240Y365099D02*
X1627901D01*
X1625500Y367500D01*
G01X1622550Y358200D02*
Y369572D01*
X1625681Y372703D01*
G01X1629300Y385400D02*
X1625681Y381781D01*
Y372703D01*
G01X1630400Y398700D02*
X1635000D01*
G01X1654770Y399145D02*
X1654325Y398700D01*
X1647100D01*
G01D02*
X1638500D01*
G01X1625535Y361835D02*
X1625400Y361700D01*
Y355600D01*
X1624500Y354700D01*
X1622550D01*
G01X1630476Y360103D02*
X1630337Y359964D01*
X1629764D01*
X1628566Y358766D01*
Y349698D01*
G01X1630534D02*
Y354900D01*
G01X1630550Y401300D02*
X1627525Y398275D01*
Y397925D01*
X1620700Y391100D01*
G01X1645650Y345250D02*
X1643926D01*
X1643555Y344879D01*
X1642443D01*
G01D02*
X1641223Y346099D01*
X1639055D01*
G01X1616890Y396080D02*
Y393310D01*
X1617200Y393000D01*
Y391100D01*
G01D02*
Y390846D01*
X1613452Y387098D01*
G01X1634472Y349698D02*
Y354572D01*
X1635342Y355442D01*
G01X1638991Y352037D02*
Y351743D01*
X1636946Y349698D01*
X1636440D01*
G01X1630408Y357603D02*
X1631097D01*
X1632503Y356197D01*
Y349698D01*
G01X1648650Y348750D02*
X1649700D01*
X1651950Y346500D01*
X1655600D01*
G01X1648650Y348750D02*
X1645650D01*
G01X1616890Y399580D02*
X1615033Y401437D01*
X1611500D01*
G01X1633400Y369400D02*
X1631730Y367730D01*
X1630200D01*
G01X1603050Y432523D02*
X1605727D01*
X1605750Y432500D01*
G01X1627300Y439500D02*
X1627800Y439000D01*
X1636401D01*
X1639411Y442010D01*
X1642810D01*
X1652505Y432315D01*
X1661424D01*
X1664762Y435653D01*
Y438035D01*
G01X1627300Y439500D02*
Y440700D01*
X1626675Y441325D01*
X1622598D01*
X1621709Y442214D01*
X1621686D01*
X1619614Y444286D01*
X1610816D01*
X1608760Y442230D01*
G01D02*
Y442840D01*
X1607314Y444286D01*
X1602601D01*
X1602600Y444287D01*
G01X1612250Y435500D02*
X1614750D01*
G01X1612183Y442623D02*
X1609500Y439940D01*
X1601760D01*
X1599800Y441900D01*
X1599320D01*
G01X1612183Y442623D02*
X1612306Y442500D01*
X1614750D01*
G01X1639750Y445477D02*
Y444049D01*
X1637601Y441900D01*
X1635700D01*
G01X1609750Y412000D02*
X1610600Y412850D01*
Y413450D01*
X1610950Y413800D01*
X1615116D01*
X1617031Y411885D01*
X1633385D01*
X1634400Y412900D01*
G01X1609750Y416000D02*
X1612604D01*
X1613104Y415500D01*
X1615250D01*
G01X1630386Y413942D02*
X1629613Y413169D01*
X1617244D01*
X1615250Y415163D01*
Y415500D01*
G01X1613400Y420500D02*
X1616010D01*
X1617347Y421837D01*
G01Y418837D02*
Y418536D01*
X1618709Y417174D01*
X1624444D01*
X1624602Y417332D01*
G01X1605750Y426000D02*
X1604500D01*
X1604300Y425800D01*
X1602520D01*
G01X1597400Y424761D02*
X1598561D01*
X1602800Y429000D01*
X1605750D01*
G01X1633250Y435500D02*
X1627250D01*
G01X1633250D02*
Y434250D01*
X1633800Y433700D01*
X1638147D01*
X1638772Y433075D01*
X1639375D01*
X1639500Y433200D01*
G01X1606500Y405250D02*
X1609500D01*
G01D02*
X1612637D01*
X1612825Y405438D01*
G01X1606500Y405250D02*
X1605750D01*
X1602600Y408400D01*
X1601300D01*
G01X1603000Y435500D02*
X1605750D01*
G01X1606791Y459843D02*
X1611057D01*
X1611800Y459100D01*
G01X1600400Y446100D02*
X1605650D01*
X1605750Y446000D01*
G01X1633250Y432000D02*
Y430763D01*
X1630150Y427663D01*
G01D02*
X1627250Y430563D01*
Y432000D01*
G01X1620847Y421837D02*
X1621109Y421575D01*
X1645362D01*
X1652037Y428250D01*
X1664500D01*
X1665725Y427025D01*
X1667025D01*
X1667809Y427809D01*
G01X1620847Y418837D02*
X1622560Y420550D01*
X1645787D01*
X1652462Y427225D01*
X1664075D01*
X1665300Y426000D01*
X1667429D01*
X1667729Y425700D01*
Y424621D01*
G01X1609250Y426000D02*
X1610118Y426868D01*
X1613882D01*
X1614750Y426000D01*
G01D02*
Y424250D01*
X1615500Y423500D01*
X1621500D01*
X1622800Y424800D01*
X1628655D01*
G01D02*
X1630573D01*
X1631873Y423500D01*
X1645271D01*
X1651636Y429865D01*
X1663465D01*
X1665350Y431750D01*
X1666748D01*
X1667649Y430849D01*
G01X1609250Y429000D02*
X1610423Y427827D01*
X1613577D01*
X1614750Y429000D01*
G01D02*
Y430250D01*
X1615235Y430735D01*
X1620982D01*
X1621430Y430287D01*
X1621437D01*
X1625724Y426000D01*
X1631199D01*
X1632399Y424800D01*
X1642515D01*
G01D02*
X1644701D01*
X1650791Y430890D01*
X1663040D01*
X1665125Y432975D01*
X1666414D01*
X1667588Y434149D01*
G01X1643430Y437780D02*
X1643210Y437560D01*
X1612251D01*
X1611661Y438150D01*
X1600160D01*
X1598130Y436120D01*
Y435920D01*
G01X1633250Y449500D02*
Y448850D01*
X1634600Y447500D01*
X1635800D01*
X1636700Y446600D01*
Y445800D01*
G01X1630300Y452100D02*
X1632900Y449500D01*
X1633250D01*
G01X1630200Y457175D02*
X1619076D01*
X1613801Y451900D01*
X1611530D01*
X1610630Y451000D01*
X1609250D01*
G01X1605669Y454809D02*
Y456393D01*
X1606277Y457001D01*
X1616200D01*
X1618899Y459700D01*
X1628700D01*
X1642783Y473783D01*
Y480044D01*
X1645180Y482441D01*
Y491113D01*
X1644293Y492000D01*
X1640136D01*
X1639271Y491135D01*
G01X1643300Y455100D02*
X1643941D01*
X1646451Y452590D01*
G01X1649800Y452300D02*
X1646741D01*
X1646451Y452590D01*
G01X1646469Y450090D02*
X1645459Y451100D01*
X1638150D01*
X1636750Y452500D01*
G01Y449500D02*
X1636850Y449400D01*
X1642000D01*
X1643300Y448100D01*
G01D02*
X1643810Y447590D01*
X1646525D01*
G01X1627800Y464100D02*
X1625600Y461900D01*
X1622700D01*
G01X1615300Y459100D02*
X1617400Y461200D01*
X1622000D01*
X1622700Y461900D01*
G01X1623750Y446500D02*
X1621550Y448700D01*
X1619984D01*
G01D02*
X1619200D01*
X1617900Y450000D01*
X1616300D01*
G01X1602450Y451360D02*
X1602810Y451000D01*
X1605750D01*
G01X1639822Y453140D02*
X1639736Y453054D01*
X1639133D01*
X1637687Y454500D01*
X1633750D01*
X1633250Y454000D01*
Y452500D01*
G01X1644040Y428970D02*
X1645720D01*
X1647200Y430450D01*
G01X1643430Y434280D02*
Y429580D01*
X1644040Y428970D01*
G01X1636750Y435500D02*
X1639300D01*
X1639500Y435700D01*
G01X1612800Y450000D02*
X1611997Y449197D01*
X1601671D01*
X1601550Y449318D01*
X1597885D01*
G01X1640625Y429460D02*
X1640332Y429167D01*
Y428232D01*
X1639200Y427100D01*
X1636700D01*
G01X1636750Y432000D02*
Y427150D01*
X1636700Y427100D01*
G01X1611935Y429515D02*
X1614750Y432330D01*
Y432500D01*
G01X1611935Y429515D02*
X1610765Y430685D01*
X1600259D01*
X1599194Y429620D01*
G01X1612256Y440088D02*
X1612844Y439500D01*
X1614750D01*
G01X1612825Y408974D02*
X1612875D01*
X1612651Y408750D01*
X1609500D01*
G01X1623750Y443500D02*
X1622752D01*
X1621226Y445026D01*
G01X1627300Y449800D02*
Y453663D01*
G01D02*
Y453700D01*
X1628275Y454675D01*
X1630200D01*
G01X1620700Y403400D02*
X1616900D01*
G01X1595800Y405900D02*
X1601800D01*
X1604300Y403400D01*
X1616900D01*
G01X1620700D02*
X1621600D01*
X1622400Y404200D01*
Y405900D01*
X1623500Y407000D01*
X1624200D01*
G01X1603000Y422971D02*
X1605449D01*
G01X1594000Y455500D02*
X1596500D01*
G01X1623800Y449800D02*
X1623200D01*
X1621000Y452000D01*
G01X1620700Y406900D02*
Y407100D01*
X1617900Y409900D01*
G01X1616900Y406900D02*
Y408548D01*
X1616237Y409211D01*
Y409263D01*
X1613700Y411800D01*
X1612500D01*
G01X1627622Y524928D02*
Y526473D01*
X1628221Y527072D01*
Y528779D01*
X1628038Y528962D01*
Y530500D01*
G01X1630159Y520608D02*
X1627535Y523232D01*
X1626571D01*
X1625704Y524099D01*
Y525907D01*
X1624443Y527168D01*
X1622633D01*
X1621295Y528506D01*
Y530312D01*
G01X1634611Y487167D02*
X1640072D01*
X1640743Y487838D01*
Y487760D01*
X1640781D01*
G01X1634611Y518663D02*
X1629062D01*
X1627407Y520318D01*
G01D02*
X1625807Y521918D01*
X1623361D01*
G01X1634611Y502915D02*
X1640623D01*
X1648123Y495415D01*
Y483364D01*
X1649788Y481699D01*
Y479642D01*
X1652783Y476647D01*
Y475551D01*
X1652782Y475550D01*
Y474838D01*
X1658840Y468780D01*
X1659311D01*
X1661000Y467091D01*
Y466050D01*
G01X1623361Y518918D02*
X1625683D01*
X1627301Y517300D01*
X1629668D01*
X1632242Y514726D01*
X1634611D01*
G01D02*
X1637730D01*
X1639391Y513065D01*
G01X1634611Y498978D02*
X1642686D01*
X1646798Y494866D01*
Y482814D01*
X1648463Y481149D01*
Y479093D01*
X1651457Y476099D01*
Y474289D01*
X1657500Y468246D01*
Y466050D01*
G01X1629778Y507294D02*
Y500025D01*
X1630825Y498978D01*
X1634611D01*
G01X1642670Y514939D02*
X1644874Y517143D01*
X1650649D01*
X1652328Y515464D01*
X1653016D01*
X1653755Y514725D01*
X1653756Y514726D01*
X1656611D01*
G01X1629500Y491500D02*
X1630104D01*
X1630500Y491104D01*
X1634611D01*
G01X1626518Y528029D02*
X1626493Y528054D01*
X1625747D01*
X1624538Y529263D01*
Y530500D01*
G01X1631975Y527700D02*
X1631538Y528137D01*
Y530500D01*
G01X1594110Y611510D02*
X1595790Y613190D01*
X1602330D01*
X1608070Y607450D01*
Y586170D01*
X1609620Y584620D01*
Y576570D01*
X1607760Y574710D01*
X1603660D01*
X1599104Y579266D01*
Y580396D01*
G01X1595604Y584396D02*
Y580396D01*
G01Y588396D02*
Y584396D01*
G01X1589578Y582396D02*
X1591910D01*
X1593910Y580396D01*
X1595604D01*
G01X1592934Y592396D02*
X1595604D01*
G01X1589578Y593700D02*
X1591630D01*
X1592934Y592396D01*
G01X1593519Y618736D02*
X1592493Y619762D01*
Y621264D01*
X1594177Y622948D01*
X1775452D01*
X1776500Y621900D01*
Y621200D01*
G01X1590881Y618788D02*
X1591468Y619375D01*
Y621689D01*
X1593752Y623973D01*
X1777027D01*
X1778400Y622600D01*
Y618900D01*
G01X1691000Y3000D02*
Y300D01*
X1700800Y-9500D01*
X1708003D01*
X1713503Y-15000D01*
G01X1695300Y94712D02*
Y93793D01*
X1697166Y91927D01*
X1700103D01*
X1703819Y88211D01*
X1705203D01*
X1706800Y86614D01*
Y83289D01*
X1712845Y77244D01*
Y73346D01*
X1713691Y72500D01*
X1715801D01*
X1720002Y68299D01*
X1722171D01*
X1724785Y70913D01*
X1726279D01*
X1726992Y70200D01*
X1736100D01*
X1738100Y68200D01*
Y57100D01*
X1735500Y54500D01*
X1729500D01*
G01X1653000Y85250D02*
Y86699D01*
X1650931Y88768D01*
Y90182D01*
G01X1667000Y88000D02*
X1667499D01*
X1670708Y91209D01*
Y92672D01*
X1665993Y97387D01*
X1663832D01*
X1662887Y98332D01*
Y100417D01*
X1661337Y101967D01*
Y101968D01*
X1659468Y103837D01*
X1659467D01*
X1659410Y103894D01*
Y104467D01*
G01X1668859Y113916D02*
X1678023D01*
X1684739Y107200D01*
X1702650D01*
X1706596Y103254D01*
Y95656D01*
X1712688Y89564D01*
X1717686D01*
X1718650Y88600D01*
X1722199D01*
X1722950Y87849D01*
Y86600D01*
G01X1671854Y100546D02*
X1668995D01*
X1665709Y103832D01*
Y104467D01*
G01X1687280Y68600D02*
Y72571D01*
X1683688Y76163D01*
X1679211D01*
X1678237Y75189D01*
Y74103D01*
X1677117Y72983D01*
X1675739D01*
X1673800Y74922D01*
Y75200D01*
G01X1668000Y81600D02*
X1671237Y78363D01*
X1674400D01*
G01D02*
X1686359D01*
X1688872Y75850D01*
X1691782D01*
X1692207Y75425D01*
Y72441D01*
X1692400Y72248D01*
Y68600D01*
G01X1676428Y74646D02*
X1678770Y76988D01*
X1684953D01*
X1689840Y72101D01*
Y68600D01*
G01X1653000Y77600D02*
Y81750D01*
G01X1656500Y89500D02*
Y91000D01*
X1654406Y93094D01*
Y94104D01*
G01X1677573Y86930D02*
X1679707Y89064D01*
Y94697D01*
X1679980Y94970D01*
G01X1654100Y73800D02*
Y76099D01*
X1655857Y77856D01*
X1656737D01*
G01X1664350Y69962D02*
X1661591Y67203D01*
X1653897D01*
X1650800Y70300D01*
G01X1664350Y69962D02*
X1665821Y68491D01*
Y66818D01*
X1668584Y64055D01*
X1671844D01*
X1683218Y52681D01*
X1693522D01*
X1694960Y51243D01*
Y46400D01*
G01X1664350Y72462D02*
X1666746Y70066D01*
Y67202D01*
X1668968Y64980D01*
X1672444D01*
X1683404Y54020D01*
X1693782D01*
X1697520Y50282D01*
Y46400D01*
G01X1654100Y70300D02*
X1656272Y68128D01*
X1660966D01*
X1662500Y69662D01*
Y70612D01*
X1664350Y72462D01*
G01X1669000Y92000D02*
X1667547D01*
X1665909Y93638D01*
G01D02*
X1662013Y97534D01*
Y99767D01*
X1657671Y104109D01*
Y106206D01*
X1656260Y107617D01*
G01X1670055Y96483D02*
X1672098Y94440D01*
Y85002D01*
X1675500Y81600D01*
G01X1663700Y87800D02*
X1664848D01*
X1666648Y86000D01*
X1668600D01*
X1669800Y84800D01*
G01D02*
X1673000Y81600D01*
G01X1653111Y107617D02*
X1654818Y105910D01*
Y99778D01*
X1657708Y96888D01*
X1659731D01*
X1663700Y92919D01*
Y87800D01*
G01X1675062Y91219D02*
Y95630D01*
X1673693Y96999D01*
Y97012D01*
X1671200Y99505D01*
X1671187D01*
X1671186Y99506D01*
X1670504D01*
X1670503Y99505D01*
X1668607D01*
X1665108Y103004D01*
X1665103D01*
X1664246Y103861D01*
Y105237D01*
X1662560Y106923D01*
Y107617D01*
G01Y104467D02*
Y103757D01*
X1664502Y101815D01*
X1665131D01*
X1668265Y98681D01*
X1670845D01*
X1673399Y96127D01*
Y88714D01*
X1674749Y87364D01*
Y87050D01*
G01X1684248Y56746D02*
X1686049Y54945D01*
X1694264D01*
X1698347Y50862D01*
X1716570D01*
X1719750Y54042D01*
Y57500D01*
G01X1716050Y67000D02*
X1714800D01*
X1713200Y65400D01*
X1711300D01*
G01Y68900D02*
X1713500D01*
X1715100Y70500D01*
G01X1684720Y68600D02*
Y72285D01*
X1684369Y72636D01*
X1681482D01*
X1679900Y74218D01*
Y74500D01*
G01X1740638Y106427D02*
G03X1739200Y102955I3472J-3472D01*
G01Y100216D01*
G02X1737434Y98450I-1766J0D01*
G01X1737100D01*
G03X1733942Y97142I0J-4466D01*
G01X1729115Y92314D01*
G02X1725702Y90900I-3413J3412D01*
G01X1724609D01*
G02X1724100Y91021I0J1130D01*
G03X1723079Y91444I-1021J-1021D01*
G01X1716401D01*
G02X1712432Y93088I0J5613D01*
G01X1712140Y93380D01*
G02X1710359Y97680I4300J4300D01*
G01Y106174D01*
G03X1707373Y109160I-2986J0D01*
G01X1688685D01*
G02X1686474Y110076I0J3126D01*
G01X1682615Y113935D01*
G01X1702500Y84668D02*
Y87083D01*
G01X1692500Y90000D02*
X1693824D01*
X1694900Y88924D01*
Y84683D01*
X1699941Y79642D01*
Y77668D01*
G01X1696655Y77991D02*
Y80345D01*
X1694500Y82500D01*
X1692500D01*
G01X1689000Y90000D02*
Y88314D01*
X1687437Y86751D01*
Y84063D01*
X1689000Y82500D01*
X1692500D01*
G01X1689000Y90000D02*
X1688967Y89967D01*
X1686033D01*
X1686000Y90000D01*
G01X1700000Y105500D02*
X1701950D01*
X1704677Y102773D01*
Y95753D01*
X1711788Y88642D01*
Y85112D01*
X1717150Y79750D01*
X1718500D01*
G01X1711869Y81690D02*
X1710563Y82996D01*
Y85965D01*
X1709578Y86950D01*
X1708480D01*
X1705381Y90049D01*
X1704824D01*
G01X1711700Y62000D02*
X1711100Y61400D01*
X1700800D01*
X1697520Y64680D01*
Y68600D01*
G01X1711700Y62000D02*
X1714700D01*
G01X1705000Y59500D02*
X1708000D01*
G01X1705000D02*
X1700649D01*
X1694960Y65189D01*
Y68600D01*
G01X1704900Y63200D02*
X1702099D01*
X1700080Y65219D01*
Y68600D01*
G01X1704900Y63200D02*
Y66268D01*
G01X1673400Y59420D02*
X1676050Y56770D01*
Y54520D01*
X1679314Y51256D01*
X1691244D01*
X1692400Y50100D01*
Y46400D01*
G01X1667916Y58116D02*
Y59436D01*
X1668850Y60370D01*
X1672450D01*
X1673400Y59420D01*
G01X1653111Y110766D02*
X1654686Y109191D01*
G01X1658154Y99400D02*
X1658100D01*
Y100500D01*
X1656260Y102340D01*
Y104467D01*
G01X1653111Y117066D02*
X1654673Y118628D01*
G01X1653111Y113916D02*
Y113915D01*
X1654685Y112341D01*
G01X1656260Y117066D02*
X1657835Y115491D01*
G01X1656260Y110766D02*
X1657835Y109191D01*
G01X1659410Y110766D02*
X1660985Y109191D01*
G01X1685622Y103069D02*
X1683783D01*
X1678814Y108038D01*
X1670851D01*
X1669586Y109303D01*
X1668036D01*
X1666573Y110766D01*
X1665709D01*
G01X1685622Y103069D02*
X1686381D01*
X1689348Y100102D01*
Y98750D01*
X1689368D01*
G01X1668859Y117066D02*
X1670434Y115491D01*
G01X1665709Y117066D02*
X1667284Y115491D01*
G01X1659410Y117066D02*
X1660985Y115491D01*
G01X1662560Y120215D02*
X1664135Y118640D01*
G01X1656260Y113916D02*
X1657835Y112341D01*
G01X1659410Y113916D02*
X1660985Y112341D01*
G01X1653111Y102240D02*
Y104467D01*
G01X1679980Y94970D02*
X1673472Y101478D01*
X1669229D01*
X1667396Y103311D01*
Y104849D01*
X1665709Y106536D01*
Y107617D01*
G01Y113916D02*
X1667238Y112387D01*
G01X1670055Y96483D02*
X1669555Y96983D01*
X1668797D01*
X1664897Y100883D01*
X1664075D01*
X1661097Y103861D01*
Y105930D01*
X1659410Y107617D01*
G01X1696650Y102000D02*
Y99334D01*
X1696907Y99077D01*
G01X1668859Y107617D02*
X1669522D01*
X1670489Y106650D01*
X1678288D01*
X1685976Y98962D01*
X1686876D01*
G01X1684020Y142025D02*
Y141515D01*
X1683433Y140928D01*
X1682096D01*
X1681586Y141438D01*
G01X1668859Y145412D02*
X1673128D01*
G03X1676515Y146815I0J4790D01*
G01X1678325Y148625D01*
G02X1682120Y150197I3795J-3795D01*
G02X1682566Y150213I453J-6390D01*
G01X1696707D01*
G03Y152138I0J962D01*
G01X1684735D01*
G02Y154065I0J964D01*
G01X1687726D01*
G03X1688688Y155027I0J962D01*
G01Y155248D01*
G02X1690613I962J0D01*
G01Y155027D01*
G03X1691577Y154063I964J0D01*
G01X1698502D01*
X1698927Y153638D01*
Y153139D01*
G01X1689785Y161180D02*
X1689480Y160875D01*
X1689201D01*
X1689199Y160873D01*
G03X1687871Y160323I0J-1878D01*
G01X1687092Y159544D01*
G03Y158536I504J-504D01*
G02Y157528I-504J-504D01*
G01X1686738Y157174D01*
G02X1685730I-504J504D01*
G03X1684722I-504J-504D01*
G01X1676559Y149011D01*
G02X1671675Y146988I-4884J4884D01*
G01X1668113D01*
G03X1666700Y146403I0J-1999D01*
G01X1665709Y145412D01*
G01X1700836Y161268D02*
Y162112D01*
G03X1700346Y162602I-490J0D01*
G01X1698400D01*
G03X1697653Y161855I0J-747D01*
G01Y160610D01*
G03X1698615Y159648I962J0D01*
G01X1699676D01*
G02Y157723I0J-962D01*
G01X1698425D01*
G03X1697653Y156951I0J-772D01*
G02X1695727I-963J0D01*
G01Y161855D01*
G03X1693801I-963J0D01*
G01Y157498D01*
G02X1691875I-963J0D01*
G01Y161855D01*
G03X1690807Y162923I-1068J0D01*
G01X1688805D01*
G03X1686930Y162147I-1J-2652D01*
G01X1675508Y150725D01*
G02X1670286Y148562I-5222J5222D01*
G01X1668859D01*
G01X1695734Y164676D02*
X1701866D01*
G03Y166731I0J1028D01*
G01X1692762D01*
G03X1692187Y166493I0J-814D01*
G01X1690992Y165298D01*
G02X1689942Y164863I-1050J1050D01*
G01X1688871D01*
G03X1686656Y164365I0J-5176D01*
G03X1685570Y163601I1658J-3511D01*
G01X1679250Y157286D01*
X1674390Y152430D01*
G02X1672653Y151711I-1737J1739D01*
G01X1668859D01*
G01X1665709D02*
Y152349D01*
G02X1665994Y153037I973J0D01*
G01X1665997Y153040D01*
G02X1666596Y153288I599J-599D01*
G01X1671745D01*
G03X1672932Y153780I0J1678D01*
G01X1683692Y164541D01*
G02X1684219Y165015I4687J-4681D01*
G02X1687805Y166758I4312J-4312D01*
G03X1689657Y167525I0J2619D01*
G01X1689714Y167582D01*
G02X1692428Y168706I2714J-2714D01*
G01X1695983D01*
G03X1696945Y169668I0J962D01*
G01Y169745D01*
G02X1698870I962J0D01*
G01Y169664D01*
G03X1700795I962J0D01*
G01Y169745D01*
G02X1702720I962J0D01*
G01Y169668D01*
G03X1703682Y168706I962J0D01*
G01X1704752D01*
G02X1705836Y168257I0J-1533D01*
G02X1706286Y167171I-1086J-1086D01*
G01Y163321D01*
G03X1707248Y162359I962J0D01*
G01X1708873D01*
G02Y160434I0J-962D01*
G01X1707248D01*
G03X1706286Y159472I0J-962D01*
G02X1705826Y159012I-460J0D01*
G01X1703398D01*
G02X1702758Y159652I0J640D01*
G01Y160789D01*
G02X1703183Y161214I425J0D01*
G01X1703610D01*
G01X1701455Y153083D02*
X1701473Y153101D01*
X1705238D01*
G03Y155056I0J978D01*
G01X1703744D01*
G02Y156982I0J963D01*
G01X1706976D01*
G02X1708175Y155783I0J-1199D01*
G01Y149584D01*
G02X1706879Y148288I-1296J0D01*
G01X1682921D01*
G03X1678534Y146471I0J-6205D01*
G01X1677462Y145399D01*
G02X1676492Y144696I-2686J2685D01*
G02X1672900Y143838I-3593J7095D01*
G01X1664786D01*
G03X1663677Y143378I0J-1567D01*
G01X1662561Y142262D01*
X1662560D01*
G01X1702140Y146363D02*
X1704155D01*
G02X1704928Y146043I0J-1093D01*
G02X1705635Y144336I-1707J-1707D01*
G01Y134761D01*
G03X1707561I963J0D01*
G01Y143230D01*
G02X1709487I963J0D01*
G01Y134670D01*
G03X1711413I963J0D01*
G01Y142959D01*
G02X1713339I963J0D01*
G01Y137263D01*
G03X1714252Y136350I913J0D01*
G01X1719509D01*
G02X1720627Y135887I0J-1581D01*
G01X1721740Y134774D01*
G01X1702140Y146363D02*
X1684297D01*
G03X1679250Y144435I0J-7570D01*
G03X1678944Y144146I5043J-5646D01*
G01X1678943Y144145D01*
G02X1673440Y142262I-5503J7100D01*
G01X1668859D01*
G01X1665709Y139113D02*
X1665860D01*
G03X1666886Y139538I0J1451D01*
G01X1667386Y140038D01*
X1667561Y140214D01*
G02X1668586Y140638I1025J-1027D01*
G01X1675458D01*
G03X1679250Y141838I0J6591D01*
G03X1680119Y142569I-3793J5391D01*
G01X1680156Y142606D01*
G02X1684578Y144438I4422J-4421D01*
G01X1691776D01*
G01D02*
X1702655D01*
G02Y142438I0J-1000D01*
G01X1701122D01*
G03Y140512I0J-963D01*
G01X1702603D01*
G02Y138586I0J-963D01*
G01X1699196D01*
G02X1698233Y139549I0J963D01*
G01Y141475D01*
G03X1697270Y142438I-963J0D01*
G01X1693586D01*
G01X1740638Y112726D02*
X1739576Y111664D01*
G02X1738335Y111150I-1241J1241D01*
G01X1735536D01*
G03X1733490Y109104I0J-2046D01*
G01Y105911D01*
G02X1732849Y104363I-2190J0D01*
G01X1725412Y96926D01*
G02X1721860Y95455I-3552J3553D01*
G01X1716872D01*
G02X1714389Y97938I0J2483D01*
G01Y108241D01*
G03X1709380Y113250I-5009J0D01*
G01X1701890D01*
G01X1668859Y126514D02*
X1668860Y126515D01*
G02X1671682Y127684I2822J-2822D01*
G01X1677233D01*
G02X1678486Y127165I0J-1772D01*
G03X1678791Y126954I731J731D01*
G01X1679250Y126745D01*
X1679441Y126658D01*
G03X1680625Y126401I1184J2599D01*
G02X1683329Y125281I0J-3824D01*
G01X1695003Y113607D01*
G03X1695865Y113250I862J862D01*
G01X1701890D01*
G01X1692272Y119372D02*
X1692271D01*
X1679353Y132290D01*
G02X1679092Y132920I630J630D01*
G03X1678577Y134163I-1758J0D01*
G01X1678226Y134514D01*
G03X1675092Y135812I-3134J-3134D01*
G01X1673950D01*
G03X1672342Y135146I0J-2274D01*
G01X1672121Y134925D01*
G02X1670704Y134338I-1417J1417D01*
G01X1662186D01*
G03X1660046Y133451I0J-3025D01*
G01X1659410Y132814D01*
G01X1692272Y119372D02*
Y119371D01*
X1695742Y115901D01*
G03X1696679Y115513I937J937D01*
G01X1697626D01*
G03X1698589Y116476I0J963D01*
G01Y118530D01*
G02X1700515I963J0D01*
G01Y116476D01*
G03X1702441I963J0D01*
G01Y118531D01*
G02X1704367I963J0D01*
G01Y116476D01*
G03X1706293I963J0D01*
G01Y118530D01*
G02X1708219I963J0D01*
G01Y116476D01*
G03X1710145I963J0D01*
G01Y118462D01*
G02X1712071I963J0D01*
G01Y116476D01*
G03X1713034Y115513I963J0D01*
G01X1715262D01*
G02X1716500Y115000I0J-1751D01*
G03X1718311Y114250I1811J1811D01*
G01X1722185D01*
G03X1724027Y115013I0J2605D01*
G01X1724890Y115876D01*
G01X1682615Y113935D02*
X1681820Y114730D01*
X1681801Y114750D01*
G03X1679972Y115507I-1828J-1829D01*
G01X1677217D01*
G02X1674194Y116758I-1J4276D01*
G01X1672968Y117984D01*
G03X1671843Y118450I-1125J-1125D01*
G01X1668934D01*
G02X1666440Y119484I0J3525D01*
G01X1665709Y120215D01*
G01Y126514D02*
G03X1665982Y125855I933J0D01*
G01X1666501Y125336D01*
G03X1667462Y124938I961J961D01*
G01X1670664D01*
G03X1671480Y125276I0J1154D01*
G01X1672122Y125918D01*
G02X1672530Y126087I408J-408D01*
G01X1675003D01*
G02X1679013Y124426I0J-5671D01*
G01X1680407Y123032D01*
G02Y121672I-680J-680D01*
G01X1680164Y121429D01*
G03Y120069I680J-680D01*
G01X1680166Y120067D01*
G03X1681526I680J680D01*
G01X1681769Y120310D01*
G02X1683129I680J-680D01*
G01X1683131Y120308D01*
G02Y118948I-680J-680D01*
G01X1682888Y118705D01*
G03Y117345I680J-680D01*
G01X1682890Y117343D01*
G03X1684250I680J680D01*
G01X1684493Y117586D01*
G02X1685853I680J-680D01*
G01X1691458Y111986D01*
G03X1693225Y111254I1768J1768D01*
G01X1695119D01*
G01X1737488Y100128D02*
X1731964D01*
G03X1731574Y99966I1J-552D01*
G01X1727648Y96040D01*
G02X1721358Y93435I-6290J6291D01*
G01X1716619D01*
G02X1713690Y94648I0J4143D01*
G01X1713652Y94686D01*
G02X1712363Y97798I3113J3112D01*
G01Y107664D01*
G03X1708773Y111254I-3590J0D01*
G01X1695119D01*
G01X1714189Y165781D02*
X1711814Y163406D01*
Y157833D01*
X1713952Y155695D01*
Y151150D01*
G02X1712026I-963J0D01*
G01Y153550D01*
G03X1710100I-963J0D01*
G01Y149564D01*
X1717014Y142650D01*
G01X1688207Y168972D02*
X1687329D01*
G03X1683955Y167575I-1J-4770D01*
G01X1679250Y162871D01*
X1671488Y155111D01*
G02X1670886Y154861I-603J602D01*
G01X1668859D01*
G01X1718591Y115876D02*
X1713237Y121230D01*
X1707500D01*
G01X1706100Y124950D02*
Y123500D01*
X1705300Y122700D01*
Y121655D01*
X1705725Y121230D01*
X1707500D01*
G01X1685578Y94887D02*
Y96198D01*
X1680890Y100886D01*
X1679250D01*
G01X1677506D02*
X1676640Y101752D01*
Y104367D01*
X1675969Y105038D01*
X1670350D01*
X1670322Y105066D01*
Y105073D01*
X1669465Y105930D01*
X1669458D01*
X1669234Y106154D01*
X1668005D01*
X1667238Y106921D01*
Y108434D01*
X1666592Y109080D01*
X1664246D01*
X1662560Y110766D01*
G01X1696650Y105500D02*
X1700000D01*
G01X1668859Y110766D02*
X1670733D01*
X1672111Y109388D01*
X1679011D01*
X1682899Y105500D01*
X1687600D01*
X1688800Y104300D01*
X1690870D01*
G01D02*
X1692800D01*
X1694000Y105500D01*
X1696650D01*
G01X1662560Y113916D02*
X1664135Y112341D01*
G01X1662560Y117066D02*
X1664135Y115491D01*
G01X1659410Y120215D02*
X1660985Y118640D01*
G01X1656260Y120215D02*
X1657835Y118640D01*
G01X1674912Y183000D02*
Y181967D01*
X1670344Y177399D01*
Y169844D01*
X1668859Y168359D01*
Y167459D01*
G01X1673530Y209974D02*
Y204693D01*
X1669405Y200568D01*
G01D02*
X1666337Y197500D01*
X1662362D01*
X1661937Y197075D01*
Y187130D01*
X1661211Y186404D01*
Y183825D01*
X1662500Y182536D01*
Y181001D01*
X1657966Y176467D01*
Y169165D01*
X1656260Y167459D01*
G01X1710650Y169700D02*
Y170850D01*
X1710120Y171380D01*
Y172616D01*
G01D02*
Y173280D01*
X1708350Y175050D01*
G01X1699900Y174350D02*
X1703350D01*
G01D02*
X1704850D01*
X1707100Y176600D01*
Y188300D01*
G01X1677600Y172700D02*
X1678286Y173386D01*
X1681386D01*
X1683340Y175340D01*
Y177101D01*
G01X1672120Y190000D02*
Y198899D01*
X1673800Y200579D01*
Y201070D01*
G01X1672120Y190000D02*
Y188580D01*
X1673300Y187400D01*
Y181717D01*
X1666701Y175118D01*
Y171982D01*
X1667172Y171511D01*
Y168922D01*
X1665709Y167459D01*
G01X1692845Y170746D02*
X1684392D01*
X1679062Y165416D01*
G01X1667140Y182300D02*
Y177997D01*
X1662560Y173417D01*
Y170609D01*
G01X1683340Y180601D02*
X1685492D01*
X1685930Y181039D01*
Y184670D01*
X1684550Y186050D01*
Y187970D01*
G01X1683340Y180601D02*
X1682052D01*
X1680776Y179325D01*
Y178223D01*
X1676832Y174279D01*
X1673769D01*
X1672843Y173353D01*
Y166225D01*
X1669465Y162847D01*
X1667396D01*
X1665709Y161160D01*
G01X1669849Y193067D02*
X1669957D01*
Y188481D01*
X1670632Y187806D01*
Y184512D01*
X1668752Y182632D01*
Y178442D01*
X1663384Y173074D01*
Y171854D01*
X1664023Y171215D01*
Y168922D01*
X1662560Y167459D01*
G01X1653111Y161160D02*
Y161161D01*
X1654685Y162735D01*
G01X1679849Y192788D02*
Y193806D01*
X1676924Y196731D01*
G01X1680901Y170417D02*
X1682655Y172171D01*
X1692260D01*
X1694431Y174342D01*
Y174350D01*
X1696400D01*
G01X1665709Y158010D02*
X1666932D01*
X1668507Y159585D01*
X1670585D01*
X1679100Y168100D01*
Y168616D01*
X1680901Y170417D01*
G01X1688046Y174447D02*
X1689843Y176244D01*
Y177381D01*
G01X1662560Y164310D02*
X1660985Y165885D01*
G01X1693343Y177381D02*
X1692556Y176594D01*
Y175712D01*
X1691439Y174595D01*
Y174354D01*
G01X1696368Y177380D02*
X1693344D01*
X1693343Y177381D01*
G01X1699868Y177380D02*
Y179132D01*
X1698611Y180389D01*
Y183518D01*
G01X1684600Y194000D02*
X1687600D01*
X1689421Y192179D01*
X1692312D01*
G01X1693242Y198749D02*
Y196816D01*
X1692312Y195886D01*
Y192179D01*
G01X1676624Y185521D02*
Y182400D01*
X1671189Y176965D01*
Y169390D01*
X1670400Y168601D01*
Y166900D01*
X1669400Y165900D01*
X1667299D01*
X1665709Y164310D01*
G01X1676624Y185521D02*
X1676849Y185746D01*
Y189288D01*
G01X1678400Y179600D02*
X1675053D01*
X1672019Y176566D01*
Y169019D01*
X1671300Y168300D01*
Y166600D01*
X1669010Y164310D01*
X1668859D01*
G01X1678400Y179600D02*
X1678740Y179940D01*
Y187250D01*
X1679849Y188359D01*
Y189288D01*
G01X1652218Y182351D02*
Y185787D01*
X1653300Y186869D01*
Y188639D01*
X1653949Y189288D01*
G01X1652218Y182351D02*
X1652765Y181804D01*
Y176840D01*
X1651748Y175823D01*
Y168822D01*
X1653111Y167459D01*
G01X1659410Y170609D02*
Y173000D01*
X1665300Y178890D01*
Y180100D01*
X1663434Y181966D01*
Y185008D01*
G01D02*
X1664349Y185923D01*
Y189288D01*
G01X1656260Y170609D02*
X1656535Y170884D01*
Y176550D01*
X1658500Y178515D01*
Y179742D01*
G01D02*
Y181901D01*
X1660200Y183601D01*
Y186563D01*
X1659949Y186814D01*
Y189288D01*
G01X1659410Y167459D02*
X1660963Y169012D01*
Y173209D01*
X1666300Y178546D01*
Y180300D01*
X1665500Y181100D01*
Y183801D01*
X1666944Y185245D01*
X1668377D01*
X1668519Y185387D01*
G01D02*
Y187514D01*
X1667349Y188684D01*
Y189288D01*
G01X1656949D02*
Y186868D01*
G01X1653111Y164310D02*
X1654897Y166096D01*
Y176570D01*
X1657600Y179273D01*
Y183000D01*
X1658000Y183400D01*
Y185337D01*
G01X1663566Y213009D02*
X1660599Y215976D01*
X1655316D01*
X1654153Y214813D01*
X1652695D01*
X1651319Y213437D01*
Y212708D01*
G01X1844444Y224035D02*
X1845726Y225317D01*
Y244986D01*
X1839957Y250755D01*
Y254547D01*
X1832904Y261600D01*
X1689099D01*
X1688928Y261771D01*
X1682164D01*
X1676300Y267635D01*
Y286797D01*
X1664471Y298626D01*
Y308539D01*
X1664453Y308557D01*
G01X1835936Y235604D02*
X1837250Y236918D01*
Y254071D01*
X1831801Y259520D01*
X1680315D01*
X1674375Y265460D01*
Y285999D01*
X1657974Y302400D01*
X1654900D01*
G01X1730996Y442804D02*
X1723189Y434997D01*
X1683564D01*
X1679916Y431349D01*
Y309315D01*
X1677100Y306499D01*
Y296500D01*
X1679100Y294500D01*
G01X1663800Y320500D02*
X1662174Y318874D01*
X1662100D01*
X1659226Y316000D01*
X1656500D01*
G01Y323941D02*
X1663059D01*
X1663800Y323200D01*
Y320500D01*
G01X1662000Y328750D02*
Y326600D01*
X1661150Y325750D01*
X1657150D01*
X1656500Y325100D01*
Y323941D01*
G01X1724369Y441601D02*
X1718887Y436119D01*
X1683153D01*
X1678891Y431857D01*
Y309740D01*
X1676000Y306849D01*
Y295100D01*
X1679100Y292000D01*
G01X1660700Y351600D02*
Y353100D01*
X1673338Y365738D01*
Y433203D01*
X1677753Y437618D01*
Y440919D01*
X1676718Y441954D01*
Y441998D01*
X1676640Y442076D01*
Y443454D01*
X1678933Y445747D01*
Y456233D01*
X1682097Y459397D01*
Y469497D01*
X1692443Y479843D01*
Y487259D01*
G01X1652050Y410500D02*
Y408400D01*
X1651147Y407497D01*
Y404203D01*
X1652042Y403308D01*
X1655498D01*
X1657119Y401687D01*
Y401669D01*
G01X1655550Y410500D02*
Y408011D01*
X1653310Y405771D01*
G01X1657984Y403994D02*
Y406984D01*
X1659050Y408050D01*
Y410500D01*
G01X1661470Y456251D02*
X1654951D01*
X1654400Y455700D01*
G01D02*
Y453900D01*
X1656000Y452300D01*
Y451750D01*
G01X1669816Y446453D02*
X1666847D01*
X1666200Y447100D01*
G01X1651867Y484741D02*
X1653378Y483230D01*
X1656611D01*
G01X1651926Y482197D02*
Y480335D01*
X1652968Y479293D01*
X1656611D01*
G01X1680133Y535489D02*
Y534838D01*
X1682371Y532600D01*
X1684800D01*
X1686400Y531000D01*
Y519523D01*
X1687673Y518250D01*
X1690000D01*
G01D02*
X1693017D01*
X1693019Y518252D01*
G01D02*
Y519954D01*
X1696362Y523297D01*
X1704890D01*
X1706574Y521613D01*
X1711305D01*
X1712562Y520356D01*
Y516950D01*
G01X1661000Y466050D02*
X1661213D01*
X1664713Y469550D01*
X1679250D01*
X1684719Y475019D01*
Y494147D01*
X1686542Y495970D01*
Y497217D01*
G01D02*
Y497502D01*
X1689581Y500541D01*
Y503485D01*
X1690091Y503995D01*
G01X1656611Y510789D02*
X1665311D01*
X1672275Y503825D01*
Y500151D01*
X1672606Y499820D01*
G01D02*
X1674036Y501250D01*
X1675750D01*
G01X1675350Y488400D02*
X1672450D01*
X1671050Y487000D01*
G01D02*
X1663009Y495041D01*
X1656611D01*
G01Y514726D02*
X1666000D01*
Y514725D01*
X1667725D01*
X1669050Y513400D01*
Y509750D01*
X1674250Y504550D01*
X1675750D01*
G01X1656611Y498978D02*
X1662542D01*
X1670670Y490850D01*
X1671050D01*
G01D02*
X1673050D01*
X1674000Y491800D01*
X1675450D01*
G01X1687500Y505200D02*
Y512666D01*
X1683166Y517000D01*
X1676500D01*
X1675750Y516250D01*
Y514000D01*
G01X1656611Y522600D02*
X1660407D01*
X1660833Y522174D01*
Y521568D01*
X1661258Y521143D01*
X1664901D01*
X1672853Y513191D01*
X1674941D01*
X1675750Y514000D01*
G01Y511000D02*
Y507705D01*
X1676755Y506700D01*
X1683150D01*
X1684650Y505200D01*
G01X1656611Y518663D02*
X1660409D01*
X1660833Y519087D01*
Y519693D01*
X1661258Y520118D01*
X1664476D01*
X1672428Y512166D01*
X1674584D01*
X1675750Y511000D01*
G01Y498050D02*
X1674706D01*
X1673956Y497300D01*
X1672313D01*
G01D02*
X1670400Y499213D01*
Y503100D01*
X1666648Y506852D01*
X1656611D01*
G01X1675650Y494800D02*
X1672917D01*
X1672159Y494042D01*
G01D02*
X1669325Y496876D01*
Y499675D01*
X1666085Y502915D01*
X1656611D01*
G01X1687443Y487203D02*
Y491278D01*
X1687152Y491569D01*
G01X1725133Y614896D02*
X1716993Y606756D01*
X1714573D01*
X1711969Y604152D01*
Y579367D01*
X1710389Y577787D01*
G01X1699106Y618018D02*
Y612008D01*
X1701291Y609823D01*
Y602268D01*
G01X1743503Y-5000D02*
X1743500D01*
Y2750D01*
X1745250Y4500D01*
G01X1749085Y9177D02*
X1748127D01*
X1745250Y6300D01*
Y4500D01*
G01X1716163Y3233D02*
Y4525D01*
X1716588Y4950D01*
X1734779D01*
X1740596Y10767D01*
X1743233D01*
X1744900Y9100D01*
G01X1713503Y-5000D02*
X1713500D01*
Y-1566D01*
X1716163Y1097D01*
Y3233D01*
G01X1756250Y4500D02*
Y8326D01*
X1755500Y9076D01*
G01X1743503Y-15000D02*
X1743500D01*
X1748400Y-10100D01*
Y-2100D01*
X1751200Y700D01*
X1754999D01*
X1756250Y1951D01*
Y4500D01*
G01X1745094Y52606D02*
Y55606D01*
G01Y49606D02*
Y52606D01*
G01Y47106D02*
Y49606D01*
G01X1726500Y54500D02*
X1729500D01*
G01X1723500D02*
X1726500D01*
G01X1735150Y58150D02*
X1733400Y56400D01*
X1728500D01*
X1727400Y57500D01*
X1723250D01*
G01X1726250Y60500D02*
X1723250D01*
G01D02*
Y57500D01*
G01Y63500D02*
X1726250D01*
G01X1723250Y66500D02*
Y63500D01*
G01X1725474Y69250D02*
X1725250D01*
X1723250Y67250D01*
Y66500D01*
G01X1722950Y86600D02*
X1725887D01*
X1728800Y89513D01*
X1735213D01*
X1737000Y91300D01*
X1742141D01*
X1746491Y95650D01*
G01X1760559Y51000D02*
Y53139D01*
X1761920Y54500D01*
X1767400D01*
X1769742Y56842D01*
X1778958D01*
X1785457Y63341D01*
X1786341D01*
G01X1762500Y63000D02*
Y62118D01*
X1763118Y61500D01*
Y58000D01*
G01X1762500Y63000D02*
X1782500D01*
X1784341Y64841D01*
G01X1742594Y47106D02*
X1741594Y48106D01*
Y52606D01*
G01X1748594Y49606D02*
Y48206D01*
X1749400Y47400D01*
X1750400D01*
G01X1726500Y51000D02*
Y48300D01*
X1724300Y46100D01*
X1720100D01*
G01X1723500Y51000D02*
X1721940D01*
X1720500Y52440D01*
G01X1729750Y60500D02*
Y58950D01*
X1730550Y58150D01*
X1732650D01*
G01X1716050Y67000D02*
X1717600D01*
X1718100Y66500D01*
X1719750D01*
G01X1732650Y60650D02*
X1733600Y61600D01*
Y65000D01*
G01D02*
X1731250D01*
X1729750Y63500D01*
G01X1771000Y79800D02*
Y81000D01*
X1771600Y81600D01*
X1776400D01*
G01X1762000Y79750D02*
X1757650D01*
X1756200Y78300D01*
G01X1757772Y90174D02*
X1756274D01*
X1755400Y89300D01*
Y87700D01*
G01X1718500Y79750D02*
X1721150D01*
X1721400Y79500D01*
G01X1737488Y141073D02*
X1737487D01*
X1735914Y139500D01*
G01X1724890Y141073D02*
X1726446D01*
G03X1726871Y141498I0J425D01*
G01Y142230D01*
G03X1726280Y142821I-591J0D01*
G01X1723727D01*
G03X1723314Y142650I0J-584D01*
G01X1737488Y134774D02*
Y134749D01*
X1735989Y133250D01*
G01X1772220Y150750D02*
X1777220D01*
G01X1739064Y145800D02*
X1740636Y147372D01*
X1740638D01*
G01D02*
X1740689Y147423D01*
Y148750D01*
X1742789Y150850D01*
X1747189D01*
X1749889Y153550D01*
X1760339D01*
G01D02*
X1771489D01*
X1772220Y152819D01*
Y150750D01*
G01X1728789Y136250D02*
Y134636D01*
X1728363Y134210D01*
X1727678D01*
X1727114Y134774D01*
X1724890D01*
G01X1723189Y165781D02*
X1721654Y164246D01*
Y164201D01*
X1720916Y163463D01*
Y158449D01*
X1721654Y157711D01*
Y151750D01*
G03X1723580I963J0D01*
G01Y156143D01*
G02X1725506I963J0D01*
G01Y151138D01*
X1721740Y147372D01*
G01D02*
X1721742D01*
X1723264Y145850D01*
G01X1737488Y144222D02*
Y144226D01*
X1735989Y145725D01*
Y149050D01*
G01X1724890Y137923D02*
X1725012D01*
X1726539Y139450D01*
G01X1734989Y142750D02*
X1734195Y141956D01*
Y138488D01*
X1734760Y137923D01*
X1737488D01*
G01X1721740Y141073D02*
X1721737D01*
X1720164Y139500D01*
G01X1740638Y141073D02*
Y141076D01*
X1739064Y142650D01*
G01X1720164Y145800D02*
Y148775D01*
X1719729Y149210D01*
Y156203D01*
G03X1717803I-963J0D01*
G01Y151789D01*
G02X1715877I-963J0D01*
G01Y158094D01*
X1716401Y158618D01*
Y164951D01*
X1717231Y165781D01*
X1718689D01*
G01X1721740Y144222D02*
Y144224D01*
X1720164Y145800D01*
G01X1740638Y144222D02*
Y144224D01*
X1742214Y145800D01*
G01X1777220Y146250D02*
X1772220D01*
G01X1742214Y145800D02*
Y148275D01*
X1743189Y149250D01*
X1748089D01*
X1750289Y151450D01*
X1751389D01*
X1752289Y150550D01*
Y149150D01*
X1752889Y148550D01*
X1758228D01*
G01D02*
X1771389D01*
X1772220Y147719D01*
Y146250D01*
G01X1726464Y145800D02*
X1731283Y150619D01*
Y155208D01*
G03X1729357I-963J0D01*
G01Y152399D01*
G02X1727431I-963J0D01*
G01Y157208D01*
X1725389Y159250D01*
Y163500D01*
X1725408D01*
X1727689Y165781D01*
G01X1724890Y144222D02*
Y144226D01*
X1726464Y145800D01*
G01X1772220Y136750D02*
Y138519D01*
X1771789Y138950D01*
X1759589D01*
G01X1777220Y136750D02*
X1772220D01*
G01X1740638Y137923D02*
Y137926D01*
X1739064Y139500D01*
G01X1759589Y138950D02*
X1750489D01*
X1749889Y139550D01*
Y140950D01*
X1749389Y141450D01*
X1748289D01*
X1747489Y140650D01*
Y139950D01*
X1747089Y139550D01*
X1742265D01*
X1740638Y137923D01*
G01X1721740D02*
Y137926D01*
X1723314Y139500D01*
G01X1772220Y132250D02*
X1777220D01*
G01X1739064Y136350D02*
X1740638Y134776D01*
Y134774D01*
G01D02*
X1741239Y135375D01*
Y135900D01*
X1741689Y136350D01*
X1748289D01*
X1748789Y135850D01*
Y134050D01*
X1749289Y133550D01*
X1750489D01*
X1751489Y134550D01*
X1763217D01*
G01D02*
X1771589D01*
X1772220Y133919D01*
Y132250D01*
G01X1732189Y165781D02*
X1729989Y163581D01*
Y159101D01*
X1733036Y156054D01*
Y148857D01*
X1728189Y144010D01*
Y138550D01*
X1725989Y136350D01*
X1723314D01*
X1721740Y134776D01*
Y134774D01*
G01X1740638Y128474D02*
X1739064Y126900D01*
G01X1736689Y165781D02*
X1734479Y163571D01*
Y145940D01*
X1729989Y141450D01*
Y138250D01*
X1730400Y137839D01*
Y134001D01*
X1728599Y132200D01*
X1727464D01*
X1726464Y133200D01*
G01X1724890Y131624D02*
Y131626D01*
X1726464Y133200D01*
G01X1724890Y112726D02*
Y112724D01*
X1726464Y111150D01*
G01X1740638Y119026D02*
X1739064Y120600D01*
G01X1737488Y106427D02*
Y106424D01*
X1735914Y104850D01*
G01X1724890Y106427D02*
Y106426D01*
X1723314Y104850D01*
G01X1721740Y106427D02*
X1721737D01*
X1720164Y108000D01*
G01X1737488Y109577D02*
Y109574D01*
X1735914Y108000D01*
G01X1724890Y109577D02*
Y109576D01*
X1723314Y108000D01*
G01X1737488Y122175D02*
X1739064Y123750D01*
G01X1724890Y122175D02*
X1724891D01*
X1726464Y120602D01*
Y120600D01*
G01X1740638Y122175D02*
X1740639D01*
X1742214Y120600D01*
G01X1721740Y122175D02*
X1723314Y120601D01*
G01X1737488Y125325D02*
X1735912Y123750D01*
G01X1724890Y125325D02*
Y125324D01*
X1726464Y123750D01*
G01X1721740Y103278D02*
X1721736D01*
X1720164Y104850D01*
G01X1772220Y127750D02*
X1777220D01*
G01X1731789Y139450D02*
Y138250D01*
X1733989Y136050D01*
Y132950D01*
X1735315Y131624D01*
X1737488D01*
G01D02*
X1737563D01*
X1739189Y133250D01*
X1747489D01*
X1748189Y132550D01*
Y130550D01*
X1748689Y130050D01*
X1760240D01*
G01D02*
X1771600D01*
X1772220Y129430D01*
Y127750D01*
G01X1718591Y141073D02*
X1717014Y142650D01*
G01X1737488Y128474D02*
X1739064Y130050D01*
G01X1746189Y153250D02*
X1743366D01*
X1737488Y147372D01*
G01X1721740Y131624D02*
Y131626D01*
X1723314Y133200D01*
G01X1742214Y142650D02*
X1743787Y141077D01*
Y141073D01*
G01X1772220Y141250D02*
X1777220D01*
G01X1772220D02*
Y142819D01*
X1771189Y143850D01*
X1761298D01*
G01D02*
X1749489D01*
X1749089Y144250D01*
Y146150D01*
X1748689Y146550D01*
X1747389D01*
X1747089Y146250D01*
Y142090D01*
X1746072Y141073D01*
X1743787D01*
G01X1740638Y131624D02*
X1740640D01*
X1742214Y130050D01*
G01X1777220Y123250D02*
X1772220D01*
G01X1742214Y130050D02*
X1745089D01*
X1748289Y126850D01*
Y123250D01*
X1750539Y121000D01*
X1756589D01*
G01D02*
X1771239D01*
X1772220Y121981D01*
Y123250D01*
G01X1764850Y158650D02*
X1766409D01*
X1768886Y156173D01*
G01X1719000Y190500D02*
X1718128Y189628D01*
Y188173D01*
X1719364Y186937D01*
X1721815D01*
G01X1723189Y169781D02*
Y165781D01*
G01X1718689Y169731D02*
Y165781D01*
G01X1727689D02*
Y169781D01*
G01X1732189Y165781D02*
Y169781D01*
G01X1736689Y165781D02*
Y169781D01*
G01X1714189Y165781D02*
Y167740D01*
X1714129Y167800D01*
Y169631D01*
G01X1736847Y233334D02*
Y232354D01*
X1734449Y229956D01*
Y226756D01*
G01X1737599D02*
Y231086D01*
X1739847Y233334D01*
G01X1769095Y244105D02*
Y234039D01*
X1768700Y233644D01*
G01X1756496Y226756D02*
X1756495Y226757D01*
Y231310D01*
X1754036Y233769D01*
X1750276D01*
X1749462Y232955D01*
G01X1747047Y244105D02*
Y249657D01*
X1746900Y249804D01*
G01X1750197Y244105D02*
Y247997D01*
X1751900Y249700D01*
G01X1775394Y226756D02*
Y233192D01*
X1774243Y234343D01*
X1772068D01*
X1769606Y231881D01*
X1766877D01*
X1766077Y232681D01*
G01X1742398Y234681D02*
Y232553D01*
X1740748Y230903D01*
Y226756D01*
G01X1719317Y441947D02*
X1720327Y442957D01*
Y469858D01*
X1722365Y471896D01*
Y471811D01*
X1722347D01*
G01X1734649Y441754D02*
Y448349D01*
X1737150Y450850D01*
G01X1714530Y508850D02*
X1717436D01*
X1719485Y506801D01*
Y506800D01*
X1719486D01*
G01X1773471Y561455D02*
X1779943D01*
X1780394Y561004D01*
Y561076D01*
G01X1772300Y586870D02*
X1777630D01*
X1779000Y585500D01*
G01X1773471Y558895D02*
X1769195D01*
X1767800Y557500D01*
X1763700D01*
X1761200Y555000D01*
Y549300D01*
X1760092Y548192D01*
X1757478D01*
G01X1722500Y562000D02*
Y571900D01*
X1724723Y574123D01*
X1730814D01*
G01X1722500Y562000D02*
Y557368D01*
X1724768Y555100D01*
X1727600D01*
G01X1773471Y564015D02*
X1780015D01*
X1781000Y565000D01*
G01X1772300Y581750D02*
X1777250D01*
X1779500Y579500D01*
G01X1773471Y556335D02*
X1781865D01*
X1782300Y555900D01*
G01X1773471Y566575D02*
X1779075D01*
X1780500Y568000D01*
G01X1773471Y569135D02*
X1778917D01*
X1780500Y570718D01*
G01X1779400Y582500D02*
X1779200D01*
X1777390Y584310D01*
X1772300D01*
G01X1742381Y588530D02*
X1744041Y586870D01*
X1748800D01*
G01X1780756Y573490D02*
X1771193D01*
X1770719Y573964D01*
G01X1743000Y570000D02*
X1745000Y568000D01*
Y567000D01*
X1745425Y566575D01*
X1749971D01*
G01X1743000Y570000D02*
X1741400Y568400D01*
Y563825D01*
X1740575Y563000D01*
X1739000D01*
G01X1761680Y604490D02*
Y596320D01*
X1765500Y592500D01*
Y577800D01*
X1767200Y576100D01*
Y573800D01*
X1766200Y572800D01*
X1762925D01*
X1762500Y572375D01*
Y564800D01*
X1767500Y559800D01*
G01X1739000Y566000D02*
Y568499D01*
X1742201Y571700D01*
X1743799D01*
X1746364Y569135D01*
X1749971D01*
G01X1765300Y574700D02*
X1764900Y574300D01*
X1760800D01*
X1755635Y569135D01*
X1749971D01*
G01X1733096Y588640D02*
Y585496D01*
X1731124Y583524D01*
G01D02*
X1727400Y579800D01*
Y577500D01*
X1728218Y576682D01*
X1730814D01*
G01X1738498Y554255D02*
X1740272D01*
X1744912Y558895D01*
X1749971D01*
G01X1736000Y554000D02*
X1738243D01*
X1738498Y554255D01*
G01X1756500Y554500D02*
Y560215D01*
X1755260Y561455D01*
X1749971D01*
G01X1738697Y557888D02*
X1741783D01*
X1745350Y561455D01*
X1749971D01*
G01X1729700Y564500D02*
X1728000D01*
X1725694Y566806D01*
Y568814D01*
G01X1729700Y564500D02*
X1732000D01*
X1733700Y566200D01*
Y570400D01*
X1734864Y571564D01*
X1737814D01*
G01X1746986Y603249D02*
X1750351D01*
X1750399Y603201D01*
G01X1730728Y604617D02*
X1739364D01*
X1739714Y604967D01*
G01X1772300Y594550D02*
X1780350D01*
X1788300Y586600D01*
Y585100D01*
G01X1736245Y594742D02*
X1739947D01*
X1740270Y594419D01*
G01X1724041Y596711D02*
X1723983Y596653D01*
X1718568D01*
X1718037Y597184D01*
G01X1772300Y589430D02*
X1778070D01*
X1779000Y588500D01*
G01X1743486Y607088D02*
Y603249D01*
G01D02*
X1738916Y598679D01*
X1736245D01*
G01X1727112Y600844D02*
Y603000D01*
X1727228Y603116D01*
Y604617D01*
G01D02*
Y608629D01*
X1727666Y609067D01*
G01X1724041Y594742D02*
X1723983Y594684D01*
X1718037D01*
G01X1772300Y591990D02*
X1778405D01*
X1778639Y592224D01*
X1778675D01*
G01X1736245Y590805D02*
X1738008D01*
X1738434Y590379D01*
Y588986D01*
G01X1733096Y588640D02*
X1735607D01*
X1736003Y588244D01*
G01X1728341Y614851D02*
X1719043Y605553D01*
X1715714D01*
X1713546Y603385D01*
Y592742D01*
X1715461Y590827D01*
Y590723D01*
G01D02*
X1716317D01*
X1716909Y590131D01*
X1718631D01*
X1719305Y590805D01*
X1724041D01*
G01X1728341Y614851D02*
Y617959D01*
G01X1739179Y592070D02*
X1738476Y592773D01*
X1736245D01*
G01X1748800Y594550D02*
X1753600D01*
X1754300Y595250D01*
Y605268D01*
G01X1765180Y604490D02*
Y606730D01*
X1763294Y608616D01*
X1755617D01*
X1754300Y607299D01*
Y605268D01*
G01X1825507Y30668D02*
Y33693D01*
X1821875Y37325D01*
X1819790D01*
X1817186Y39929D01*
G01X1828874Y-11100D02*
Y-13520D01*
G01D02*
X1828394Y-14000D01*
X1826945D01*
X1825756Y-12811D01*
Y-9845D01*
X1827061Y-8540D01*
X1828874D01*
G01X1825507Y17268D02*
Y21224D01*
X1825870Y21587D01*
G01X1819837Y21700D02*
Y24681D01*
X1822357Y27201D01*
Y30668D01*
G01X1825324Y1000D02*
X1826500Y2176D01*
Y3999D01*
X1827901Y5400D01*
X1830099D01*
X1831299Y4200D01*
X1833100D01*
G01Y7700D02*
X1828001D01*
X1824564Y4263D01*
Y3441D01*
G01X1808000Y6000D02*
Y8697D01*
X1808603Y9300D01*
G01D02*
X1809603Y10300D01*
X1814400D01*
X1815800Y11700D01*
X1817514D01*
X1819207Y13393D01*
Y17268D01*
G01X1819000Y6000D02*
Y7504D01*
X1816723Y9781D01*
G01D02*
X1817482D01*
X1822357Y14656D01*
Y17268D01*
G01X1795696Y6061D02*
Y1399D01*
X1799504Y-2409D01*
Y-5000D01*
G01X1827100Y81600D02*
X1828250Y80450D01*
X1829900D01*
G01X1793852Y85063D02*
X1795647D01*
X1798445Y82265D01*
Y82256D01*
X1798454D01*
G01X1832830Y76430D02*
X1833210D01*
G01X1833530D02*
X1836750Y79650D01*
Y81300D01*
G01X1824350Y94450D02*
Y91650D01*
G01X1829550Y90850D02*
X1827150D01*
X1826350Y91650D01*
X1824350D01*
G01Y94450D02*
X1822500D01*
X1821350Y95600D01*
Y98270D01*
G01X1833000Y83950D02*
X1829900D01*
G01X1833000Y87500D02*
X1834684D01*
X1836359Y89175D01*
X1838400D01*
G01X1833000Y83950D02*
Y87500D01*
G01X1838400Y90750D02*
X1833150D01*
X1833050Y90850D01*
G01Y94550D02*
Y90850D01*
G01X1795495Y136789D02*
Y134506D01*
X1796001Y134000D01*
X1798953D01*
X1801492Y136539D01*
X1802485D01*
G01X1803509Y128500D02*
Y130237D01*
X1802485Y131261D01*
Y136539D01*
G01X1807818Y124179D02*
X1808400Y123597D01*
Y120800D01*
G01X1811900Y121000D02*
Y122800D01*
X1813118Y124018D01*
Y127976D01*
G01X1793000Y130059D02*
X1789059D01*
X1788000Y129000D01*
G01D02*
Y126750D01*
X1788250Y126500D01*
G01X1812700Y133277D02*
X1815883D01*
G01X1787500Y149000D02*
Y147350D01*
X1787000Y146850D01*
Y143500D01*
G01X1798055Y136789D02*
Y139444D01*
X1797499Y140000D01*
X1791425D01*
X1791000Y139575D01*
Y136500D01*
X1790000Y135500D01*
X1787000D01*
G01X1827500Y144900D02*
Y141980D01*
X1826270Y140750D01*
X1820760D01*
X1819348Y142162D01*
Y145937D01*
G01X1798510Y108000D02*
Y105255D01*
X1798935Y104830D01*
X1801819D01*
X1803559Y106570D01*
X1804720D01*
G01X1812743Y104395D02*
X1810938Y106200D01*
X1807400D01*
X1807030Y106570D01*
X1804720D01*
G01X1792935Y143789D02*
Y146919D01*
X1793000Y146984D01*
Y149000D01*
G01X1795495Y143789D02*
Y141425D01*
X1795070Y141000D01*
X1793331D01*
X1792935Y141396D01*
Y143789D01*
G01X1793000Y149000D02*
X1795920D01*
X1797720Y150800D01*
G01X1819348Y149437D02*
X1815348D01*
G01X1811348D02*
Y154063D01*
X1812848Y155563D01*
G01X1811348Y149437D02*
X1810411D01*
X1809503Y148529D01*
Y146760D01*
X1806400Y143657D01*
G01X1815348Y149437D02*
X1811348D01*
G01X1798510Y115000D02*
Y117414D01*
X1799034Y117938D01*
X1802087D01*
X1802750Y118601D01*
Y120000D01*
G01X1795950Y115000D02*
Y112532D01*
X1796239Y112243D01*
X1798209D01*
X1798510Y112544D01*
Y115000D01*
G01X1809867Y126371D02*
X1807071D01*
X1802750Y122050D01*
Y120000D01*
G01X1790250D02*
Y118750D01*
X1791000Y118000D01*
Y115500D01*
G01D02*
X1785900D01*
X1784100Y117300D01*
G01X1809900Y108500D02*
X1803600D01*
X1803100Y108000D01*
X1801070D01*
G01X1791000Y108500D02*
X1793500D01*
X1794000Y109000D01*
Y110144D01*
X1794745Y110889D01*
X1800624D01*
X1801070Y110443D01*
Y108000D01*
G01X1787373Y120188D02*
Y121894D01*
X1790192Y124713D01*
Y126415D01*
X1791277Y127500D01*
X1800000D01*
G01X1777220Y141250D02*
X1780182Y144212D01*
X1781712D01*
X1783500Y146000D01*
Y155500D01*
X1786000Y158000D01*
G01Y161500D02*
Y163500D01*
X1785500Y164000D01*
G01X1828937Y226756D02*
Y232835D01*
X1828936Y232836D01*
X1830675Y234575D01*
X1834907D01*
X1835936Y235604D01*
G01X1832087Y226756D02*
X1834656D01*
X1836900Y229000D01*
Y232700D01*
G01X1794292Y226756D02*
X1794291Y226757D01*
Y231909D01*
X1793700Y232500D01*
G01X1797441Y226756D02*
X1797440Y226757D01*
Y231260D01*
X1793600Y235100D01*
G01X1822877Y235852D02*
X1817545D01*
X1813189Y231496D01*
Y226756D01*
G01X1826085Y236034D02*
X1824706Y234655D01*
X1824705D01*
X1824186Y234136D01*
X1817921D01*
X1816339Y232554D01*
Y226756D01*
G01X1822638Y244105D02*
Y249036D01*
X1822637Y249037D01*
X1824300Y250700D01*
Y251800D01*
G01X1825788Y244105D02*
Y249501D01*
X1826287Y250000D01*
G01X1822638Y232106D02*
Y226756D01*
G01X1825788D02*
Y231315D01*
X1825787Y231316D01*
X1826662Y232191D01*
G01X1778543Y226756D02*
Y232325D01*
X1780016Y233798D01*
X1783580D01*
X1784440Y232938D01*
G01X1803740Y244105D02*
X1803739Y244106D01*
Y249255D01*
X1804388Y249904D01*
G01X1832087Y244105D02*
X1832086Y244106D01*
Y250000D01*
X1831700Y250386D01*
Y252272D01*
G01X1810052Y545103D02*
X1814115Y541040D01*
Y530715D01*
X1811600Y528200D01*
Y526900D01*
X1810350Y525650D01*
G01D02*
X1806699Y529301D01*
X1803752D01*
G01X1810200Y513300D02*
X1815050D01*
X1818250Y510100D01*
Y500430D01*
X1832269Y486411D01*
Y480731D01*
X1837300Y475700D01*
Y472276D01*
G01X1822758Y534330D02*
X1827770D01*
X1828400Y533700D01*
Y528400D01*
X1825900Y525900D01*
Y523500D01*
G01X1800207Y538267D02*
X1795370D01*
X1794945Y537842D01*
Y528519D01*
X1797013Y526451D01*
Y521058D01*
X1798300Y519771D01*
X1810971D01*
X1812914Y521714D01*
X1825122D01*
X1825149Y521687D01*
X1828077D01*
X1831177Y518587D01*
Y518206D01*
X1835409Y513974D01*
Y500508D01*
X1834014Y499113D01*
X1832949D01*
X1831887Y498051D01*
Y493855D01*
X1836396Y489346D01*
Y481349D01*
G01X1833700Y497300D02*
X1835426D01*
X1837237Y499111D01*
Y503574D01*
X1837325Y503662D01*
Y514463D01*
X1832877Y518911D01*
Y519292D01*
X1831600Y520569D01*
Y529000D01*
G01X1822757Y587480D02*
X1816458D01*
G01X1829300Y572900D02*
X1829000D01*
X1828200Y573700D01*
X1822757D01*
G01X1793100Y578500D02*
X1793401D01*
X1794507Y579606D01*
X1800206D01*
G01X1816020Y571448D02*
X1814410Y569838D01*
Y566792D01*
X1807539Y559921D01*
X1800207D01*
G01X1812802Y578693D02*
X1812985Y578510D01*
Y567085D01*
X1807789Y561889D01*
X1800207D01*
G01X1840690Y557190D02*
X1839809Y558071D01*
X1830768D01*
X1829513Y559326D01*
X1829474D01*
X1828879Y559921D01*
X1822758D01*
G01X1837534Y579322D02*
X1837462Y579250D01*
X1835000D01*
G01D02*
X1832251D01*
X1830638Y577637D01*
X1822757D01*
G01X1792805Y574675D02*
X1792827D01*
X1795789Y577637D01*
X1800206D01*
G01X1800207Y554015D02*
X1809283D01*
X1812952Y550346D01*
Y545501D01*
G01X1794000Y552800D02*
Y554900D01*
X1795084Y555984D01*
X1800207D01*
G01X1832500Y539500D02*
X1832000D01*
X1831700Y539200D01*
X1830700D01*
X1829767Y538267D01*
X1822758D01*
G01X1818509Y527893D02*
Y532468D01*
X1817101Y533876D01*
Y537550D01*
X1817834Y538283D01*
X1817850Y538267D01*
X1822758D01*
G01X1829000Y536315D02*
X1828984Y536299D01*
X1822758D01*
G01X1822757Y571732D02*
X1827968D01*
X1828600Y571100D01*
X1829653D01*
X1830876Y569877D01*
Y569084D01*
X1832200Y567760D01*
G01D02*
X1833280Y568840D01*
Y570500D01*
G01X1791349Y589122D02*
X1793579D01*
X1795221Y587480D01*
X1800206D01*
G01Y583543D02*
X1795109D01*
X1794041Y582475D01*
X1793974D01*
X1793500Y582001D01*
X1790100D01*
X1788300Y583801D01*
Y585100D01*
G01X1792170Y583900D02*
X1793450D01*
X1795061Y585511D01*
X1800206D01*
G01Y575669D02*
X1795669D01*
X1794776Y574776D01*
G01X1829176Y584287D02*
X1828522D01*
X1827298Y585511D01*
X1822757D01*
G01Y583543D02*
X1816610D01*
X1816052Y584101D01*
G01X1835000Y582750D02*
X1833473D01*
X1831184Y580461D01*
X1828592D01*
X1827737Y579606D01*
X1822757D01*
G01X1839126Y583354D02*
X1837006D01*
X1836402Y582750D01*
X1835000D01*
G01X1822758Y544173D02*
X1831173D01*
X1831500Y544500D01*
G01Y548000D02*
X1831337Y548163D01*
X1822811D01*
X1822758Y548110D01*
G01Y550078D02*
X1829578D01*
X1831800Y552300D01*
G01X1836000Y539500D02*
Y542200D01*
X1834200Y544000D01*
Y549500D01*
X1835000Y550300D01*
G01X1834000Y529000D02*
X1840000D01*
G01X1834000D02*
X1831600D01*
G01X1819654Y593803D02*
X1819443D01*
X1818445Y594801D01*
X1814601D01*
X1813301Y593501D01*
X1800404D01*
X1800378Y593527D01*
G01X1805500Y603100D02*
Y598649D01*
X1800378Y593527D01*
G01X1782700Y610900D02*
X1782100Y611500D01*
Y619100D01*
X1786000Y623000D01*
X1798600D01*
X1800200Y621400D01*
Y617100D01*
X1799222Y616122D01*
X1796240D01*
X1795500Y615382D01*
G01X1829051Y591299D02*
X1827200Y589448D01*
X1822757D01*
G01X1829051Y591299D02*
Y602578D01*
X1821529Y610100D01*
X1801700D01*
X1798000Y613800D01*
X1796400D01*
X1795500Y614700D01*
Y615382D01*
G01X1800206Y591417D02*
X1795746D01*
X1795000Y592163D01*
Y599600D01*
G01X1791323Y594030D02*
Y593394D01*
X1795269Y589448D01*
X1800206D01*
G01X1788290Y612006D02*
X1786058D01*
X1784000Y614064D01*
Y618000D01*
X1786500Y620500D01*
X1788500D01*
G01Y617941D02*
X1786441D01*
X1785500Y617000D01*
Y614695D01*
X1786226Y613969D01*
X1789031D01*
X1790000Y613000D01*
Y610500D01*
X1788500Y609000D01*
X1780543D01*
G01X1788500Y617941D02*
X1795500D01*
G01D02*
X1798041D01*
X1798500Y618400D01*
Y620000D01*
X1798000Y620500D01*
X1795500D01*
G01X1780543Y609000D02*
X1778500D01*
X1776500Y607000D01*
Y604500D01*
G01X1779000Y588500D02*
X1782000D01*
G01X1784200Y593924D02*
Y592999D01*
X1785699Y591500D01*
X1787500D01*
G01X1838500Y40400D02*
X1839400Y39500D01*
Y34466D01*
X1841257Y32609D01*
Y30668D01*
G01X1856333Y34518D02*
Y34864D01*
X1853017Y38180D01*
X1845744D01*
X1844407Y36843D01*
Y30668D01*
G01X1837500Y35700D02*
Y35170D01*
X1838107Y34563D01*
Y30668D01*
G01X1840400Y9700D02*
X1841257Y10557D01*
Y17268D01*
G01X1845420Y13310D02*
X1844407Y14323D01*
Y17268D01*
G01X1838850Y13160D02*
Y13750D01*
X1838107Y14493D01*
Y17268D01*
G01X1837100Y-15700D02*
Y-18500D01*
X1836700Y-18900D01*
G01X1837100Y-15700D02*
Y-13787D01*
X1838542Y-12345D01*
Y-10700D01*
X1838537Y-10695D01*
Y-10286D01*
X1838376Y-9476D01*
X1837440Y-8540D01*
X1835874D01*
G01X1895354Y75650D02*
X1902588D01*
X1903648Y76710D01*
G01X1893750Y122480D02*
X1898323D01*
X1899495Y121308D01*
Y120075D01*
X1900290Y119280D01*
G01X1893750Y116570D02*
X1899000D01*
X1900290Y115280D01*
G01X1874600Y133750D02*
Y140762D01*
G01D02*
Y142001D01*
X1875500Y142901D01*
Y144250D01*
G01X1854868Y184667D02*
X1852537Y182336D01*
Y175911D01*
X1855459Y172989D01*
X1856489D01*
X1859563Y169915D01*
Y165067D01*
X1859567Y165063D01*
Y163685D01*
X1859563Y163681D01*
Y157037D01*
X1861000Y155600D01*
X1872700D01*
X1873707Y154593D01*
X1879605D01*
X1880001Y154989D01*
X1882266D01*
X1882849Y154406D01*
X1882915D01*
X1883153Y154168D01*
Y151304D01*
X1881500Y149651D01*
Y147750D01*
G01X1882480Y133750D02*
Y137028D01*
X1882743Y137291D01*
Y139957D01*
X1881700Y141000D01*
G01X1881500Y144250D02*
Y141200D01*
X1881700Y141000D01*
G01X1876570Y133750D02*
Y138450D01*
X1877111Y138991D01*
Y140638D01*
X1878500Y142027D01*
Y144250D01*
G01X1888390Y109250D02*
Y106337D01*
X1887497Y105444D01*
G01X1882480Y109250D02*
Y106876D01*
X1881165Y105561D01*
G01D02*
X1880510Y106216D01*
Y109250D01*
G01X1885102Y101134D02*
Y105699D01*
X1886420Y107017D01*
Y109250D01*
G01X1882528Y102739D02*
X1883188Y103399D01*
Y105756D01*
X1884450Y107018D01*
Y109250D01*
G01X1877372Y102673D02*
X1878540Y103841D01*
Y109250D01*
G01X1876570D02*
Y106007D01*
X1876001Y105438D01*
G01X1893750Y128390D02*
X1896114D01*
X1897149Y127355D01*
X1897165D01*
X1897420Y127100D01*
X1900200D01*
G01X1869250Y112630D02*
X1867032D01*
X1866606Y112204D01*
Y109967D01*
G01X1857020Y129619D02*
X1858800Y127839D01*
Y123890D01*
X1859500Y123190D01*
Y120500D01*
G01X1857020Y126619D02*
X1857810Y125829D01*
Y118190D01*
X1858500Y117500D01*
X1859500D01*
G01X1870000Y144250D02*
X1872031D01*
X1872400Y144619D01*
G01X1868100Y149700D02*
X1866500Y148100D01*
Y144250D01*
G01X1871521Y153593D02*
X1869700Y151772D01*
Y151300D01*
X1868100Y149700D01*
G01X1878096Y152843D02*
Y149548D01*
X1878500Y149144D01*
Y147750D01*
G01X1870000Y140750D02*
Y138600D01*
X1869600Y138200D01*
X1868541D01*
G01D02*
X1867251D01*
X1865500Y136449D01*
Y132412D01*
X1865748Y132164D01*
Y132123D01*
X1866150Y131721D01*
Y129049D01*
X1866809Y128390D01*
X1869250D01*
G01Y126420D02*
X1866929D01*
X1864804Y128545D01*
Y129771D01*
X1862632Y131943D01*
Y137382D01*
X1863358Y138108D01*
G01D02*
X1864875Y139625D01*
X1865375D01*
X1866500Y140750D01*
G01X1861932Y146431D02*
X1859931Y148432D01*
Y149754D01*
X1859337Y150348D01*
X1854637D01*
G01X1862500Y150000D02*
Y146999D01*
X1861932Y146431D01*
G01X1869668Y146750D02*
Y146930D01*
X1871738Y149000D01*
X1872928D01*
X1874178Y147750D01*
X1875500D01*
G01X1893750Y124450D02*
X1897507D01*
G01X1888870Y140100D02*
Y142370D01*
X1891350Y144850D01*
G01X1888390Y133750D02*
Y137790D01*
X1888870Y138270D01*
Y140100D01*
G01X1869250Y116570D02*
X1867430D01*
X1865500Y118500D01*
Y119500D01*
X1864500Y120500D01*
X1863000D01*
G01X1869250Y114600D02*
X1867400D01*
X1864500Y117500D01*
X1863000D01*
G01X1893750Y130360D02*
X1897400D01*
X1897760Y130000D01*
X1900200D01*
G01X1889300Y164242D02*
X1884508D01*
X1882650Y166100D01*
G01X1875900Y162350D02*
X1877650D01*
X1877900Y162600D01*
X1879150D01*
G01X1870050Y159966D02*
X1872362D01*
X1874746Y162350D01*
X1875900D01*
G01X1889300Y162273D02*
X1887828D01*
X1887101Y163000D01*
X1883050D01*
X1882650Y162600D01*
G01X1836100Y179700D02*
X1836800D01*
X1838346Y181246D01*
Y186937D01*
X1838350D01*
G01X1840900Y179700D02*
Y186337D01*
X1841500Y186937D01*
G01X1845700Y179700D02*
X1844650Y180750D01*
Y186937D01*
G01X1896710Y194380D02*
Y194140D01*
X1897642Y193208D01*
Y190300D01*
G01X1881400Y177850D02*
Y175832D01*
X1882548Y174684D01*
G01D02*
X1883329Y173903D01*
X1884680D01*
X1885102Y174325D01*
X1886948D01*
X1887189Y174084D01*
X1889300D01*
G01Y158336D02*
X1887600D01*
Y158300D01*
X1886000Y156700D01*
G01D02*
X1883800D01*
X1882958Y157542D01*
Y157984D01*
X1882650Y158292D01*
Y159100D01*
G01X1893705Y190300D02*
Y192395D01*
X1890830Y195270D01*
Y198140D01*
X1891958Y199268D01*
X1891990D01*
X1892791Y200069D01*
G01X1895100Y201770D02*
Y200020D01*
X1893586Y198506D01*
Y196570D01*
G01X1895673Y190300D02*
Y192178D01*
X1893586Y194265D01*
Y196570D01*
G01X1895614Y204785D02*
X1895026D01*
X1887737Y197496D01*
Y196600D01*
G01X1889300Y187864D02*
Y188736D01*
X1887737Y190299D01*
Y196600D01*
G01X1875900Y165350D02*
X1873750D01*
X1872800Y164400D01*
X1867584D01*
X1863750Y168234D01*
G01X1879150Y166100D02*
X1877800D01*
X1877050Y165350D01*
X1875900D01*
G01X1861243Y183100D02*
Y183664D01*
X1861757Y184178D01*
Y201757D01*
X1865940Y205940D01*
X1870140D01*
X1872100Y207900D01*
G01X1889300Y185895D02*
X1887205D01*
X1885000Y188100D01*
X1884000D01*
G01X1889300Y181958D02*
X1887543D01*
X1885801Y183700D01*
X1884400D01*
G01X1879150Y169100D02*
Y171050D01*
X1879880Y171780D01*
Y173320D01*
X1873600Y179600D01*
X1859463D01*
X1858686Y180377D01*
G01X1889300Y168179D02*
X1885822D01*
X1884313Y169688D01*
Y170903D01*
X1874116Y181100D01*
X1860960D01*
X1860623Y181437D01*
X1860554D01*
X1859580Y182411D01*
Y182480D01*
X1859563Y182497D01*
Y184043D01*
X1860332Y184812D01*
Y198268D01*
X1858500Y200100D01*
G01X1864000Y184900D02*
Y186500D01*
X1867500Y190000D01*
Y200650D01*
X1874000Y207150D01*
Y208724D01*
X1877028Y211752D01*
X1882116D01*
X1883800Y213436D01*
G01X1889300Y183927D02*
X1887173D01*
X1884951Y186149D01*
X1883350D01*
X1881400Y188099D01*
Y189350D01*
G01X1864000Y184900D02*
X1865400D01*
X1868250Y187750D01*
X1876900D01*
X1878500Y189350D01*
X1881400D01*
G01X1885465Y166285D02*
X1882650Y169100D01*
G01X1889300Y166210D02*
X1885540D01*
X1885465Y166285D01*
G01X1847000Y198600D02*
Y199686D01*
X1845387Y201299D01*
Y203499D01*
X1844650Y204236D01*
G01X1865100Y174600D02*
X1864200Y175500D01*
X1860200D01*
X1856806Y178894D01*
Y183302D01*
X1858907Y185403D01*
Y196951D01*
X1856837Y199021D01*
Y200789D01*
X1867382Y211334D01*
X1874224D01*
X1876660Y213770D01*
Y215181D01*
X1877517Y216038D01*
Y217988D01*
G01X1870082Y460603D02*
X1870092Y465920D01*
Y465930D01*
X1868167Y467855D01*
G01X1863137Y452710D02*
Y449802D01*
X1860633Y447298D01*
Y441754D01*
G01X1859059Y448076D02*
X1858275D01*
X1857480Y447281D01*
Y441758D01*
X1857484Y441754D01*
G01X1858633Y452803D02*
X1860630Y454800D01*
X1872400D01*
X1873232Y455632D01*
Y460603D01*
G01X1872860Y450550D02*
X1876382Y447028D01*
Y441754D01*
G01X1873232D02*
Y447578D01*
X1872860Y447950D01*
G01X1863000Y480000D02*
X1862496Y479496D01*
Y476401D01*
X1863247Y475650D01*
Y469637D01*
X1866933Y465951D01*
Y460603D01*
G01X1859600Y476200D02*
X1861388D01*
X1862322Y475266D01*
Y469179D01*
X1863783Y467718D01*
Y460603D01*
G01X1870815Y453022D02*
X1870082Y452289D01*
Y441754D01*
G01X1875900Y453600D02*
Y450048D01*
X1877411Y448537D01*
X1878663D01*
X1879531Y447669D01*
Y441754D01*
G01X1876382Y460603D02*
Y461455D01*
X1876381Y461456D01*
X1876414Y470785D01*
X1876945Y471316D01*
G01X1879531Y460603D02*
X1879527D01*
Y476926D01*
X1877407Y479046D01*
G01X1854334Y460603D02*
Y466334D01*
X1857450Y469450D01*
Y473654D01*
G01X1851185Y460603D02*
Y467091D01*
X1855206Y471112D01*
G01X1866933Y441754D02*
Y447333D01*
X1867500Y447900D01*
G01X1838900Y498800D02*
X1841900D01*
G01X1919510Y475100D02*
X1917935Y476675D01*
X1910856D01*
X1905873Y481658D01*
X1864658D01*
X1863000Y480000D01*
G01X1919510Y479200D02*
X1917966Y477656D01*
X1911184D01*
X1906157Y482683D01*
X1862549D01*
X1859600Y479734D01*
Y476200D01*
G01X1838900Y502300D02*
X1842700D01*
X1845778Y505378D01*
X1851504D01*
G01Y497504D02*
X1857996D01*
X1860000Y495500D01*
G01X1840000Y526000D02*
X1841299D01*
X1841835Y526536D01*
Y527207D01*
X1842764Y528136D01*
G01D02*
X1844900Y526000D01*
Y521600D01*
X1845374Y521126D01*
X1851504D01*
G01X1839000Y509500D02*
X1844220D01*
X1844490Y509230D01*
G01X1839000Y513000D02*
X1839430D01*
X1841300Y511130D01*
X1844570D01*
X1846692Y513252D01*
X1851504D01*
G01X1868204D02*
X1874748D01*
X1876400Y511600D01*
Y500265D01*
X1875973Y499838D01*
G01X1908300Y514500D02*
X1902300D01*
X1899200Y517600D01*
Y520600D01*
X1894385Y525415D01*
X1892720D01*
G01X1862500Y574250D02*
X1864450D01*
X1865100Y574900D01*
Y590900D01*
X1866920Y592720D01*
X1875020D01*
X1883600Y601300D01*
Y604716D01*
X1884643Y605759D01*
Y619175D01*
X1889833Y624365D01*
X1961517D01*
X1965400Y620482D01*
Y619500D01*
G01X1851250Y584622D02*
X1853122Y582750D01*
X1862500D01*
G01D02*
Y577750D01*
G01X1862000Y569750D02*
X1852126D01*
X1851250Y568874D01*
G01X1875850Y567200D02*
X1871637Y571413D01*
X1855587D01*
X1855050Y571950D01*
X1844650D01*
X1843200Y570500D01*
X1840250D01*
X1840129Y570379D01*
X1838627D01*
X1838506Y570500D01*
X1836780D01*
G01X1868000Y584250D02*
Y586800D01*
X1866800Y588000D01*
G01X1880750Y562500D02*
X1879300D01*
X1878875Y562925D01*
Y565475D01*
G01X1884250Y562500D02*
Y560200D01*
X1883000Y558950D01*
Y557160D01*
G01Y552040D02*
X1885789D01*
X1886800Y553051D01*
Y556300D01*
X1887660Y557160D01*
X1890400D01*
G01X1897300Y548800D02*
X1894060Y552040D01*
X1890400D01*
G01X1886440Y575700D02*
Y573060D01*
X1887500Y572000D01*
X1891000D01*
X1891560Y571440D01*
Y568300D01*
G01X1886440D02*
Y562925D01*
X1886865Y562500D01*
X1888250D01*
G01X1882300Y565550D02*
X1885050Y568300D01*
X1886440D01*
G01X1885100Y584300D02*
X1887500Y581900D01*
X1890600D01*
X1891560Y580940D01*
Y575700D01*
G01X1885100Y584300D02*
X1873200D01*
X1871100Y586400D01*
G01X1868000Y580750D02*
Y578200D01*
X1867400Y577600D01*
Y574350D01*
G01X1873510Y552500D02*
Y554890D01*
X1873100Y555300D01*
X1871300D01*
X1870950Y554950D01*
Y552500D01*
G01X1864750Y549500D02*
X1870500D01*
X1870950Y549950D01*
Y552500D01*
G01X1890660Y540663D02*
X1893349D01*
X1894512Y539500D01*
X1896450D01*
G01X1882660Y540663D02*
X1878697D01*
X1876070Y543290D01*
Y545500D01*
G01X1864750Y545000D02*
X1868250Y548500D01*
X1873200D01*
X1873510Y548190D01*
Y545500D01*
G01D02*
Y541710D01*
G01X1875600Y588500D02*
X1875721Y588379D01*
X1878678D01*
X1878996Y588061D01*
X1881806D01*
G01X1840000Y532500D02*
X1841648D01*
X1845148Y529000D01*
X1851504D01*
G01X1837000Y534900D02*
X1838559Y536459D01*
Y539500D01*
G01X1887100Y546100D02*
X1889600Y548600D01*
X1894600D01*
X1896200Y547000D01*
X1898248D01*
X1899348Y548100D01*
X1899800D01*
G01X1961700Y616700D02*
X1963700Y618700D01*
Y620166D01*
X1960509Y623357D01*
X1890841D01*
X1886074Y618590D01*
Y605174D01*
X1885025Y604125D01*
Y601175D01*
X1875350Y591500D01*
X1872700D01*
X1871100Y589900D01*
G01X1881806Y591561D02*
Y596206D01*
X1886200Y600600D01*
Y603284D01*
X1887000Y604084D01*
Y617500D01*
X1891932Y622432D01*
X1959418D01*
X1961700Y620150D01*
Y619500D01*
G01X1923300Y94300D02*
X1922800Y93800D01*
Y90900D01*
G01X1916094Y103696D02*
X1920307D01*
X1921139Y104528D01*
Y105424D01*
G01X1924100Y127700D02*
X1919409Y123009D01*
Y106338D01*
X1920323Y105424D01*
X1921139D01*
G01X1927810Y123544D02*
X1924100Y127254D01*
Y127700D01*
G01X1923800Y151000D02*
X1923523Y150723D01*
X1921189D01*
X1919451Y152461D01*
Y155744D01*
X1919295Y155900D01*
G01X1917327D02*
Y154173D01*
X1918400Y153100D01*
Y152100D01*
X1919484Y151016D01*
Y149500D01*
G01X1914690Y152580D02*
Y152940D01*
X1914610Y153020D01*
Y153037D01*
X1913390Y154257D01*
Y155900D01*
G01X1927000Y152200D02*
X1928400Y153600D01*
X1931500D01*
G01X1923700Y158336D02*
Y155800D01*
X1926100Y153400D01*
Y153100D01*
X1927000Y152200D01*
G01X1900200Y127100D02*
X1901542D01*
X1902709Y128267D01*
X1908225D01*
X1911750Y124742D01*
G01X1897640Y136600D02*
X1900200Y134040D01*
Y133500D01*
G01X1905450Y133010D02*
X1901860Y136600D01*
X1897640D01*
G01X1903790Y119280D02*
X1905120D01*
X1906180Y120340D01*
X1908280D01*
X1909620Y119000D01*
Y117370D01*
G01D02*
X1908986Y118004D01*
X1906414D01*
G01X1906467Y115305D02*
X1903815D01*
X1903790Y115280D01*
G01X1923700Y160305D02*
X1925617D01*
X1926952Y158970D01*
Y156049D01*
G01X1955426Y102580D02*
X1953096D01*
X1952726Y102950D01*
G01X1925097Y111920D02*
X1928930D01*
X1931250Y114240D01*
G01X1921144Y111844D02*
X1925021D01*
X1925097Y111920D01*
G01X1921139Y108924D02*
Y111839D01*
X1921144Y111844D01*
G01X1931250Y114240D02*
Y117690D01*
X1932998Y119438D01*
G01X1912894Y103646D02*
Y102090D01*
X1913319Y101665D01*
X1919645D01*
X1920740Y102760D01*
X1925040D01*
X1925300Y102500D01*
G01D02*
Y101446D01*
X1923329Y99475D01*
G01X1929377Y118916D02*
Y119275D01*
X1931800Y121698D01*
Y128500D01*
X1935589Y132289D01*
X1941656Y134800D01*
X1943900D01*
X1945415Y136315D01*
Y139989D01*
X1947000Y141574D01*
Y142600D01*
G01X1929377Y118916D02*
X1925881Y115420D01*
X1925097D01*
G01X1915358Y155900D02*
Y154642D01*
X1916526Y153474D01*
Y149892D01*
X1916310Y149676D01*
G01X1919702Y128501D02*
X1918201D01*
X1916765Y127065D01*
Y122342D01*
X1918017Y121090D01*
Y108222D01*
X1916991Y107196D01*
X1916094D01*
G01Y110696D02*
X1912944D01*
X1912894Y110646D01*
G01X1915854Y118600D02*
X1914200D01*
X1911300Y115700D01*
Y112240D01*
X1912894Y110646D01*
G01X1926892Y121203D02*
X1926298Y121797D01*
X1926028D01*
X1924625Y123200D01*
X1923100D01*
X1922526Y122626D01*
G01X1921144Y118844D02*
Y121244D01*
X1922526Y122626D01*
G01X1923837Y118800D02*
Y117222D01*
X1921959Y115344D01*
X1921144D01*
G01X1937728Y99441D02*
X1937800Y99513D01*
Y104200D01*
X1937300Y104700D01*
G01D02*
X1932000D01*
X1925025Y97725D01*
X1921711D01*
X1918837Y100599D01*
X1912496D01*
X1911012Y102083D01*
Y106512D01*
X1911646Y107146D01*
X1912894D01*
G01X1931550Y140500D02*
Y143450D01*
X1931000Y144000D01*
Y147000D01*
G01X1933849Y140500D02*
X1931550D01*
G01X1946925Y163227D02*
X1945478D01*
X1942665Y160414D01*
Y147926D01*
X1935695Y140956D01*
X1935663D01*
X1935207Y140500D01*
X1933849D01*
G01X1931000Y147000D02*
X1933900D01*
X1934000Y147100D01*
G01X1955531Y152047D02*
X1952202D01*
X1949570Y149415D01*
X1947584D01*
X1943835Y145666D01*
G01X1925300Y137300D02*
X1926531Y138531D01*
X1931550D01*
G01X1925300Y137300D02*
Y140627D01*
X1925358Y140685D01*
G01X1933849Y138531D02*
X1931550D01*
G01X1943835Y145666D02*
X1936700Y138531D01*
X1933849D01*
G01X1929756Y131037D02*
X1928648D01*
X1928126Y131559D01*
X1925925D01*
X1925500Y131984D01*
Y132500D01*
G01X1933849Y134594D02*
X1934815D01*
X1937337Y135638D01*
X1941449Y139750D01*
G01X1933849Y134594D02*
X1931550D01*
G01X1925500Y132500D02*
X1927400D01*
X1929494Y134594D01*
X1931550D01*
G01X1941449Y139750D02*
X1947242Y145543D01*
X1951685D01*
X1953055Y144173D01*
X1955531D01*
G01X1919800Y196050D02*
X1917450D01*
X1917024Y195624D01*
Y193600D01*
G01D02*
X1917327Y193297D01*
Y190300D01*
G01X1923700Y164242D02*
X1925858D01*
X1926700Y163400D01*
X1929700D01*
G01D02*
X1931500Y161600D01*
X1933250D01*
G01X1922800Y196050D02*
Y194900D01*
X1921500Y193600D01*
G01D02*
X1920500D01*
X1919296Y192396D01*
Y190300D01*
G01X1936750Y169600D02*
X1939870D01*
X1940240Y169970D01*
G01X1936750Y165600D02*
X1939550D01*
G01X1928000Y195850D02*
X1925850D01*
X1925400Y196300D01*
G01D02*
X1925100Y196000D01*
Y194700D01*
X1922820Y192420D01*
Y190906D01*
X1922214Y190300D01*
X1921264D01*
G01X1929090Y193190D02*
X1930120D01*
X1931950Y195020D01*
Y196100D01*
G01X1923700Y185895D02*
X1924895D01*
X1926500Y187500D01*
Y188700D01*
X1927900Y190100D01*
Y192000D01*
X1929090Y193190D01*
G01X1923700Y183927D02*
X1925027D01*
X1930150Y189050D01*
Y190100D01*
G01Y181100D02*
X1929650Y181600D01*
X1926900D01*
X1925290Y179990D01*
X1923700D01*
G01Y181958D02*
X1925158D01*
X1927300Y184100D01*
X1930150D01*
G01X1935450Y196100D02*
X1937100D01*
X1939400Y198400D01*
G01X1934100Y193400D02*
X1933650Y192950D01*
Y190100D01*
G01Y181100D02*
Y179806D01*
X1934400Y179056D01*
Y177500D01*
X1935600Y176300D01*
G01X1932837Y186700D02*
X1933650Y185887D01*
Y184100D01*
G01X1923700Y187864D02*
Y190700D01*
X1925000Y192000D01*
G01X1933250Y157600D02*
X1930000D01*
X1929000Y158600D01*
G01D02*
Y159156D01*
X1925883Y162273D01*
X1923700D01*
G01Y166210D02*
X1926440D01*
X1927350Y165300D01*
X1932950D01*
X1933250Y165600D01*
G01D02*
Y165977D01*
X1934662Y167389D01*
X1943590D01*
X1943803Y167176D01*
G01X1933250Y169600D02*
X1930780Y167130D01*
X1929336D01*
G01D02*
X1926170D01*
X1925121Y168179D01*
X1923700D01*
G01X1936750Y157600D02*
X1940500D01*
G01X1923700Y174084D02*
X1925570D01*
X1925985Y173669D01*
X1928794D01*
X1930645Y175520D01*
X1931065D01*
G01X1923700Y172116D02*
X1925284D01*
X1927000Y170400D01*
X1927500D01*
G01X1933250Y173600D02*
Y172010D01*
X1932661Y171421D01*
X1931574D01*
X1930300Y170147D01*
G01D02*
X1928853Y168700D01*
X1926699D01*
X1925252Y170147D01*
X1923700D01*
G01X1927064Y207564D02*
X1927998Y206630D01*
X1928530D01*
X1933290Y201870D01*
G01X1949901Y188110D02*
X1950531Y187480D01*
X1955531D01*
G01X1960760Y184173D02*
X1960130Y183543D01*
X1955531D01*
G01X1946500Y180000D02*
X1950043Y183543D01*
X1955531D01*
G01Y159921D02*
X1951638D01*
X1948332Y163227D01*
X1946925D01*
G01X1937909Y186846D02*
Y188693D01*
X1941000Y191784D01*
G01X1941012D02*
X1941000D01*
G01D02*
X1941016Y191800D01*
X1942700D01*
X1944300Y190200D01*
G01X1955531Y175669D02*
X1952064D01*
X1951434Y176299D01*
X1944701D01*
X1944550Y176450D01*
G01X1941609Y183346D02*
Y174991D01*
X1944553Y172047D01*
X1946200D01*
G01X1941609Y183346D02*
X1937909D01*
G01X1950981Y168064D02*
X1951250Y167795D01*
X1955531D01*
G01X1946200Y172047D02*
X1950183Y168064D01*
X1950981D01*
G01X1899611Y190300D02*
X1899701Y190390D01*
Y192898D01*
X1898800Y193799D01*
Y195344D01*
G01D02*
Y196609D01*
X1897760Y197649D01*
Y198710D01*
G01X1899092Y231294D02*
X1902907D01*
G01X1937430Y464785D02*
X1935838Y466377D01*
X1920901D01*
X1920476Y465952D01*
Y460603D01*
G01X1923900Y479530D02*
Y477510D01*
X1925980Y475430D01*
G01X1945550Y492280D02*
X1944400Y491130D01*
X1942572D01*
X1940930Y489488D01*
Y484868D01*
X1939712Y483650D01*
X1937740D01*
X1936740Y484650D01*
X1933900D01*
G01X1945610Y489180D02*
X1944620Y490170D01*
X1942970D01*
X1941890Y489090D01*
Y484470D01*
X1940110Y482690D01*
X1937960D01*
X1937360Y482090D01*
X1933900D01*
G01X1957212Y479521D02*
X1955241Y477550D01*
X1953870D01*
X1952820Y478600D01*
Y490460D01*
X1951000Y492280D01*
X1949050D01*
G01X1957063Y474769D02*
X1955232Y476600D01*
X1953480D01*
X1951860Y478220D01*
Y489730D01*
X1951250Y490340D01*
X1950270D01*
X1949110Y489180D01*
G01X1923900Y482090D02*
X1928000D01*
X1928620Y482710D01*
G01X1962401Y494924D02*
X1956196D01*
X1953130Y497990D01*
Y504110D01*
X1954620Y505600D01*
Y520339D01*
X1962401Y528120D01*
Y532451D01*
X1964890Y534940D01*
G01X1945900Y549900D02*
X1945500D01*
X1944882Y550518D01*
Y558464D01*
G01X1952756Y566338D02*
X1949018Y562600D01*
X1938400D01*
X1934500Y566500D01*
X1930250D01*
Y566442D01*
G01D02*
Y564850D01*
X1930800Y564300D01*
X1932800D01*
G01X1930250Y569442D02*
X1930772Y568920D01*
X1932080D01*
X1933500Y567500D01*
X1936400D01*
X1936900Y568000D01*
G01X1930250Y569442D02*
X1932308Y571500D01*
X1939720D01*
X1944882Y566338D01*
G01X1926750Y566442D02*
Y559650D01*
X1926600Y559500D01*
G01X1926750Y569442D02*
Y569500D01*
X1923600Y566350D01*
Y565100D01*
G01X1931239Y596040D02*
Y594963D01*
X1932389Y593813D01*
X1933929D01*
X1935100Y592642D01*
X1941292D01*
X1942660Y594010D01*
X1946330D01*
X1948960Y591380D01*
Y587720D01*
X1947280Y586040D01*
X1934150D01*
X1932610Y584500D01*
Y583502D01*
X1930808Y581700D01*
X1926400D01*
X1925803Y581103D01*
Y578500D01*
G01X1963071Y540467D02*
X1960517D01*
X1958940Y538890D01*
G01X1911000Y556700D02*
X1908200Y553900D01*
X1905800D01*
X1901893Y557807D01*
X1901804D01*
G01D02*
Y566704D01*
X1903400Y568300D01*
Y570900D01*
X1901804Y572496D01*
Y576807D01*
G01X1939800Y543700D02*
X1939400Y543300D01*
X1936100D01*
X1934200Y545200D01*
X1924000D01*
X1922500Y546700D01*
G01X1914750Y544863D02*
Y544550D01*
X1913982Y543782D01*
X1911000D01*
G01X1929750Y548500D02*
Y557050D01*
X1934600Y561900D01*
G01X1922000Y543750D02*
X1925575D01*
X1926000Y543325D01*
Y540000D01*
G01X1968000Y590000D02*
X1965600D01*
X1958500Y582900D01*
Y551009D01*
X1956191Y548700D01*
G01X1913100Y538000D02*
X1915344D01*
X1917744Y540400D01*
G01X1904000Y543782D02*
X1906528D01*
X1907500Y544754D01*
Y545600D01*
G01X1907200Y551600D02*
Y550094D01*
X1908394Y548900D01*
X1911000D01*
G01X1904000D02*
X1900600D01*
X1899800Y548100D01*
G01X1934749Y599040D02*
X1934776D01*
G01X1931249D02*
Y596050D01*
X1931239Y596040D01*
G01X1931199Y602040D02*
Y599090D01*
X1931249Y599040D01*
G01X1934699Y605040D02*
X1937676D01*
X1944882Y597834D01*
G01X1919504Y594001D02*
X1915299D01*
X1914700Y594600D01*
G01X1919504Y613001D02*
Y606705D01*
X1918000Y605201D01*
Y601800D01*
X1919504Y600296D01*
Y594001D01*
G01X1952756Y597834D02*
X1956700Y601778D01*
Y621182D01*
X1956275Y621607D01*
X1921407D01*
X1919504Y619704D01*
Y613001D01*
G01X1934699Y602040D02*
X1937570D01*
X1938130Y601480D01*
G01X1963071Y545979D02*
X1960191D01*
X1959120Y547050D01*
G01X1961715Y555639D02*
X1963501D01*
X1964640Y554500D01*
X1968000D01*
G01X1970071Y545979D02*
Y547321D01*
X1972700Y549950D01*
G01X1970071Y540467D02*
Y539529D01*
X1972800Y536800D01*
G01X1968000Y568500D02*
X1964850D01*
X1962950Y566600D01*
G01X1962500Y578500D02*
Y577100D01*
X1963600Y576000D01*
X1968000D01*
G01Y597500D02*
X1962244Y591744D01*
X1961771D01*
G01X1963300Y612800D02*
X1964600Y611500D01*
X1968000D01*
G54D354*
G01X721563Y289369D02*
Y286400D01*
G01X718413D02*
Y288287D01*
X717750Y288950D01*
Y290600D01*
G01X1400222Y554185D02*
X1400914D01*
X1402569Y552530D01*
Y550285D01*
X1403387Y549467D01*
X1404910D01*
G01X1582767Y393509D02*
X1585791D01*
G01X1545407Y604713D02*
X1548550D01*
G01X1557413Y595850D02*
Y592913D01*
X1555600Y591100D01*
G01X1548550Y603138D02*
X1546778D01*
X1546577Y602937D01*
X1544733D01*
X1544701Y602969D01*
X1544609D01*
X1543544Y604034D01*
G01X1548550Y598413D02*
Y597213D01*
X1546892Y595555D01*
X1544436D01*
X1544300Y595419D01*
X1542500D01*
G01Y610500D02*
X1545900D01*
X1546963Y609437D01*
X1548550D01*
G01Y607862D02*
X1546402D01*
X1545650Y608614D01*
X1541862D01*
X1541162Y607914D01*
Y607903D01*
G01X1548550Y606287D02*
X1546313D01*
X1545800Y606800D01*
X1543778D01*
X1543697Y606719D01*
G54D63*
X28870Y507085D03*
X1377504Y65465D03*
X1776900Y90000D03*
G54D219*
X1417111Y466941D03*
G54D90*
X94973Y341879D03*
X98590Y371450D03*
X98540Y356360D03*
X98563Y348771D03*
X98520Y363880D03*
X96528Y387642D03*
X744020Y258770D03*
X750900Y264100D03*
X751700Y276900D03*
X745200Y270500D03*
X745400Y281900D03*
X1359512Y45934D03*
G54D156*
X703915Y98272D03*
X1772170Y136750D03*
Y132250D03*
Y127750D03*
Y123250D03*
Y150750D03*
Y146250D03*
Y141250D03*
X1730678Y604617D03*
X1746936Y603249D03*
X1806548Y155437D03*
X1780670Y141250D03*
Y136750D03*
Y132250D03*
Y127750D03*
Y123250D03*
Y150750D03*
Y146250D03*
G54D309*
X1893750Y130360D03*
Y128390D03*
Y120510D03*
Y114600D03*
Y112630D03*
Y126420D03*
Y118540D03*
Y116570D03*
Y124450D03*
Y122480D03*
G54D345*
X1962401Y483109D03*
Y494924D03*
Y500829D03*
G54D174*
X1256754Y321327D03*
X1261585Y307408D03*
X1261972Y300150D03*
X1245219Y322557D03*
X1260848Y293146D03*
G54D273*
X1698611Y192179D03*
Y183518D03*
X1692312D03*
Y192179D03*
G54D336*
X1918885Y224779D03*
Y235941D03*
G54D54*
X44291Y178386D03*
G54D246*
X1583398Y-4537D03*
Y-2569D03*
Y-600D03*
Y1369D03*
Y3337D03*
G54D327*
X1932700Y136563D03*
G54D72*
X94683Y-5822D03*
Y31978D03*
Y13078D03*
Y69778D03*
Y50878D03*
Y88678D03*
Y514079D03*
Y532955D03*
Y570755D03*
Y589679D03*
Y551879D03*
Y608555D03*
X637793Y-5822D03*
Y31978D03*
Y13078D03*
Y69778D03*
Y50878D03*
Y88678D03*
Y514079D03*
Y532955D03*
Y570755D03*
Y589679D03*
Y551879D03*
Y608555D03*
X744293Y-5822D03*
Y31978D03*
Y13078D03*
Y69778D03*
Y88678D03*
Y50878D03*
Y514079D03*
Y570755D03*
Y532955D03*
Y589679D03*
Y551879D03*
Y608555D03*
X1287403Y-5822D03*
Y31978D03*
Y13078D03*
Y69778D03*
Y88678D03*
Y50878D03*
Y514079D03*
Y570755D03*
Y532955D03*
Y589679D03*
Y551879D03*
Y608555D03*
G54D183*
X1254441Y355073D03*
X1265918Y348135D03*
X1246918Y362262D03*
G54D45*
X8141Y29503D03*
Y31275D03*
X8466Y60870D03*
Y62642D03*
Y64413D03*
Y66185D03*
Y67957D03*
Y69728D03*
Y71500D03*
Y73272D03*
Y75043D03*
Y76815D03*
X8141Y33046D03*
Y34818D03*
Y36590D03*
Y38361D03*
Y40133D03*
Y41905D03*
Y43676D03*
Y45448D03*
X-1959Y536159D03*
Y537931D03*
Y539702D03*
Y541474D03*
Y543246D03*
Y545017D03*
Y546789D03*
Y548561D03*
Y550332D03*
Y552104D03*
Y572159D03*
Y573931D03*
Y575702D03*
Y577474D03*
Y579246D03*
Y581017D03*
Y582789D03*
Y584561D03*
Y586332D03*
Y588104D03*
X122165Y216692D03*
Y248692D03*
Y250464D03*
Y252235D03*
Y254007D03*
Y255779D03*
Y257550D03*
Y259322D03*
Y261094D03*
Y262865D03*
Y264637D03*
Y218464D03*
Y220235D03*
Y222007D03*
Y223779D03*
Y225550D03*
Y227322D03*
Y229094D03*
Y230865D03*
Y232637D03*
Y280692D03*
Y282464D03*
Y284235D03*
Y286007D03*
Y287779D03*
Y289550D03*
Y291322D03*
Y293094D03*
Y294865D03*
Y296637D03*
Y312692D03*
Y314464D03*
Y316235D03*
Y318007D03*
Y319779D03*
Y321550D03*
Y323322D03*
Y325094D03*
Y326865D03*
Y328637D03*
Y344692D03*
Y346464D03*
Y348235D03*
Y350007D03*
Y351779D03*
Y353550D03*
Y355322D03*
Y357094D03*
Y358865D03*
Y360637D03*
Y376692D03*
Y378464D03*
Y380235D03*
Y382007D03*
Y383779D03*
Y385550D03*
Y387322D03*
Y389094D03*
Y390865D03*
Y392637D03*
X709959Y216526D03*
Y214754D03*
Y212983D03*
Y211211D03*
Y209439D03*
Y207668D03*
Y205896D03*
Y221841D03*
Y220069D03*
Y218298D03*
X771773Y216692D03*
Y218464D03*
Y220235D03*
Y222007D03*
Y223779D03*
Y225550D03*
Y227322D03*
Y229094D03*
Y230865D03*
Y232637D03*
Y248692D03*
Y250464D03*
Y252235D03*
Y254007D03*
Y255779D03*
Y257550D03*
Y259322D03*
Y261094D03*
Y262865D03*
Y264637D03*
Y312692D03*
Y314464D03*
Y316235D03*
Y318007D03*
Y319779D03*
Y321550D03*
Y323322D03*
Y325094D03*
Y326865D03*
Y328637D03*
Y280692D03*
Y282464D03*
Y284235D03*
Y286007D03*
Y287779D03*
Y289550D03*
Y291322D03*
Y293094D03*
Y294865D03*
Y296637D03*
Y344692D03*
Y346464D03*
Y348235D03*
Y350007D03*
Y351779D03*
Y353550D03*
Y355322D03*
Y357094D03*
Y358865D03*
Y360637D03*
X771723Y376692D03*
Y378464D03*
Y380235D03*
Y382007D03*
Y383779D03*
Y385550D03*
Y387322D03*
Y389094D03*
Y390865D03*
Y392637D03*
X1375048Y1017D03*
Y-755D03*
Y-2526D03*
Y-4298D03*
Y-6070D03*
Y-7841D03*
Y-9613D03*
Y-11385D03*
Y-13156D03*
Y-14928D03*
X1375359Y31269D03*
Y29498D03*
Y27726D03*
Y25954D03*
Y24183D03*
Y22411D03*
Y20639D03*
Y18868D03*
Y17096D03*
Y33041D03*
X1377666Y391909D03*
Y390137D03*
Y388366D03*
Y386594D03*
Y384822D03*
Y383051D03*
Y381279D03*
Y379507D03*
Y377736D03*
Y375964D03*
X1379359Y579897D03*
Y578125D03*
Y576354D03*
Y574582D03*
Y572810D03*
Y571039D03*
Y569267D03*
Y567495D03*
Y565724D03*
Y563952D03*
Y611097D03*
Y609325D03*
Y607554D03*
Y605782D03*
Y604010D03*
Y602239D03*
Y600467D03*
Y598695D03*
Y596924D03*
Y595152D03*
G54D237*
X1481828Y599224D03*
X1517366Y600492D03*
G54D282*
X1741609Y173094D03*
G54D129*
X485812Y403471D03*
X489192Y401522D03*
X492572Y399571D03*
X495952Y397621D03*
X482432Y405422D03*
X1135420Y403471D03*
X1138800Y401522D03*
X1142180Y399571D03*
X1145560Y397621D03*
X1132040Y405422D03*
G54D165*
X721319Y496250D03*
X1394664Y544352D03*
X1541300Y316800D03*
X1634350Y204750D03*
X1736689Y173231D03*
X1732189D03*
X1727689D03*
X1723189D03*
Y165731D03*
X1727689D03*
X1732189D03*
X1736689D03*
X1718689D03*
Y173181D03*
X1714189Y165731D03*
X1855663Y145648D03*
G54D264*
X1632503Y343146D03*
G54D318*
X1851250Y584622D03*
Y576748D03*
Y568874D03*
G54D255*
X1627642Y-14488D03*
X1647327Y-315D03*
G54D18*
X-14488Y434094D03*
X-4488D03*
X5512D03*
X15512D03*
X89980Y145531D03*
X99980D03*
X109980D03*
X119980D03*
G54D27*
X40500Y-42250D03*
Y-52250D03*
X10512Y467244D03*
X20512D03*
X30512D03*
X40512D03*
X60500Y-42250D03*
X80500D03*
X100500D03*
X60500Y-52250D03*
X80500D03*
X100500D03*
X50512Y467244D03*
X120500Y-42250D03*
X140500D03*
X120500Y-52250D03*
X140500D03*
X467246Y-52301D03*
Y-42301D03*
X487246Y-52301D03*
Y-42301D03*
X507246Y-52301D03*
Y-42301D03*
X527246Y-52301D03*
Y-42301D03*
X547246Y-52301D03*
Y-42301D03*
X567246Y-52301D03*
Y-42301D03*
X798984Y-52057D03*
Y-42057D03*
X818984Y-52057D03*
Y-42057D03*
X838984Y-52057D03*
Y-42057D03*
X858984Y-52057D03*
Y-42057D03*
X878984Y-52057D03*
Y-42057D03*
X898984Y-52057D03*
Y-42057D03*
X1135583Y-52285D03*
Y-42285D03*
X1155583Y-52285D03*
Y-42285D03*
X1392258Y-52257D03*
Y-42257D03*
X1412258Y-52257D03*
Y-42257D03*
X1432258Y-52257D03*
Y-42257D03*
X1452258Y-52257D03*
Y-42257D03*
X1884100Y493000D03*
X1894100D03*
X1891086Y612105D03*
Y602105D03*
G54D228*
X1510127Y79413D03*
Y160909D03*
G54D147*
X671048Y16437D03*
X671447Y580430D03*
X1788200Y89000D03*
X1818500Y159500D03*
G54D192*
X1248059Y474441D03*
X1244243Y470374D03*
G54D81*
X101200Y177500D03*
Y198500D03*
X746000Y202000D03*
Y223000D03*
G54D138*
X652700Y275600D03*
X693962Y313316D03*
X689000Y312366D03*
G54D291*
X1727112Y600844D03*
X1733096D03*
X1891736Y190300D03*
X1895673D03*
X1893705D03*
X1897642D03*
X1901579D03*
X1913390D03*
X1915359D03*
X1921264D03*
X1907485D03*
X1909453D03*
X1903548D03*
X1905516D03*
X1911422D03*
X1919296D03*
X1917327D03*
X1899611D03*
G54D36*
X29654Y21862D03*
X29743Y52374D03*
X25000Y562500D03*
X20300Y529100D03*
X143700Y208300D03*
X147500Y272900D03*
X143700Y241000D03*
X144400Y306100D03*
X146209Y337400D03*
X144010Y369674D03*
X795699Y207600D03*
X799151Y240966D03*
X798387Y272898D03*
X795800Y336400D03*
X797570Y305000D03*
X792582Y368417D03*
G54D364*
G01X1209649Y356596D02*
Y356597D01*
G01X1526525Y440375D02*
X1524950Y441950D01*
G01X1523375Y440375D02*
X1521800Y441950D01*
G01X1510775Y443525D02*
X1509200Y445100D01*
G01X1513925Y443525D02*
X1512350Y445100D01*
G01X1513925Y443525D02*
X1515500Y445100D01*
G01X1510775Y443525D02*
X1512350Y445100D01*
G01X1517075Y443525D02*
X1515500Y445100D01*
G01X1507625Y452975D02*
X1509200Y454550D01*
G01X1510925Y456160D02*
X1512875Y458110D01*
Y459540D01*
G01X1509200Y454550D02*
X1509750Y455100D01*
X1509865D01*
X1510925Y456160D01*
G01X1510775Y452975D02*
X1509200Y454550D01*
G01X1517075Y452975D02*
X1516220Y453830D01*
X1514780D01*
X1513925Y452975D01*
G01X1510775D02*
X1512350Y451400D01*
G01X1512400Y454500D02*
X1513925Y452975D01*
G01X1509200Y445100D02*
X1507625Y443525D01*
G01X1523375Y412025D02*
X1524412Y410993D01*
G01X1512350Y451400D02*
X1513925Y449825D01*
G01X1509200Y413600D02*
X1510775Y412025D01*
G01X1512400Y454500D02*
Y454685D01*
G01X1513925Y446675D02*
X1512350Y448250D01*
G01X1506460Y413980D02*
Y414010D01*
G01X1507625Y415175D02*
X1509200Y413600D01*
G01X1510775Y415175D02*
X1509200Y413600D01*
G01X1512100Y413840D02*
Y413850D01*
G01X1510775Y412025D02*
X1512050Y413300D01*
G01X1512350Y451400D02*
X1513925Y452975D01*
G01X1506460Y414010D02*
X1507625Y415175D01*
G01X1512100Y413850D02*
X1510775Y415175D01*
G01X1512400Y454685D02*
X1510925Y456160D01*
G01X1512350Y448250D02*
X1513925Y449825D01*
G01X1522222Y436072D02*
X1523375Y437225D01*
G01X1522222Y438378D02*
X1523375Y437225D01*
G01X1522222Y432922D02*
X1523375Y434075D01*
G01X1522222Y435228D02*
X1523375Y434075D01*
G01X1522222Y429772D02*
X1523375Y430925D01*
G01X1522222Y432078D02*
X1523375Y430925D01*
G01X1522222Y426622D02*
X1523375Y427775D01*
G01X1522222Y428928D02*
X1523375Y427775D01*
G01X1519072Y442372D02*
X1520225Y443525D01*
G01X1519072Y444678D02*
X1520225Y443525D01*
G01X1519072Y441528D02*
X1520225Y440375D01*
G01D02*
X1521378Y439222D01*
G01X1503920Y411067D02*
X1505073Y412220D01*
G01D02*
X1506226Y413373D01*
G01X1503920D02*
X1505073Y412220D01*
G01D02*
X1506226Y411067D01*
G01X1517075Y443525D02*
X1518228Y444678D01*
G01X1517075Y443525D02*
X1518228Y442372D01*
G01X1525372Y410872D02*
X1526525Y412025D01*
G01D02*
X1527678Y410872D01*
G01X1517075Y412025D02*
X1518650Y413600D01*
G01D02*
X1520225Y415175D01*
G01X1526525Y418325D02*
X1525000Y416800D01*
Y416750D01*
G01X1529675Y418325D02*
X1528800Y419200D01*
X1527400D01*
X1526525Y418325D01*
G01X1520225Y452975D02*
X1519917Y453283D01*
X1519023D01*
X1518675Y452935D01*
Y451425D01*
G01X1514825Y456160D02*
X1514100Y456885D01*
Y457630D01*
X1514809Y458339D01*
X1515502D01*
X1516775Y457066D01*
G01X1510775Y449825D02*
X1509620Y448670D01*
G01X1501200Y450600D02*
X1501925D01*
G01X1505714Y448145D02*
X1506155D01*
G01X1526525Y446675D02*
X1527678Y447828D01*
G01X1526525Y446675D02*
X1527678Y445522D01*
G01X1501925Y450600D02*
X1503125Y449400D01*
G01X1506155Y448145D02*
X1507625Y446675D01*
G01X1506472Y448672D02*
X1507625Y449825D01*
G01X1506472Y450978D02*
X1507625Y449825D01*
G01D02*
X1508778Y448672D01*
G01X1501972Y448247D02*
X1503125Y449400D01*
G01D02*
X1504278Y450553D01*
G01X1503125Y449400D02*
X1504278Y448247D01*
G01X1523375Y452975D02*
X1523820Y452530D01*
Y451690D01*
X1523530Y451400D01*
G01X1523375Y449825D02*
X1523723Y450173D01*
Y451207D01*
X1523530Y451400D01*
G01D02*
X1521800D01*
G01X1526525Y434075D02*
X1524950Y435650D01*
G01X1526525Y437225D02*
X1524950Y438800D01*
G01X1526525Y427775D02*
X1524950Y426200D01*
G01X1526525Y424625D02*
X1524950Y423050D01*
G01X1520225Y424625D02*
X1518650Y423050D01*
G01X1507625Y430925D02*
X1509200Y429350D01*
G01X1510775Y424625D02*
X1509200Y423050D01*
G01X1513925Y418325D02*
X1512350Y416750D01*
G01X1507625Y418325D02*
X1509200Y416750D01*
G01X1518650Y429350D02*
X1517075Y430925D01*
G01X1515500Y429350D02*
X1513925Y430925D01*
G01Y418325D02*
X1512350Y419900D01*
G01X1513925Y418325D02*
X1515500Y419900D01*
G01X1512350D02*
X1513925Y421475D01*
G01X1509200Y419900D02*
X1507625Y421475D01*
G01X1515500Y419900D02*
X1517075Y421475D01*
G01X1512350Y429350D02*
X1513925Y430925D01*
G01X1509200Y423050D02*
X1507625Y421475D01*
G01X1510775D02*
X1509200Y419900D01*
G01X1517075Y430925D02*
X1515500Y429350D01*
G01X1520225Y430925D02*
X1518650Y429350D01*
G01X1510775Y430925D02*
X1512350Y429350D01*
G01X1507625Y424625D02*
X1509200Y423050D01*
G01X1513925Y427775D02*
X1512350Y426200D01*
G01X1510775Y427775D02*
X1509200Y426200D01*
G01Y429350D02*
X1507625Y427775D01*
G01X1510775Y430925D02*
X1509200Y429350D01*
G01X1513925Y424625D02*
X1512350Y423050D01*
G01X1520225Y427775D02*
X1518650Y426200D01*
G01X1517075Y427775D02*
X1515500Y426200D01*
G01X1517075Y424625D02*
X1515500Y423050D01*
G01X1509200Y416750D02*
X1510775Y418325D01*
G01X1507625Y440375D02*
X1509200Y441950D01*
G01X1517075Y440375D02*
X1515500Y441950D01*
G01X1513925Y440375D02*
X1512350Y441950D01*
G01X1520225Y437225D02*
X1518650Y438800D01*
G01X1513925Y434075D02*
X1515500Y435650D01*
G01X1518650D02*
X1517075Y437225D01*
G01Y434075D02*
X1518650Y435650D01*
G01X1520225Y434075D02*
X1518650Y435650D01*
G01X1510775Y434075D02*
X1509200Y435650D01*
G01D02*
X1507625Y437225D01*
G01Y434075D02*
X1509200Y435650D01*
G01X1515500D02*
X1517075Y434075D01*
G01X1513925Y437225D02*
X1515500Y435650D01*
G01X1517075Y437225D02*
X1515500Y438800D01*
G01X1513925Y437225D02*
X1512350Y438800D01*
G01X1515500Y435650D02*
X1517075Y437225D01*
G01X1513925D02*
X1512350Y435650D01*
G01X1510775Y437225D02*
X1509200Y438800D01*
G01X1518650D02*
X1517075Y437225D01*
G01X1515500Y438800D02*
X1513925Y437225D01*
G01X1507625Y434075D02*
X1508850Y432850D01*
G01X1509200Y441950D02*
X1510775Y440375D01*
G01X1505605Y423604D02*
Y423495D01*
G01D02*
X1507625Y421475D01*
G01X1515922Y432922D02*
X1517075Y434075D01*
G01D02*
X1518228Y432922D01*
G01X1517075Y430925D02*
X1518228Y432078D01*
G01X1515922D02*
X1517075Y430925D01*
G01X1512772Y432922D02*
X1513925Y434075D01*
G01D02*
X1515078Y432922D01*
G01X1513925Y430925D02*
X1515078Y432078D01*
G01X1512772D02*
X1513925Y430925D01*
G01X1509622Y432922D02*
X1510775Y434075D01*
G01D02*
X1511928Y432922D01*
G01X1510775Y430925D02*
X1511928Y432078D01*
G01X1509622D02*
X1510775Y430925D01*
G01X1506472Y436072D02*
X1507625Y437225D01*
G01X1506472Y438378D02*
X1507625Y437225D01*
G01X1506472Y429772D02*
X1507625Y430925D01*
G01D02*
X1508778Y432078D01*
G01X1506472Y426622D02*
X1507625Y427775D01*
G01X1506472Y428928D02*
X1507625Y427775D01*
G01X1506472Y417172D02*
X1507625Y418325D01*
G01X1506472Y419478D02*
X1507625Y418325D01*
G01X1505075Y425740D02*
X1506228Y426893D01*
G01X1503922D02*
X1505075Y425740D01*
G01X1503922Y417827D02*
X1505075Y418980D01*
G01D02*
X1506228Y420133D01*
G01X1503922D02*
X1505075Y418980D01*
G01D02*
X1506228Y417827D01*
G01X1503125Y429120D02*
X1504278Y430273D01*
G01X1503125Y429120D02*
X1504278Y427967D01*
G01X1503125Y422360D02*
X1504278Y423513D01*
G01X1503125Y422360D02*
X1504278Y421207D01*
G01X1526525Y437225D02*
X1527678Y438378D01*
G01X1526525Y437225D02*
X1527678Y436072D01*
G01X1525372Y432922D02*
X1526525Y434075D01*
G01D02*
X1527678Y435228D01*
G01X1526525Y434075D02*
X1527678Y432922D01*
G01X1526525Y427775D02*
X1527678Y428928D01*
G01X1526525Y427775D02*
X1527678Y426622D01*
G01X1526525Y424625D02*
X1527678Y425778D01*
G01X1526525Y424625D02*
X1527678Y423472D01*
G01X1523375Y415175D02*
X1522836Y414636D01*
Y413947D01*
X1523183Y413600D01*
X1524950D01*
G01X1540700Y410450D02*
X1539125Y412025D01*
G01X1529675Y440375D02*
X1531250Y441950D01*
G01X1532825Y440375D02*
X1534400Y441950D01*
G01X1535975Y440375D02*
X1537550Y441950D01*
G01X1535975Y434075D02*
X1535420Y433520D01*
Y432830D01*
X1535720Y432530D01*
X1536790D01*
X1537550Y433290D01*
Y435650D01*
G01X1542275Y434075D02*
X1543850Y435650D01*
G01X1532825Y449825D02*
X1534400Y451400D01*
G01X1535975Y449825D02*
X1537550Y451400D01*
G01X1534400D02*
X1535975Y449825D01*
G01Y421475D02*
X1537550Y419900D01*
G01X1539125Y421475D02*
X1540700Y419900D01*
G01X1537550D02*
X1539125Y421475D01*
G01X1542275Y424625D02*
X1543850Y426200D01*
G01X1542275Y430925D02*
X1543850Y429350D01*
G01Y426200D02*
X1542275Y427775D01*
G01X1540700Y419900D02*
X1542275Y421475D01*
G01X1531250Y451400D02*
X1532825Y449825D01*
G01X1534822Y410872D02*
X1535975Y412025D01*
G01D02*
X1537128Y410872D01*
G01X1531672D02*
X1532825Y412025D01*
G01D02*
X1533978Y410872D01*
G01X1528522D02*
X1529675Y412025D01*
G01D02*
X1530828Y410872D01*
G01X1532825Y418325D02*
X1534400Y416750D01*
G01X1535975Y418325D02*
X1537550Y416750D01*
G01X1540700D02*
X1539125Y418325D01*
G01X1545425D02*
X1543850Y416750D01*
G01X1542275Y415175D02*
X1543850Y413600D01*
G01Y416750D02*
X1542275Y418325D01*
G01X1543850Y413600D02*
X1545425Y415175D01*
G01Y446675D02*
X1543850Y445100D01*
G01X1544350Y447760D02*
X1545425Y446685D01*
Y446675D01*
G01X1528522Y445522D02*
X1529675Y446675D01*
G01X1528522Y447828D02*
X1529675Y446675D01*
G01X1546822Y431347D02*
X1547975Y432500D01*
G01X1546822Y433653D02*
X1547975Y432500D01*
G01D02*
X1549128Y431347D01*
G01X1544272Y432922D02*
X1545425Y434075D01*
G01D02*
X1546578Y432922D01*
G01X1545425Y430925D02*
X1546578Y432078D01*
G01X1544272D02*
X1545425Y430925D01*
G01D02*
X1546578Y429772D01*
G01X1545425Y421475D02*
X1546578Y422628D01*
G01X1544272D02*
X1545425Y421475D01*
G01D02*
X1546578Y420322D01*
G01X1549925Y435880D02*
X1548930Y436875D01*
G01X1549925Y435880D02*
X1550920Y434885D01*
G01X1545425Y440375D02*
X1543850Y441950D01*
G01X1545425Y440375D02*
X1546470Y439330D01*
G01X1545425Y437225D02*
X1546480Y438280D01*
G01X1547975Y439260D02*
X1547030Y440205D01*
G01X1549925Y435880D02*
X1550831Y436786D01*
G01X1545425Y437225D02*
X1543950Y438700D01*
G01X1550831Y436786D02*
X1551875D01*
G01X1546822Y438107D02*
X1547975Y439260D01*
G01D02*
X1549128Y440413D01*
G01X1547975Y439260D02*
X1549128Y438107D01*
G01X1544272Y439222D02*
X1545425Y440375D01*
G01D02*
X1546578Y441528D01*
G01X1529675Y437225D02*
X1531250Y438800D01*
G01X1532825Y434075D02*
X1534400Y435650D01*
G01X1529675Y434075D02*
X1531250Y435650D01*
G01X1532825Y437225D02*
X1534400Y438800D01*
G01X1532825Y424625D02*
X1534400Y423050D01*
G01X1529675Y424625D02*
X1531250Y423050D01*
G01X1537550Y426200D02*
X1535975Y427775D01*
G01Y430925D02*
X1537550Y429350D01*
G01X1535975Y424625D02*
X1537550Y423050D01*
G01Y429350D02*
X1539125Y430925D01*
G01X1540700Y423050D02*
X1539125Y424625D01*
G01X1529675Y427775D02*
X1531250Y426200D01*
G01X1532825Y427775D02*
X1534400Y426200D01*
G01X1532825Y430925D02*
X1534400Y429350D01*
G01X1529675Y430925D02*
X1531250Y429350D01*
G01X1540700Y426200D02*
X1539125Y427775D01*
G01X1540700Y429350D02*
X1539125Y430925D01*
G01X1531672Y432922D02*
X1532825Y434075D01*
G01D02*
X1533978Y432922D01*
G01X1532825Y430925D02*
X1533978Y432078D01*
G01X1531672D02*
X1532825Y430925D01*
G01X1528522Y436072D02*
X1529675Y437225D01*
G01X1528522Y438378D02*
X1529675Y437225D01*
G01X1528522Y432922D02*
X1529675Y434075D01*
G01X1528522Y435228D02*
X1529675Y434075D01*
G01D02*
X1530828Y432922D01*
G01X1528522Y429772D02*
X1529675Y430925D01*
G01D02*
X1530828Y432078D01*
G01X1528522D02*
X1529675Y430925D01*
G01X1528522Y426622D02*
X1529675Y427775D01*
G01X1528522Y428928D02*
X1529675Y427775D01*
G01X1528522Y423472D02*
X1529675Y424625D01*
G01X1528522Y425778D02*
X1529675Y424625D01*
G54D355*
G01X264092Y235706D02*
X265483D01*
X266729Y234460D01*
G01X264036Y233156D02*
X264551Y232641D01*
X267648D01*
X269467Y234460D01*
X273489D01*
G01X262992Y230559D02*
X266729D01*
G01X262783Y227856D02*
X263161Y228234D01*
X267041D01*
X269366Y230559D01*
X273489D01*
G01X270109Y357309D02*
X265495D01*
G01X273489Y359260D02*
X273226Y359523D01*
X266497D01*
X265520Y360500D01*
G01X273489Y363160D02*
X265605D01*
G01X262512Y224141D02*
X262706Y224335D01*
X266814D01*
G03X268744Y225497I-85J2325D01*
G02X270068Y226285I1365J-788D01*
G01X270537D01*
G03X271195Y226433I0J1538D01*
G02X272205Y226660I1010J-2134D01*
G01X273489D01*
G01X263144Y221066D02*
X263319Y220891D01*
X265137D01*
X265431Y221185D01*
X266798D01*
G03X268094Y221972I-69J1575D01*
G02X270059Y223147I2037J-1176D01*
G01X272555D01*
G02X273489Y222760I0J-1321D01*
G01X262944Y210544D02*
X265130Y212730D01*
Y213361D01*
X266729Y214960D01*
G01X261000Y212359D02*
X261741D01*
X265838Y216456D01*
X268085D01*
X269581Y214960D01*
X273489D01*
G01X258125Y217000D02*
X263823D01*
X265683Y218860D01*
X266729D01*
G01X259383Y214500D02*
X262820D01*
X265676Y217356D01*
X267963D01*
X269467Y218860D01*
X273489D01*
G01X262512Y225291D02*
X262718Y225085D01*
X266788D01*
G03X268094Y225872I-59J1575D01*
G02X270058Y227035I2015J-1163D01*
G01X270536D01*
G03X270874Y227111I0J788D01*
G03X270534Y228610I-338J711D01*
G01X270109D01*
G01X263144Y219916D02*
X263369Y220141D01*
X265448D01*
X265742Y220435D01*
X266814D01*
G03X268744Y221597I-85J2325D01*
G02X270072Y222397I1387J-801D01*
G01X270784D01*
G02X271284Y221897I0J-500D01*
G01Y221309D01*
G02X270784Y220809I-500J0D01*
G01X270109D01*
G01Y365109D02*
X268718Y366500D01*
X265700D01*
G01X270109Y372909D02*
X271240Y372257D01*
X271331Y371916D01*
G02X270367Y371355I-1223J993D01*
G02X270180Y371335I-261J1554D01*
G01X270158Y371334D01*
X268892D01*
X268492Y371734D01*
X267892D01*
X267492Y371334D01*
X266113D01*
X265892Y371555D01*
G01X273489Y370959D02*
X271892Y370775D01*
X270490Y370614D01*
G02X270194Y370584I-382J2295D01*
G01X266071D01*
X265892Y370405D01*
G01X276869Y384609D02*
X272539D01*
X271064Y386084D01*
X267175D01*
X266484Y385393D01*
G01X276869Y388509D02*
X272536D01*
X270962Y386935D01*
X267042D01*
X266034Y387943D01*
G01X273489Y378760D02*
X266665D01*
G01X270109Y384609D02*
X268343Y382843D01*
X266525D01*
G01X273489Y374860D02*
X271892Y374674D01*
X270392Y374500D01*
G02X270179Y374484I-281J2309D01*
G01X265662D01*
X265459Y374281D01*
X265372D01*
G01X270109Y376809D02*
X271240Y376157D01*
X271331Y375816D01*
G02X270155Y375235I-1222J994D01*
G01X269692Y375234D01*
X268492D01*
X268092Y375634D01*
X267492D01*
X267092Y375234D01*
X265589D01*
X265392Y375431D01*
G01X307289Y390460D02*
X303970Y390084D01*
G02X301869Y393530I-61J2326D01*
G01X301894Y393572D01*
G03Y395146I-1365J787D01*
G02Y397472I2015J1163D01*
G03X301913Y399013I-1365J787D01*
G01X301143Y400385D01*
X299937Y401591D01*
X299598D01*
G01X303909Y201309D02*
X305448Y199770D01*
Y196641D01*
G01X317148Y191821D02*
X318048D01*
X319053Y192826D01*
Y197136D01*
G03X318510Y198594I-2229J0D01*
G02X317428Y201309I3372J2917D01*
G01X315648Y194707D02*
Y205559D01*
X314048Y207159D01*
G01X327568D02*
X327157Y206748D01*
Y206115D01*
G02X327573Y203989I-5222J-2126D01*
G01Y200125D01*
X327918Y199780D01*
Y199179D01*
X327573Y198834D01*
Y197939D01*
X327729Y197783D01*
Y197141D01*
G01X310668Y209109D02*
Y207804D01*
X310382Y207518D01*
G03X310299Y207506I291J-2306D01*
G03X310668Y202887I370J-2295D01*
G02X312034Y200522I0J-1577D01*
G03X312049Y198209I1980J-1144D01*
G01X312100Y198107D01*
G02X312073Y196536I-1519J-760D01*
G01X311641Y195743D01*
X310828Y194551D01*
X309968Y193691D01*
X309738D01*
G01X327568Y218860D02*
Y217554D01*
X327283Y217269D01*
G03X327200Y217257I291J-2308D01*
G03X327483Y212635I368J-2297D01*
G01X327612D01*
G02X328933Y210272I-44J-1575D01*
G03Y207946I2015J-1163D01*
G02Y206372I-1365J-787D01*
G03X328621Y205220I2015J-1164D01*
G01Y201343D01*
X328622Y201342D01*
G03X328932Y200148I2326J-33D01*
G01Y200146D01*
X328935Y200143D01*
X329342Y199414D01*
Y198135D01*
X328929Y197722D01*
Y197141D01*
G01X310458Y192713D02*
Y193120D01*
X311408Y194070D01*
X312282Y195351D01*
X312732Y196177D01*
G03X312772Y198443I-2150J1171D01*
G01X312708Y198569D01*
X312694Y198593D01*
G02X312684Y200147I1320J786D01*
G03X310669Y203637I-2016J1163D01*
G01Y203638D01*
G02X310418Y206765I-1J1574D01*
G01X311033D01*
X311375Y206423D01*
Y205917D01*
X310668Y205210D01*
G01X327568Y214960D02*
X326859Y215802D01*
X326343D01*
G03X327509Y213385I1223J-900D01*
G01X327638D01*
G02X329583Y209897I-70J-2325D01*
G03X329564Y208356I1365J-787D01*
G01X329583Y208322D01*
G02X329608Y206039I-2015J-1164D01*
G01X329583Y205997D01*
G03X329372Y205216I1365J-788D01*
G01Y201332D01*
G03X329583Y200523I1576J-21D01*
G01X329591Y200508D01*
X330129Y199544D01*
Y197141D01*
G01X323212Y207216D02*
G02X322888Y206111I-1584J-136D01*
G03X322804Y205963I486J-373D01*
G03X322612Y205211I1384J-754D01*
G01Y204683D01*
X323115Y203816D01*
Y202597D01*
X322622Y201743D01*
Y200845D01*
X324129Y198233D01*
Y197141D01*
G01X320808Y214960D02*
X318859Y212338D01*
X318793Y212222D01*
X318768Y212180D01*
G03X318793Y209897I2040J-1119D01*
G01X319205Y208577D01*
Y203238D01*
X319210Y202995D01*
G03X319422Y202336I1217J28D01*
G01X320248Y201128D01*
X321679Y198415D01*
Y197141D01*
G01X307289Y199360D02*
Y198096D01*
X307167Y197974D01*
Y196214D01*
G01X317428Y205210D02*
Y203904D01*
G03X317748Y203241I847J0D01*
G02X318561Y202298I-2079J-2614D01*
G01X318900Y201712D01*
G02X319003Y201340I-673J-387D01*
G03X319156Y199642I12051J230D01*
G02X319803Y198080I-1562J-1562D01*
G01Y192236D01*
X318138Y190571D01*
X317248D01*
G01X303909Y205210D02*
X302481Y203287D01*
X302078Y202744D01*
G03X301869Y200189I1831J-1436D01*
G01X301894Y200147D01*
X301913Y200113D01*
G02X301729Y198381I-1346J-733D01*
G01X301381Y197977D01*
X299620Y197031D01*
G01X307289Y207159D02*
X305924Y204047D01*
G02X303979Y202884I-2015J1162D01*
G01X303850D01*
G03X302525Y200556I59J-1575D01*
G01X302544Y200522D01*
X302569Y200480D01*
G02X302544Y198197I-2040J-1119D01*
G03X302335Y197489I1365J-788D01*
G01X301417Y196571D01*
X300483Y196126D01*
G01X314048Y199360D02*
Y197944D01*
X314192Y197800D01*
Y195185D01*
G01X310668Y197409D02*
Y198715D01*
X310419Y198964D01*
G03X309303Y198197I247J-1555D01*
G03X309092Y197391I1363J-788D01*
G01Y195024D01*
X308308Y194240D01*
Y193959D01*
G01X283629Y267609D02*
X281379D01*
G01X290389Y263709D02*
X288139D01*
G01X280249Y257860D02*
X277999D01*
G01X283629Y255909D02*
X281379D01*
G01X287009Y269560D02*
X284759D01*
G01X290389Y267609D02*
X288139D01*
G01X280249Y261760D02*
X277999D01*
G01X287009Y257860D02*
X284759D01*
G01X290389Y259809D02*
X288139D01*
G01X280249Y265660D02*
X277999D01*
G01X287009Y261760D02*
X284759D01*
G01X283629Y263709D02*
X281379D01*
G01X330948Y384609D02*
Y383303D01*
X330699Y383054D01*
G02X329583Y383822I248J1556D01*
G01X329564Y383856D01*
G02X329583Y385397I1384J754D01*
G03X329608Y387680I-2015J1164D01*
G01X329583Y387722D01*
X329564Y387756D01*
G02X329583Y389297I1384J754D01*
G03X329476Y391659I-1901J1097D01*
G01X329208Y392039D01*
Y393198D01*
X329658Y393648D01*
Y395641D01*
G01X330948Y380709D02*
Y382015D01*
X330663Y382300D01*
G02X330580Y382312I291J2308D01*
G02X328933Y383447I368J2297D01*
G01X328908Y383489D01*
G02X328933Y385772I2040J1119D01*
G03X328952Y387313I-1365J787D01*
G01X328933Y387347D01*
X328908Y387389D01*
G02X328933Y389672I2040J1119D01*
G03X328862Y391226I-1251J721D01*
G01X328570Y391641D01*
X328566Y391647D01*
X328458Y391755D01*
Y395641D01*
G01X330948Y388509D02*
X332247Y391509D01*
X332312Y391621D01*
G03X332448Y392129I-882J508D01*
G01Y393297D01*
X332058Y393687D01*
Y395641D01*
G01X324188Y388509D02*
X325136Y389457D01*
Y391045D01*
X326058Y391967D01*
Y395641D01*
G01X327568Y390460D02*
X327258Y390770D01*
Y395641D01*
G01X327568Y382660D02*
G03X324144Y383034I-4019J-20937D01*
G02X322823Y383822I44J1575D01*
G02X322678Y384160I1356J782D01*
G02X322616Y384709I1510J449D01*
G03X322148Y387389I-5796J369D01*
G02X322173Y389672I2040J1119D01*
G03X322384Y390460I-1365J788D01*
G01Y390747D01*
X321702Y391929D01*
Y392958D01*
X322283Y393963D01*
Y394756D01*
X321753Y395674D01*
Y396944D01*
X322342Y397965D01*
Y398782D01*
X322058Y399423D01*
Y400644D01*
X322448Y401489D01*
Y403064D01*
X322192Y403320D01*
G01X324188Y384609D02*
X322891Y387605D01*
X322804Y387756D01*
G02X322823Y389297I1384J754D01*
G03X323135Y390460I-2015J1164D01*
G01Y390948D01*
X322450Y392135D01*
Y392681D01*
X323033Y393686D01*
Y394958D01*
X322503Y395876D01*
Y396742D01*
X323148Y397860D01*
Y398910D01*
X322870Y399582D01*
Y400390D01*
X323248Y401208D01*
Y402939D01*
X323498Y403189D01*
G01X364747Y201309D02*
X363256Y197865D01*
G03X363188Y197538I755J-328D01*
G01Y192003D01*
X365882Y189310D01*
Y188215D01*
G01X354607Y199360D02*
X355149Y198818D01*
Y189013D01*
X353972Y187836D01*
Y186457D01*
G01X346032Y186625D02*
Y187218D01*
X348901Y190087D01*
Y197400D01*
G02X349213Y198572I2327J8D01*
G03X349423Y199396I-1365J787D01*
G01Y201784D01*
X350968Y203329D01*
X351768Y203730D01*
G03X352803Y205230I-540J1480D01*
G01X353264Y208761D01*
X354605Y211056D01*
X354607Y211060D01*
G01X350002Y186360D02*
Y187210D01*
X351692Y188900D01*
Y196945D01*
X351228Y197409D01*
G01X348017Y186310D02*
Y187126D01*
X350492Y189601D01*
Y195600D01*
X349692Y196400D01*
Y197559D01*
G02X349863Y198197I1277J0D01*
G01X349929Y198310D01*
X351228Y201309D01*
G01X344047Y186736D02*
Y187830D01*
X347273Y191056D01*
Y198785D01*
X347848Y199360D01*
G01X338092Y182563D02*
Y184551D01*
X338606Y185065D01*
Y190180D01*
X340792Y192366D01*
Y199064D01*
X341088Y199360D01*
G01X342062Y182619D02*
Y188442D01*
X345178Y191558D01*
Y196699D01*
X344468Y197409D01*
G01Y201309D02*
Y200177D01*
X342492Y198201D01*
Y195800D01*
X343083Y195209D01*
Y192060D01*
X340291Y189268D01*
Y184457D01*
X340077Y184243D01*
Y182436D01*
G01X363897Y188142D02*
Y189623D01*
X362438Y191082D01*
Y198230D01*
X362718Y198630D01*
X362868Y198880D01*
X362918Y199430D01*
X362968Y202130D01*
X364747Y205210D01*
G01X361367Y199360D02*
X361663Y199064D01*
Y190159D01*
X361912Y189910D01*
Y188639D01*
G01X361367Y207159D02*
X361030Y206016D01*
X360708Y205273D01*
X359983Y204013D01*
G03X360002Y202472I1384J-754D01*
G02X360027Y200189I-2015J-1164D01*
G01X360002Y200147D01*
X359983Y200113D01*
G03X360002Y198572I1384J-754D01*
G02X360418Y197020I-2686J-1552D01*
G01Y191554D01*
X359927Y191063D01*
Y189913D01*
G01X357987Y205210D02*
Y206310D01*
G02X358368Y207230I1301J0D01*
G01X358467Y207329D01*
G02X359001Y207550I534J-535D01*
G01X359037D01*
G02X359849Y206738I0J-812D01*
G01Y205284D01*
X359847Y205282D01*
X359352Y204423D01*
G03Y202097I2015J-1163D01*
G02X359371Y200556I-1365J-787D01*
G01X359352Y200522D01*
X359327Y200480D01*
G03X359352Y198197I2040J-1119D01*
G02X359592Y197301I-1553J-896D01*
G01Y192596D01*
X357942Y190946D01*
Y189634D01*
G01X355957Y185958D02*
Y187613D01*
X356218Y187874D01*
Y197580D01*
X357987Y201309D01*
G01X351987Y186312D02*
Y187393D01*
X353070Y188476D01*
Y199705D01*
G02X353243Y200147I1536J-346D01*
G01X353278Y200207D01*
G03X353243Y202473I-2050J1102D01*
G02Y204047I1364J787D01*
G01X353306Y204155D01*
X354607Y207159D01*
G01X334979Y194854D02*
X336661Y197370D01*
Y199855D01*
X336223Y200614D01*
Y201780D01*
X336703Y202612D01*
Y203886D01*
X336187Y204776D01*
Y205572D01*
G02X336203Y205677I355J0D01*
G02X336343Y205997I1505J-468D01*
G01X336368Y206039D01*
G03X336343Y208322I-2040J1119D01*
G01X336324Y208356D01*
G02X336343Y209897I1384J754D01*
G03X334613Y213369I-2015J1163D01*
G01X334328Y213654D01*
Y214960D01*
G01X310668Y201309D02*
Y200003D01*
X310384Y199719D01*
G03X310300Y199707I287J-2309D01*
G03X308653Y198573I368J-2298D01*
G03X308340Y197383I2014J-1166D01*
G01X308342Y197381D01*
Y195335D01*
X307858Y194851D01*
X307502D01*
G01X327568Y211060D02*
X326202Y207947D01*
G03X326183Y206406I1366J-787D01*
G01X326202Y206372D01*
G02X326462Y205832I-4266J-2387D01*
G02X326823Y203988I-4527J-1844D01*
G01Y197941D01*
X326529Y197647D01*
Y197141D01*
G01X320808Y211060D02*
X321892D01*
X322392Y210560D01*
Y210118D01*
G03X322850Y208383I3516J0D01*
G02X323212Y207216I-2486J-1411D01*
G01X324188Y209109D02*
X325486Y206112D01*
X325553Y205997D01*
G02X325798Y205056I-1683J-941D01*
G01Y199516D01*
X325329Y199047D01*
Y197141D01*
G01X334328Y211060D02*
Y212366D01*
X334577Y212615D01*
G02X335693Y210272I-249J-1556D01*
G03Y207946I2015J-1163D01*
G02Y206372I-1365J-787D01*
G01X335668Y206330D01*
G03X335523Y206012I2039J-1122D01*
G01X335483Y205903D01*
G03X335422Y205561I930J-342D01*
G01Y204433D01*
X335953Y203514D01*
Y202814D01*
X335473Y201982D01*
Y200412D01*
X335911Y199653D01*
Y198318D01*
X333729Y196136D01*
Y195141D01*
G01X320749Y209485D02*
X321247D01*
X321703Y209213D01*
X321992Y208372D01*
G03X322323Y207611I3949J1265D01*
G02X322438Y207171I-786J-440D01*
G02X322315Y206677I-1059J1D01*
G01X322142Y206348D01*
G03X321860Y205214I2163J-1140D01*
G01Y204401D01*
X322365Y203527D01*
Y202799D01*
X321872Y201945D01*
Y200643D01*
X322929Y198812D01*
Y197141D01*
G01X324188Y216909D02*
X322889Y213910D01*
X322823Y213797D01*
G02X320893Y212635I-2015J1163D01*
G01X320764D01*
G03X320749Y209485I44J-1575D01*
G01X330948Y209109D02*
G02X331292Y210164I1792J-1D01*
G01X331719Y210286D01*
X332008Y210240D01*
G02X332313Y209897I-677J-909D01*
G02Y208323I-1365J-787D01*
G03X332001Y207156I2015J-1164D01*
G01D02*
Y206683D01*
G01D02*
X332445Y205914D01*
Y204543D01*
X332087Y203923D01*
Y202390D01*
X332536Y201611D01*
Y200939D01*
X331329Y198215D01*
Y197141D01*
G01X330948Y216909D02*
X332247Y213910D01*
X332313Y213797D01*
G02X332332Y212256I-1365J-787D01*
G01X332313Y212222D01*
Y211424D01*
X332963Y210272D01*
G02Y207946I-2015J-1163D01*
G03X332752Y207158I1365J-788D01*
G01Y206907D01*
X333195Y206144D01*
Y204341D01*
X332837Y203721D01*
Y202591D01*
X333286Y201813D01*
Y200780D01*
X332529Y198950D01*
Y197141D01*
G01X300529Y261760D02*
X298279D01*
G01X297149Y232509D02*
X294899D01*
G01X300529Y230559D02*
X298279D01*
G01X303909Y244209D02*
X301659D01*
G01X307289Y242260D02*
X305039D01*
G01X297149Y236409D02*
X294899D01*
G01X303909Y232509D02*
X301659D01*
G01X314048Y230559D02*
X311798D01*
G01X320808Y234460D02*
X318558D01*
G01X320808Y222760D02*
X318558D01*
G01X324188Y224709D02*
X321938D01*
G01X307289Y257860D02*
X305039D01*
G01X314048Y234460D02*
X311798D01*
G01X317428Y236409D02*
X315178D01*
G01X317428Y224709D02*
X315178D01*
G01X324188Y228610D02*
X321938D01*
G01X330948Y255909D02*
X328698D01*
G01X341088Y257860D02*
X338838D01*
G01X341088Y261760D02*
X338838D01*
G01X327568D02*
X325318D01*
G01X297149Y252009D02*
X294899D01*
G01X337708Y255909D02*
X335458D01*
G01X337708Y263709D02*
X335458D01*
G01X300529Y250060D02*
X298279D01*
G01X303909Y263709D02*
X301659D01*
G01X307289Y261760D02*
X305039D01*
G01X297149Y255909D02*
X294899D01*
G01X303909Y252009D02*
X301659D01*
G01X300529Y242260D02*
X298279D01*
G01X307289Y238360D02*
X305039D01*
G01X307289Y253960D02*
X305039D01*
G01X297149Y240309D02*
X294899D01*
G01X314048Y226660D02*
X311798D01*
G01X317428Y263709D02*
X315178D01*
G01X307289Y234460D02*
X305039D01*
G01X324188Y232509D02*
X321938D01*
G01X317428Y275409D02*
X315178D01*
G01X297149Y259809D02*
X294899D01*
G01X303909Y255909D02*
X301659D01*
G01X300529Y238360D02*
X298279D01*
G01X317428Y228610D02*
X315178D01*
G01X334328Y257860D02*
X332078D01*
G01X317428Y267609D02*
X315178D01*
G01X303909Y236409D02*
X301659D01*
G01X320808Y230559D02*
X318558D01*
G01X317428Y271509D02*
X315178D01*
G01X300529Y257860D02*
X298279D01*
G01X314048Y265660D02*
X311798D01*
G01X324188Y271509D02*
X321938D01*
G01X310668Y267609D02*
X308418D01*
G01X320808Y265660D02*
X318558D01*
G01X354607Y246160D02*
X352357D01*
G01X347848D02*
X345598D01*
G01X330948Y337809D02*
X328698D01*
G01X354607Y386560D02*
G02X352787Y392189I4864J4681D01*
G03X352592Y393197I-1559J221D01*
G03X350621Y394678I-2722J-1571D01*
G02X349396Y397964I2097J2653D01*
G03X349232Y399013I-1548J295D01*
G02X349212Y399045I450J304D01*
G02X348592Y401358I4003J2313D01*
G01Y403700D01*
X349574Y404682D01*
Y406130D01*
G01X351228Y396309D02*
X349931Y399305D01*
X349863Y399422D01*
G02X349787Y399595I1541J780D01*
G02X349662Y400185I1440J613D01*
G02X349661Y400197I1555J136D01*
G01X349652Y401441D01*
X349492Y401601D01*
Y403400D01*
X351669Y405577D01*
Y407377D01*
G01X347479Y405432D02*
Y399912D01*
X347848Y399543D01*
Y398260D01*
G01X344468Y400209D02*
X345384Y401125D01*
Y403714D01*
G01X347848Y390460D02*
X346043Y392841D01*
Y397215D01*
X345062Y398196D01*
X344248D01*
X342784Y399660D01*
Y401456D01*
X343091Y401763D01*
Y402909D01*
G01X344468Y392410D02*
X342165Y394713D01*
X341406D01*
X340523Y395324D01*
X340192Y396021D01*
Y400306D01*
X340996Y401110D01*
Y402882D01*
G01X354607Y398260D02*
Y404716D01*
X357954Y408063D01*
Y408976D01*
G01X354607Y390460D02*
G03X353268Y393530I-12824J-3766D01*
G01X353243Y393572D01*
G02X353058Y394641I1364J787D01*
G03X352592Y397096I-3420J623D01*
G02X352557Y399362I2015J1164D01*
G01X352592Y399422D01*
G03X352803Y400229I-1364J788D01*
G01Y406539D01*
X353764Y407500D01*
Y408372D01*
G01X357987Y392410D02*
G02X355972Y395146I11179J10343D01*
G03X355169Y395831I-1365J-787D01*
G02X353243Y397473I1349J3533D01*
G02X353268Y399088I1539J784D01*
G03X353555Y400214I-2040J1120D01*
G01Y405361D01*
X355859Y407665D01*
Y408774D01*
G01X303909Y396309D02*
X305641Y398041D01*
Y401796D01*
X305472Y401965D01*
G01X307289Y398260D02*
Y401846D01*
X307071Y402064D01*
G01X317428Y392410D02*
X315599Y394871D01*
G02X315413Y397472I1829J1438D01*
G03X315422Y398835I-1195J689D01*
G01X315331Y398998D01*
X315006Y399544D01*
G02X314858Y400083I906J539D01*
G01Y406163D01*
X314714Y406307D01*
G01X317428Y396309D02*
X316294Y398924D01*
G03X316273Y398964I-323J-144D01*
G01X316016Y399396D01*
X315608Y400126D01*
Y407181D01*
X315498Y407291D01*
G01X303909Y392410D02*
X302769Y394989D01*
G03X302544Y395522I-2240J-631D01*
G01X302525Y395556D01*
G02X302544Y397097I1384J754D01*
G03X302569Y399380I-2015J1164D01*
G01X302481Y399537D01*
X301751Y400837D01*
X300498Y402090D01*
Y402459D01*
G01X314048Y390460D02*
X312750Y393457D01*
X312683Y393572D01*
G02Y395146I1365J787D01*
G03Y397472I-2015J1163D01*
G02X312664Y399013I1365J787D01*
G01X312683Y399047D01*
X312718Y399107D01*
G03X313088Y400578I-2738J1471D01*
G01Y404537D01*
X312666Y404959D01*
G01X314048Y398260D02*
Y405275D01*
X313748Y405575D01*
G01X310668Y392410D02*
Y391104D01*
X310419Y390855D01*
G02X309317Y391600I249J1555D01*
G01X309304Y391623D01*
G02Y393197I1364J787D01*
G01X309329Y393239D01*
G03X309304Y395522I-2040J1119D01*
G02Y397096I1364J787D01*
G03X309339Y399362I-2015J1164D01*
G01X309304Y399422D01*
X309285Y399456D01*
G02X309148Y399994I986J538D01*
G01Y403383D01*
X308948Y403583D01*
G01X310668Y400209D02*
Y403561D01*
X310448Y403781D01*
G01X330948Y392410D02*
X330858Y392500D01*
Y395641D01*
G01X310668Y388509D02*
Y389815D01*
X310382Y390101D01*
G02X310300Y390113I296J2307D01*
G02X308653Y391247I368J2297D01*
G02X308628Y393530I2015J1164D01*
G01X308653Y393572D01*
G03Y395146I-1364J787D01*
G01X308628Y395188D01*
G02X308653Y397473I2040J1120D01*
G03Y399047I-1364J787D01*
G01X308627Y399096D01*
X308624D01*
G02X308343Y400190I2045J1108D01*
G01Y402490D01*
X308248Y402585D01*
G01X310668Y396309D02*
X311967Y399309D01*
X312032Y399421D01*
G03X312019Y401205I-1527J881D01*
G01X311940Y401338D01*
X311418Y404509D01*
X311367Y404560D01*
G01X337708Y384609D02*
Y384612D01*
X335826Y387140D01*
G02X335693Y389672I1882J1368D01*
G03X335709Y391013I-1188J685D01*
G01X335326Y391716D01*
Y393976D01*
X335658Y394308D01*
Y395641D01*
G01X337708Y388509D02*
X336598Y390998D01*
X336233Y391662D01*
Y393528D01*
X336908Y394203D01*
Y395641D01*
G01X334328Y382660D02*
X332803Y384185D01*
Y388160D01*
X333222Y388579D01*
Y389285D01*
G02X332944Y391213I1151J1150D01*
G01X332963Y391247D01*
X332998Y391307D01*
G03X333275Y392422I-2050J1101D01*
G01Y394162D01*
X333258Y394179D01*
Y395641D01*
G01X334328Y390460D02*
X334333Y390465D01*
Y394994D01*
X334458Y395119D01*
Y395641D01*
G01X361367Y390460D02*
X359392Y393100D01*
X358492Y394000D01*
X357142Y394979D01*
G02X356411Y396300I845J1330D01*
G01X356103Y398706D01*
G03X355692Y399300I-2849J-1532D01*
G01X355592Y399600D01*
Y404300D01*
X360049Y408757D01*
Y409566D01*
G01X364747Y396309D02*
X361655Y396668D01*
G03X361418Y396685I-285J-2309D01*
G01X361308D01*
G02X359983Y399013I59J1575D01*
G03X360492Y400452I-1779J1439D01*
G01Y403700D01*
X366334Y409542D01*
Y410519D01*
G01X361367Y398260D02*
Y402875D01*
X368429Y409937D01*
Y410774D01*
G01X364747Y392410D02*
X362732Y395146D01*
G03X361411Y395934I-1365J-787D01*
G01X361316D01*
G02X359327Y399380I51J2326D01*
G01X359352Y399422D01*
X359371Y399456D01*
G03X359563Y400212I-1384J754D01*
G01Y404571D01*
X364239Y409247D01*
Y410143D01*
G01X357987Y396309D02*
X356690Y399305D01*
X356622Y399422D01*
G02X356409Y400206I1360J790D01*
G01Y403517D01*
X362144Y409252D01*
Y410009D01*
G01X384377Y180486D02*
Y181598D01*
X385718Y182939D01*
Y189374D01*
X381647Y193445D01*
Y199360D01*
G01X378422Y181266D02*
Y181343D01*
X378218Y181547D01*
Y182577D01*
X379352Y183711D01*
Y190140D01*
X376518Y192974D01*
Y197534D01*
X376901Y198196D01*
X376902Y198197D01*
G03X376927Y200480I-2015J1164D01*
G03X374957Y201685I-2039J-1120D01*
G01X374828D01*
G02X373522Y202472I59J1575D01*
G03X371876Y203606I-2015J-1163D01*
G03X371793Y203618I-374J-2296D01*
G01X371507Y203904D01*
Y205210D01*
G01X368127Y211060D02*
Y209755D01*
X368411Y209471D01*
G02X368495Y209459I-287J-2309D01*
G02X370142Y205998I-368J-2298D01*
G03Y204424I1365J-787D01*
G02Y202098I-2015J-1163D01*
G03Y200524I1365J-787D01*
G02Y198198I-2015J-1163D01*
G03X369932Y197399I1365J-786D01*
G01Y196460D01*
X370492Y195900D01*
Y192099D01*
X372026Y190565D01*
Y182832D01*
X372152Y182706D01*
G01X374887Y199360D02*
X374352D01*
X373890Y198898D01*
Y198302D01*
X374214Y197978D01*
Y195836D01*
X372961Y194583D01*
Y192767D01*
X374312Y191416D01*
Y189552D01*
X374813Y189051D01*
X376256D01*
X377045Y188262D01*
Y185990D01*
X376256Y185201D01*
X375461D01*
X375111Y184851D01*
Y183281D01*
X375287Y183105D01*
G01X368127Y199360D02*
X367176Y198811D01*
X367036Y198335D01*
X367490Y197448D01*
Y191503D01*
X368817Y190176D01*
Y184820D01*
X369017Y184620D01*
Y184533D01*
G01X377272Y181268D02*
Y181276D01*
X377468Y181472D01*
Y182888D01*
X378602Y184022D01*
Y189829D01*
X375768Y192663D01*
Y197736D01*
X376252Y198573D01*
G03X376268Y200118I-1365J787D01*
G03X374931Y200935I-1381J-758D01*
G01X374802D01*
G02X372872Y202097I85J2325D01*
G03X371757Y202865I-1365J-788D01*
G01X371507Y202615D01*
Y201309D01*
G01X368127Y207159D02*
Y208467D01*
X368376Y208716D01*
G02X369492Y206374I-249J-1556D01*
G03Y204048I2015J-1163D01*
G02Y202474I-1365J-787D01*
G03Y200148I2015J-1163D01*
G01Y200149D01*
G02Y198573I-1365J-788D01*
G03X369180Y197393I2014J-1164D01*
G01X369182Y197391D01*
Y196149D01*
X369742Y195589D01*
Y191788D01*
X371276Y190254D01*
Y182960D01*
X371002Y182686D01*
G01X371507Y197409D02*
Y197415D01*
X372314Y198222D01*
X372909D01*
X373464Y197667D01*
Y196147D01*
X372211Y194894D01*
Y192456D01*
X373562Y191105D01*
Y189241D01*
X374502Y188301D01*
X375945D01*
X376295Y187951D01*
Y186301D01*
X375945Y185951D01*
X375150D01*
X374361Y185162D01*
Y183373D01*
X374137Y183149D01*
Y183105D01*
G01X364747Y197409D02*
X365876Y198061D01*
X366310D01*
X366357Y198014D01*
X366740Y197267D01*
Y191192D01*
X368067Y189865D01*
Y184733D01*
X367867Y184533D01*
G01X381647Y207159D02*
X382792Y206014D01*
Y205358D01*
X384700Y203450D01*
X385058D01*
X386363Y202145D01*
G02X385401Y199778I-1336J-836D01*
G01X384838Y199419D01*
X384207Y198915D01*
X383662Y198197D01*
G03X383419Y197301I1572J-907D01*
G01Y194673D01*
X388347Y189745D01*
Y179613D01*
G01X391787Y205210D02*
X390488Y202211D01*
X390422Y202097D01*
G03X390403Y200556I1365J-787D01*
G01X390422Y200522D01*
X390447Y200480D01*
G02X390422Y198197I-2040J-1119D01*
G03X390128Y197100I1901J-1097D01*
G01Y195534D01*
X392862Y192800D01*
X394392D01*
X398272Y188920D01*
Y187498D01*
G01X406212Y190701D02*
Y192655D01*
X401239Y197628D01*
X400495Y198688D01*
X398546Y201309D01*
G01X385027Y197409D02*
Y194566D01*
X390332Y189261D01*
Y186892D01*
G01X400257Y187877D02*
Y189422D01*
X394899Y194780D01*
X394431Y195700D01*
X393512Y197917D01*
X391787Y201309D01*
G01X421464Y210346D02*
X419577Y207849D01*
G03X419427Y207621I1886J-1404D01*
G03Y205271I2037J-1175D01*
G02Y203827I-1251J-722D01*
G01X418567Y202336D01*
Y198424D01*
X419723Y197268D01*
Y196112D01*
G01X378267Y205210D02*
X380072Y203405D01*
Y199403D01*
G03X380535Y198239I1584J-44D01*
G01X380708Y198066D01*
Y192884D01*
X383818Y189774D01*
Y183175D01*
X382392Y181749D01*
Y180801D01*
G01X385027Y205210D02*
X386827Y203410D01*
Y203046D01*
G03X387042Y202472I1829J358D01*
G02X387067Y200189I-2015J-1164D01*
G01X387042Y200147D01*
X387023Y200113D01*
G03X386768Y199111I1840J-1002D01*
G01Y194425D01*
X392317Y188876D01*
Y187013D01*
G01X385027Y201309D02*
X382558Y198046D01*
Y194035D01*
X387018Y189575D01*
Y182069D01*
X386362Y181413D01*
Y180000D01*
G01X388407Y199360D02*
Y194286D01*
X394302Y188391D01*
Y187013D01*
G01X402242Y188251D02*
Y190450D01*
X398104Y194588D01*
X396604D01*
X395357Y195835D01*
X394900Y196624D01*
G02X394749Y197702I1251J725D01*
G01X395166Y199360D01*
G01X388407Y207159D02*
X389707Y204159D01*
X389791Y204013D01*
G02X389772Y202472I-1384J-754D01*
G03X389747Y200189I2015J-1164D01*
G01X389772Y200147D01*
X389791Y200113D01*
G02X389772Y198572I-1384J-754D01*
G03X389318Y196877I2936J-1695D01*
G01Y194873D01*
X396287Y187904D01*
Y186770D01*
G01X395166Y207159D02*
X396466Y204159D01*
X396550Y204013D01*
G02X396741Y203296I-1384J-753D01*
G01Y200848D01*
X398605Y198984D01*
G02X399915Y198140I-57J-1527D01*
G01X400477Y197184D01*
Y195216D01*
X404227Y191466D01*
Y189513D01*
G01X378267Y201309D02*
X379892Y197557D01*
Y192300D01*
X382218Y189974D01*
Y184195D01*
X380407Y182384D01*
Y181141D01*
G01X381647Y211060D02*
X380392Y209805D01*
Y208154D01*
X379397Y207159D01*
G01X361367Y246160D02*
X359117D01*
G01X387967Y411056D02*
Y409275D01*
X381647Y402955D01*
Y398260D01*
G01X371507Y396309D02*
X372014Y395802D01*
G02X371461Y394721I-451J-451D01*
G01X371257Y394754D01*
G02X370142Y397097I250J1556D01*
G03X370167Y399380I-2015J1164D01*
G01X370135Y399434D01*
X369968Y399773D01*
Y401075D01*
X378099Y409206D01*
Y409853D01*
X378299Y410053D01*
G01X370423Y410490D02*
X370623Y410290D01*
Y409892D01*
X362468Y401737D01*
Y399505D01*
X362732Y399047D01*
G03X364693Y397884I2015J1162D01*
G01X364806D01*
G02X366131Y395556I-59J-1575D01*
G01X366112Y395522D01*
G03X366087Y393239I2015J-1164D01*
G01X366112Y393197D01*
G02Y391623I-1365J-787D01*
G03X366178Y389187I2014J-1164D01*
G01X366933Y388030D01*
G03X368127Y386560I7676J5015D01*
G01X371507Y400209D02*
X371954Y399761D01*
G02X372561Y398297I-1464J-1465D01*
G03X374057Y396087I2326J-37D01*
G03X376927Y399380I830J2173D01*
G01X376924Y399385D01*
X376643Y399947D01*
Y403442D01*
X381293Y408092D01*
Y409839D01*
X381500Y410046D01*
Y410133D01*
G01X364747Y400209D02*
X365356Y399600D01*
X366082D01*
X366443Y399961D01*
Y401645D01*
X374192Y409394D01*
Y409904D01*
X374010Y410086D01*
Y410158D01*
G01X371507Y392410D02*
G03X370847Y393824I-1845J0D01*
G01X370012Y394524D01*
G02X369492Y397472I1494J1783D01*
G03X369511Y399013I-1365J787D01*
G01X369492Y399047D01*
X369476Y399073D01*
X369475D01*
X369474Y399076D01*
X369218Y399598D01*
Y401386D01*
X377349Y409517D01*
Y409786D01*
X377149Y409986D01*
Y410073D01*
G01X371573Y410262D02*
X371373Y410062D01*
Y409581D01*
X363218Y401426D01*
Y399706D01*
X363382Y399422D01*
G03X364703Y398634I1365J787D01*
G01X364832D01*
G02X366762Y395146I-85J-2325D01*
G03X366720Y393725I1300J-750D01*
G01X366790Y393585D01*
G02X366762Y391248I-2092J-1144D01*
G03X366807Y389597I1364J-789D01*
G01X366904Y389500D01*
G03X367892I494J494D01*
G03X368127Y390067I-567J567D01*
G01Y390460D01*
G01X374887Y398260D02*
X374161Y398987D01*
G03X373321Y398652I-348J-348D01*
G01X373312Y398302D01*
G02Y398290I-2821J-6D01*
G03X374325Y396788I1576J-30D01*
G01X374327D01*
X374328Y396787D01*
G03X376275Y399008I560J1473D01*
G01X376268Y399018D01*
X376262Y399031D01*
X375892Y399770D01*
Y403752D01*
X380543Y408403D01*
Y409920D01*
X380350Y410113D01*
Y410133D01*
G01X368127Y398260D02*
X367193Y399194D01*
Y401334D01*
X374942Y409083D01*
Y409935D01*
X375160Y410153D01*
Y410161D01*
G01X385027Y400209D02*
X386592Y401774D01*
Y403300D01*
X394267Y410975D01*
Y413053D01*
G01X402092Y416028D02*
Y412501D01*
X393386Y403795D01*
Y400304D01*
G02X393170Y399456I-1772J0D01*
G01X393151Y399422D01*
X393116Y399362D01*
G03X392994Y399096I2050J-1101D01*
G01X391787Y396309D01*
G01X401863Y404972D02*
X400192Y403301D01*
Y400463D01*
G02X399911Y399422I-2067J0D01*
G01X399843Y399305D01*
X398692Y396646D01*
X398546Y396309D01*
G01Y392410D02*
X398692Y392606D01*
X400496Y395032D01*
X400561Y395146D01*
G03Y397472I-2015J1163D01*
G02X400542Y399013I1365J787D01*
G01X400561Y399047D01*
G02X400978Y399614I2480J-1387D01*
G01X401092Y399728D01*
Y401500D01*
X401792Y402200D01*
X402192D01*
G01X396367Y413753D02*
Y411976D01*
X387692Y403301D01*
Y399889D01*
X386603Y398800D01*
Y395711D01*
X385892Y395000D01*
Y393275D01*
X385027Y392410D01*
G01X391787D02*
X393802Y395146D01*
X393827Y395188D01*
G03X393802Y397473I-2040J1120D01*
G02Y399047I1364J787D01*
G01X393837Y399107D01*
X394553Y399823D01*
Y403661D01*
X404077Y413185D01*
Y417443D01*
G01X405306Y384609D02*
X406781Y388008D01*
Y390855D01*
X408326Y392400D01*
X411354D01*
X413642Y394688D01*
Y396123D01*
G01X385867Y410585D02*
Y408475D01*
X380792Y403400D01*
Y400412D01*
G02X380317Y399107I-2030J0D01*
G01X380282Y399047D01*
X380263Y399013D01*
G03X380282Y397472I1384J-754D01*
G02X380172Y394972I-2015J-1164D01*
G01X378267Y392410D01*
G01X385027Y396309D02*
Y398040D01*
X383687Y399380D01*
X383662Y399422D01*
G02X383452Y400208I1365J786D01*
G01X383760Y401872D01*
X392167Y410279D01*
Y411853D01*
G01X381647Y390460D02*
X382987Y393530D01*
X383012Y393572D01*
G03Y395146I-1365J787D01*
G02Y397472I2015J1163D01*
G03X383031Y399013I-1365J787D01*
G01X383012Y399047D01*
G02X382701Y400211I2015J1162D01*
G01Y402209D01*
X390067Y409575D01*
Y410927D01*
G01X398122Y414698D02*
X398527Y414293D01*
Y412935D01*
X388854Y403262D01*
Y398707D01*
X388407Y398260D01*
G01X406062Y417690D02*
Y413969D01*
X395753Y403660D01*
Y399771D01*
X395166Y398260D01*
G01X388407Y390460D02*
Y391184D01*
X386848Y392743D01*
Y394856D01*
X386932Y394940D01*
Y394971D01*
X387795Y395834D01*
X387826D01*
X388192Y396200D01*
X388992D01*
X390118Y397326D01*
Y403426D01*
X391292Y404600D01*
X392253D01*
X400107Y412454D01*
Y415513D01*
G01X395166Y390460D02*
X396186Y392813D01*
G03X396942Y396455I-8398J3643D01*
G01Y403549D01*
X408047Y414654D01*
Y418266D01*
G01X378267Y396309D02*
X379475Y399095D01*
G02X379607Y399380I2172J-833D01*
G01X379632Y399422D01*
X379651Y399456D01*
G03X379843Y400214I-1384J754D01*
G01Y404100D01*
X383767Y408024D01*
Y410585D01*
G01X424844Y204496D02*
X424398Y204050D01*
Y196137D01*
X424423Y196112D01*
G01X424844Y212296D02*
X423858Y211310D01*
Y210002D01*
X423501Y209171D01*
G02X421551Y207996I-2037J1175D01*
G01X421422D01*
G03X420121Y205671I42J-1550D01*
G02Y203427I-1945J-1122D01*
G01X419368Y202121D01*
Y199423D01*
X421323Y197468D01*
Y196112D01*
G01X431604Y204496D02*
X432354Y203746D01*
Y197769D01*
X432173Y197588D01*
Y196112D01*
G01X428224Y202547D02*
Y203852D01*
X427975Y204101D01*
G03X426882Y203370I250J-1556D01*
G03X426739Y202864I823J-506D01*
G01Y201373D01*
X427168Y200625D01*
Y199300D01*
X427568Y198900D01*
Y198300D01*
X427168Y197900D01*
Y196467D01*
X427523Y196112D01*
G01X421464Y206447D02*
X421652Y206260D01*
X422792Y205119D01*
Y204077D01*
X423648Y203221D01*
Y198055D01*
X422873Y197280D01*
G01X434983Y206447D02*
X436559Y202807D01*
Y197992D01*
X435273Y196706D01*
Y196112D01*
G01X434983Y210346D02*
X436809Y206131D01*
Y204409D01*
G03X436979Y203743I1391J0D01*
G01X437309Y203153D01*
Y196548D01*
X436823Y196062D01*
G01X431604Y212296D02*
X433104Y210796D01*
Y197885D01*
X433723Y197266D01*
Y196112D01*
G01X428224Y214247D02*
G02X426420Y211814I-28053J18915D01*
G03X426465Y208824I1805J-1468D01*
G03X428139Y208021I1760J1522D01*
G01X428224D01*
G02X429588Y205659I0J-1575D01*
G03Y203333I2015J-1163D01*
G02X429797Y202637I-1363J-789D01*
G01Y202619D01*
G02X429399Y200999I-2916J-142D01*
G01X429073Y200445D01*
Y196400D01*
G01X428224Y206447D02*
X427199Y205178D01*
G03X426242Y203763I15696J-11647D01*
G01X426243D01*
G03X425989Y202864I1462J-899D01*
G01Y201173D01*
X426418Y200425D01*
Y196557D01*
X425973Y196112D01*
G01X428224Y210346D02*
Y211168D01*
X427809Y211583D01*
X427274D01*
X427109Y211418D01*
G03X427033Y209315I1092J-1092D01*
G03X428180Y208771I1191J1031D01*
G01X428309D01*
G02X430239Y205283I-85J-2325D01*
G01X430238Y205284D01*
G03Y203708I1365J-788D01*
G02X430547Y202657I-2014J-1163D01*
G01Y202655D01*
G02X430046Y200619I-3666J-178D01*
G01X429823Y200240D01*
Y199400D01*
X430223Y199000D01*
Y198400D01*
X429823Y198000D01*
Y197200D01*
X430623Y196400D01*
G01X441743Y206447D02*
X443018D01*
X443418Y206047D01*
Y203615D01*
X444035Y202998D01*
Y199724D01*
X443398Y199087D01*
Y196291D01*
G01X445123Y204496D02*
X444785Y204158D01*
Y197256D01*
X444948Y197093D01*
Y196691D01*
G01X441743Y210346D02*
X439793Y207722D01*
X439728Y207609D01*
G03Y205283I2015J-1163D01*
G02Y203709I-1365J-787D01*
G03X439398Y202478I2131J-1231D01*
G01Y198901D01*
X440638Y197661D01*
Y196745D01*
X440298Y196405D01*
G01X445123Y212296D02*
X443478Y209732D01*
G02X441828Y208021I-1713J0D01*
G01X441699D01*
G03X440378Y205659I44J-1575D01*
G02Y203333I-2015J-1163D01*
G03X440148Y202474I1488J-859D01*
G01Y199209D01*
X441386Y197971D01*
Y196707D01*
X441848Y196245D01*
G01X448503Y202547D02*
Y203852D01*
X448254Y204101D01*
G03X446993Y202622I237J-1479D01*
G01Y201356D01*
X447642Y200707D01*
Y195749D01*
X448048Y195343D01*
G01X448503Y214247D02*
X446655Y211764D01*
G03X448418Y208021I1846J-1417D01*
G01X448547D01*
G02X449868Y205659I-44J-1575D01*
G01Y205660D01*
G03Y203334I2015J-1163D01*
G02X449988Y202886I-776J-448D01*
G01Y195695D01*
X449598Y195305D01*
G01X448503Y206447D02*
Y205140D01*
X448136Y204842D01*
G03X446243Y202623I355J-2220D01*
G01Y201045D01*
X446892Y200396D01*
Y195699D01*
X446498Y195305D01*
G01X448503Y210346D02*
X448112Y211544D01*
X447787Y211749D01*
G03X447253Y211305I715J-1403D01*
G03X448459Y208771I1249J-959D01*
G01X448588D01*
G02X450518Y205283I-85J-2325D01*
G01X450517D01*
G03X450518Y203709I1366J-786D01*
G02X450738Y202885I-1426J-822D01*
G01Y195654D01*
X451148Y195244D01*
G01X455263Y206447D02*
X456741Y203033D01*
Y201854D01*
X456315Y201117D01*
Y199836D01*
X456838Y198930D01*
Y197096D01*
X455798Y196056D01*
G01X455263Y210346D02*
X456563Y207346D01*
X456628Y207234D01*
G02X457067Y204491I-8350J-2743D01*
G03X457259Y203743I1576J6D01*
G01X457491Y203329D01*
Y201653D01*
X457065Y200915D01*
Y200036D01*
X458088Y198262D01*
Y197401D01*
G01X451883Y204496D02*
X452398Y203981D01*
Y196994D01*
X452698Y196694D01*
G01X451883Y212296D02*
X453181Y209299D01*
X453248Y209184D01*
G02Y207610I-1365J-787D01*
G03Y205284I2015J-1163D01*
G02X453267Y203743I-1365J-787D01*
G01X453148Y203530D01*
Y198845D01*
X453598Y198395D01*
Y197393D01*
X454248Y196743D01*
G01X462023Y206447D02*
X463588Y204882D01*
Y203872D01*
X464248Y203212D01*
Y194574D01*
G01X465403Y204496D02*
X464998Y204091D01*
Y196017D01*
X465641Y195374D01*
G01X475542Y206447D02*
X476773Y203604D01*
G03X476907Y203333I2148J894D01*
G01X478244Y201006D01*
Y198122D01*
X479179Y197187D01*
G01X475542Y210346D02*
X476842Y207346D01*
X476926Y207200D01*
G02X476907Y205659I-1384J-754D01*
G01X477557Y203709D01*
X478994Y201215D01*
Y199171D01*
X479565Y198600D01*
X479959D01*
G01X462023Y210346D02*
X460073Y207724D01*
X460008Y207610D01*
G03Y205284I2015J-1163D01*
G02X460219Y204494I-1365J-788D01*
G01Y203993D01*
X459751Y203183D01*
Y201719D01*
X460215Y200914D01*
Y200080D01*
X459604Y199022D01*
Y196785D01*
X461668Y194721D01*
Y193459D01*
X462078Y193049D01*
Y192358D01*
G01X465403Y212296D02*
X464105Y209299D01*
X464038Y209184D01*
G02X462093Y208021I-2015J1162D01*
G01X461952D01*
G03X460658Y205659I71J-1574D01*
G02X460970Y204491I-2015J-1164D01*
G01Y203769D02*
Y204491D01*
G01Y203769D02*
X460501Y202956D01*
Y201931D01*
X460965Y201126D01*
Y199879D01*
X460354Y198820D01*
Y197097D01*
X462418Y195033D01*
Y193771D01*
X462718Y193471D01*
X463158D01*
G01X472163Y204496D02*
X472888Y203771D01*
Y198531D01*
X474568Y196851D01*
X475129D01*
X475939Y196041D01*
G01X472163Y212296D02*
X473638Y210821D01*
Y198842D01*
X474879Y197601D01*
X476572D01*
X476865Y197308D01*
G01X468783Y202547D02*
Y203852D01*
X468534Y204101D01*
G03X467687Y203677I249J-1556D01*
G01X467686Y203679D01*
X467620Y203615D01*
G03X467342Y201622I1139J-1175D01*
G01X467778Y200869D01*
Y197018D01*
X471296Y193500D01*
X471901D01*
G01X468783Y214247D02*
X467784Y212130D01*
X467307D01*
X466917Y211740D01*
X466889Y211701D01*
G03X468698Y208021I1893J-1354D01*
G01X468783D01*
G02X470147Y205659I0J-1575D01*
G03Y203333I2015J-1163D01*
G01X470148Y203334D01*
X470171Y203294D01*
G02X470170Y201683I-1396J-805D01*
G01X470171Y201682D01*
X469805Y201047D01*
Y197482D01*
X472587Y194700D01*
X472894D01*
X473195Y194399D01*
G01X468783Y206447D02*
G02X467164Y204218I-7840J3992D01*
G01X467098Y204154D01*
G03X466692Y201246I1661J-1714D01*
G01X467028Y200667D01*
Y196707D01*
X470692Y193043D01*
Y192517D01*
G01X468783Y210346D02*
X468189Y211380D01*
X467618D01*
X467503Y211265D01*
Y211262D01*
G03X468739Y208771I1281J-917D01*
G01X468868D01*
G02X470798Y205283I-85J-2325D01*
G03Y203709I1364J-787D01*
G01X470821Y203669D01*
G02Y201307I-2046J-1181D01*
G01X470555Y200846D01*
Y197793D01*
X472748Y195600D01*
X474187D01*
G01X428224Y233746D02*
X425974D01*
G01X428224Y241547D02*
X425974D01*
G01X438363Y235696D02*
X436113D01*
G01X438363Y239596D02*
X436113D01*
G01X424844Y235696D02*
X422594D01*
G01X424844Y239596D02*
X422594D01*
G01X434983Y233746D02*
X432733D01*
G01X434983Y241547D02*
X432733D01*
G01X448503Y233746D02*
X446253D01*
G01X448503Y241547D02*
X446253D01*
G01X458643Y235696D02*
X456393D01*
G01X458643Y239596D02*
X456393D01*
G01X445123Y235696D02*
X442873D01*
G01X445123Y239596D02*
X442873D01*
G01X455263Y233746D02*
X453013D01*
G01X455263Y241547D02*
X453013D01*
G01X458643Y247396D02*
X456393D01*
G01X458643Y255196D02*
X456393D01*
G01X468783Y249347D02*
X466533D01*
G01X468783Y253247D02*
X466533D01*
G01X455263Y249347D02*
X453013D01*
G01X455263Y253247D02*
X453013D01*
G01X465403Y247396D02*
X463153D01*
G01Y255196D02*
X465403D01*
G01X478922Y247396D02*
X476672D01*
G01X478922Y255196D02*
X476672D01*
G01X473292Y249347D02*
X475542D01*
G01Y253247D02*
X473292D01*
G01X431604Y231797D02*
X429354D01*
G01X451883D02*
X449633D01*
G01X462023Y245447D02*
X459773D01*
G01X431604Y243496D02*
X429354D01*
G01X451883D02*
X449633D01*
G01X459773Y257147D02*
X462023D01*
G01X429354Y235696D02*
X431604D01*
G01X451883D02*
X449633D01*
G01X462023Y249347D02*
X459773D01*
G01X431604Y239596D02*
X429354D01*
G01X451883D02*
X449633D01*
G01X462023Y253247D02*
X459773D01*
G01X428224Y401447D02*
X429187Y401141D01*
X430435Y401142D01*
X430718Y401425D01*
Y402120D01*
X429849Y402989D01*
G01X441743Y397546D02*
Y398852D01*
X441457Y399138D01*
G02X439703Y402567I286J2309D01*
G01X439728Y402609D01*
X439747Y402643D01*
G03X439728Y404184I-1384J754D01*
G02Y406607I2098J1211D01*
G01X441323Y409366D01*
Y409367D01*
X441324Y409369D01*
Y415400D01*
X438723Y418001D01*
Y419468D01*
X438323Y419868D01*
G01X441743Y401447D02*
Y400141D01*
X441493Y399891D01*
G02X440359Y402200I250J1556D01*
G01X440378Y402234D01*
X440403Y402276D01*
G03X440378Y404559I-2040J1119D01*
G02Y406235I1452J838D01*
G01X442074Y409170D01*
Y415818D01*
X439473Y418419D01*
Y419480D01*
X439873Y419880D01*
G01X431604Y395597D02*
X428366Y395221D01*
X428154D01*
G02X426209Y398709I70J2325D01*
G01X426228Y398743D01*
G03X426326Y400033I-1384J754D01*
G03X426208Y400284I-1413J-511D01*
G02Y402610I2015J1163D01*
G03X426227Y404151I-1365J787D01*
G01X426199Y404201D01*
G03X426136Y404280I-301J-175D01*
G01X423223Y407193D01*
Y419000D01*
X422823Y419400D01*
G01X428224Y397546D02*
X427045Y400250D01*
G03X426858Y400660I-2201J-756D01*
G01X426839Y400694D01*
G02X426858Y402235I1384J754D01*
G03X426883Y404518I-2015J1164D01*
G01X426828Y404610D01*
X426678Y404822D01*
X423973Y407527D01*
Y419000D01*
X424373Y419400D01*
G01X438363Y395597D02*
X437170Y396790D01*
Y398353D01*
X437064Y398597D01*
X436998Y398711D01*
G02Y400285I1365J787D01*
G01X437023Y400327D01*
G03X436998Y402610I-2040J1119D01*
G01X436979Y402644D01*
G02X436998Y404185I1384J754D01*
G03X437610Y406468I-3951J2283D01*
G01Y408903D01*
X438203Y409496D01*
Y414328D01*
X435623Y416908D01*
Y419100D01*
X435223Y419500D01*
G01X434983Y397546D02*
Y396241D01*
X434733Y395991D01*
G02X433618Y398333I250J1555D01*
G03Y400659I-2015J1163D01*
G02X433599Y402200I1365J787D01*
G01Y402197D01*
X433644Y402280D01*
G03X433618Y404559I-2041J1116D01*
G01X433617Y404560D01*
G02X433438Y405229I1161J669D01*
G01Y411013D01*
X430173Y414278D01*
Y419181D01*
X430573Y419581D01*
G01X434983Y393647D02*
Y394880D01*
X434614Y395249D01*
G02X432968Y398709I369J2297D01*
G01X432987Y398743D01*
G03X432968Y400284I-1384J754D01*
G02X432943Y402567I2015J1164D01*
G01X432968Y402609D01*
X432987Y402643D01*
G03X432968Y404184I-1384J754D01*
G02X432688Y405230I1810J1045D01*
G01Y410702D01*
X429423Y413967D01*
Y419231D01*
X429023Y419631D01*
G01X434983Y401447D02*
X436282Y404447D01*
X436347Y404559D01*
G03X436518Y405198I-1107J639D01*
G01Y406470D01*
X435898Y407090D01*
Y412855D01*
X433273Y415480D01*
Y419181D01*
X433673Y419581D01*
G01X448503Y401447D02*
X449634Y402099D01*
X449739Y402491D01*
G02X449868Y404559I2144J904D01*
G01X450346Y405388D01*
Y407335D01*
X449572Y408109D01*
Y416466D01*
X449172Y416866D01*
G01X451883Y403396D02*
X450752Y402744D01*
X450410Y402836D01*
G02X450518Y404184I1473J560D01*
G01X451096Y405187D01*
Y407646D01*
X450322Y408420D01*
Y416466D01*
X450722Y416866D01*
G01X462023Y397546D02*
X459939Y400411D01*
G02X459983Y402567I2084J1036D01*
G01X460008Y402609D01*
X460027Y402643D01*
G03X460008Y404184I-1384J754D01*
G02X459778Y405042I1486J858D01*
G01Y406921D01*
X461972Y409115D01*
Y416420D01*
X461572Y416820D01*
G01X462023Y401447D02*
X460790Y404292D01*
G03X460658Y404559I-2147J-896D01*
G02X460528Y405045I842J486D01*
G01Y406610D01*
X462722Y408804D01*
Y416420D01*
X463122Y416820D01*
G01X451883Y395597D02*
G03X448459Y395971I-4019J-20937D01*
G02X447138Y396759I44J1575D01*
G02X446993Y397097I1356J782D01*
G02X446931Y397646I1510J449D01*
G03X446488Y400284I-5857J373D01*
G02Y402610I2015J1163D01*
G03X446499Y404182I-1379J796D01*
G01X444751Y407178D01*
Y408860D01*
X446472Y410581D01*
Y416420D01*
X446072Y416820D01*
G01X448503Y397546D02*
G03X447138Y400660I-16771J-5495D01*
G01X447119Y400694D01*
G02X447138Y402235I1384J754D01*
G03X447132Y404587I-2027J1171D01*
G01X445501Y407378D01*
Y408509D01*
X447222Y410230D01*
Y416430D01*
X447622Y416830D01*
G01X458643Y395597D02*
X457344Y398597D01*
X457278Y398711D01*
G02Y400285I1365J787D01*
G01X457303Y400327D01*
G03X457278Y402610I-2040J1119D01*
G01X457259Y402644D01*
G02X457278Y404185I1384J754D01*
G03X457608Y405415I-2129J1230D01*
G01X457893Y405700D01*
Y408562D01*
X458845Y409514D01*
Y416493D01*
X458472Y416866D01*
G01X468783Y401447D02*
X470515Y403179D01*
Y407576D01*
X469592Y408499D01*
Y414932D01*
X470392Y415732D01*
Y416292D01*
G01X472163Y395597D02*
G03X468739Y395971I-4019J-20937D01*
G02X467418Y396759I44J1575D01*
G02X467273Y397097I1356J782D01*
G02X467211Y397646I1510J449D01*
G03X466768Y400284I-5857J373D01*
G02Y402610I2015J1163D01*
G03X466764Y404204I-1377J794D01*
G01X465292Y406728D01*
Y408899D01*
X466392Y409999D01*
Y416200D01*
X467192Y417000D01*
Y417480D01*
G01X468783Y397546D02*
G03X467418Y400660I-16771J-5495D01*
G01X467399Y400694D01*
G02X467418Y402235I1384J754D01*
G03X467412Y404587I-2027J1171D01*
G01X466078Y406870D01*
Y408521D01*
X467142Y409585D01*
Y415850D01*
X467892Y416600D01*
X468505D01*
G01X478922Y395597D02*
X477622Y398597D01*
X477538Y398743D01*
G02X477557Y400284I1384J754D01*
G03X477582Y402567I-2015J1164D01*
G01X477557Y402609D01*
X477538Y402643D01*
G02X477557Y404184I1384J754D01*
G03X477928Y405568I-2397J1384D01*
G01Y409901D01*
G01X455263Y397546D02*
X456020Y396789D01*
Y396293D01*
X455718Y395991D01*
X455013D01*
G02X453898Y398333I250J1555D01*
G03Y400659I-2015J1163D01*
G02X453879Y402200I1365J787D01*
G01X453898Y402234D01*
X453923Y402276D01*
G03X453898Y404559I-2040J1119D01*
G01X453771Y404779D01*
X453770Y404780D01*
G02X453676Y405649I940J541D01*
G01X453718Y405801D01*
Y408886D01*
X453422Y409182D01*
Y416547D01*
X453822Y416947D01*
G01X475542Y397546D02*
Y396241D01*
X475293Y395992D01*
G02X474178Y398333I249J1555D01*
G03Y400660I-2017J1164D01*
G02Y402234I1364J787D01*
G01X474177Y402236D01*
G03X474143Y404618I-2014J1162D01*
G01X473988Y404949D01*
Y409055D01*
X473542Y409501D01*
Y413350D01*
X474692Y414500D01*
G01X455263Y393647D02*
X454894Y395249D01*
G02X453248Y398709I369J2297D01*
G01X453267Y398743D01*
G03X453248Y400284I-1384J754D01*
G02X453223Y402567I2015J1164D01*
G01X453248Y402609D01*
X453267Y402643D01*
G03X453248Y404184I-1384J754D01*
G01X453121Y404404D01*
G02X452960Y405874I1589J918D01*
G01X452968Y405903D01*
Y408575D01*
X452672Y408871D01*
Y416597D01*
X452272Y416997D01*
G01X475542Y393647D02*
Y394952D01*
X475257Y395237D01*
G02X475174Y395249I291J2308D01*
G02X473527Y398709I367J2297D01*
G03Y400284I-1363J787D01*
G01X473502Y400326D01*
G02X473527Y402611I2040J1120D01*
G03Y404185I-1364J787D01*
G01X473514Y404190D01*
X473238Y404783D01*
Y408703D01*
X472792Y409149D01*
Y413732D01*
X474142Y415082D01*
G01X455263Y401447D02*
X456562Y404447D01*
X456627Y404559D01*
G03X456615Y406309I-1500J865D01*
G01X456462Y406567D01*
X456013Y407016D01*
Y409060D01*
X456522Y409569D01*
Y416547D01*
X456922Y416947D01*
G01X477492Y412900D02*
X476292Y411700D01*
Y407284D01*
X476894Y406273D01*
G02X476906Y404559I-1456J-867D01*
G01X476841Y404447D01*
X475542Y401447D01*
G01X429849Y402989D02*
Y409108D01*
X426323Y412634D01*
Y419100D01*
X425923Y419500D01*
G01X431604Y403396D02*
X430599Y404401D01*
Y409420D01*
X427073Y412946D01*
Y419100D01*
X427473Y419500D01*
G01X438363Y403396D02*
Y408536D01*
X438953Y409126D01*
Y414639D01*
X436373Y417219D01*
Y419100D01*
X436773Y419500D01*
G01X434983Y405347D02*
Y406947D01*
X435148Y407112D01*
Y412544D01*
X432523Y415169D01*
Y419169D01*
X432123Y419569D01*
G01X458643Y403396D02*
Y408251D01*
X459595Y409203D01*
Y416439D01*
X460022Y416866D01*
G01X472163Y403396D02*
Y407278D01*
X470342Y409099D01*
Y414550D01*
X471092Y415300D01*
X471593D01*
G01X455263Y405347D02*
Y409371D01*
X455772Y409880D01*
Y416535D01*
X455372Y416935D01*
G01X475542Y405347D02*
Y412082D01*
X476892Y413432D01*
G01X489062Y249347D02*
X486812D01*
G01X489062Y253247D02*
X486812D01*
G01X485682Y247396D02*
X483432D01*
G01X485682Y255196D02*
X483432D01*
G01X482302Y245447D02*
X480052D01*
G01X482302Y257147D02*
X480052D01*
G01X482302Y249347D02*
X480052D01*
G01X482302Y253247D02*
X480052D01*
G01X479948Y407535D02*
Y404523D01*
X480287Y404184D01*
G02X480306Y402643I-1365J-787D01*
G01X480287Y402609D01*
X480262Y402567D01*
G03X482016Y399138I2040J-1120D01*
G01X482302Y398852D01*
Y397546D01*
G01Y401447D02*
Y400141D01*
X482052Y399891D01*
G02X480918Y402200I250J1556D01*
G01X480937Y402234D01*
X480962Y402276D01*
G03X480937Y404559I-2040J1119D01*
G01Y404652D01*
X480748Y404841D01*
Y406141D01*
G01X481172Y364396D02*
X478922D01*
G01Y403396D02*
Y408702D01*
G01X560041Y266896D02*
Y267740D01*
X560772Y268471D01*
X561368D01*
X563439Y266400D01*
X566081D01*
X566926Y265555D01*
G01X553281Y235696D02*
Y236268D01*
G02X553667Y236939I776J0D01*
G01X553736Y236979D01*
G02X554469Y236787I270J-463D01*
G01X554646Y236483D01*
G03X554763Y236302I2010J1171D01*
G01X554762D01*
G03X556610Y235321I1898J1345D01*
G01X556705D01*
G02X558026Y234533I-44J-1575D01*
G01Y234532D01*
G03X559221Y233337I1195J0D01*
G01X564614D01*
X564731Y233220D01*
X564774D01*
G01X560041Y239596D02*
X558771Y238864D01*
X558694Y238576D01*
G03X558902Y238079I426J-114D01*
G03X559185Y238004I283J495D01*
G01X565022D01*
X565176Y238158D01*
G01X560041Y247396D02*
X558910Y246744D01*
X558819Y246403D01*
G03X559997Y245821I1223J993D01*
G01X566341D01*
X566943Y245219D01*
Y244407D01*
X567868Y243482D01*
G01X556661Y261047D02*
X558465D01*
X558839Y261421D01*
X561680D01*
X562151Y260950D01*
X574750D01*
X575600Y261800D01*
G01X560041Y270796D02*
Y269960D01*
X560780Y269221D01*
X561679D01*
X563750Y267150D01*
X566021D01*
X566926Y268055D01*
G01X553281Y239596D02*
G02X555037Y237307I-7815J-7813D01*
G01X555296Y236859D01*
G03X555375Y236736I1364J789D01*
G03X556602Y236072I1286J911D01*
G01X556699D01*
X556700Y236071D01*
X556715D01*
G02X558776Y234714I-54J-2325D01*
G01Y234532D01*
G03X559221Y234087I445J0D01*
G01X564610D01*
X564693Y234170D01*
G01X556661Y237647D02*
X557693D01*
G02X558531Y237426I0J-1699D01*
G01Y237427D01*
G03X559186Y237254I653J1147D01*
G01X565130D01*
X565176Y237208D01*
G01X556661Y245447D02*
X557270Y246056D01*
G02X558185Y245993I430J-430D01*
G03X559971Y245071I1855J1403D01*
G01X563230D01*
X563501Y244800D01*
X563999D01*
X564270Y245071D01*
X566030D01*
X566193Y244908D01*
Y244565D01*
X565124Y243496D01*
G01X560041Y259096D02*
X559354D01*
X558800Y259650D01*
Y260321D01*
X559150Y260671D01*
X561369D01*
X561840Y260200D01*
X574700D01*
X575600Y259300D01*
G01X916337Y234460D02*
X915091Y235706D01*
X913700D01*
G01X923097Y230559D02*
X918974D01*
X916649Y228234D01*
X912769D01*
X912391Y227856D01*
G01X923097Y226660D02*
X921813D01*
G03X920803Y226433I0J-2361D01*
G02X920145Y226285I-658J1390D01*
G01X919676D01*
G03X918352Y225497I41J-1576D01*
G02X916422Y224335I-2015J1163D01*
G01X912314D01*
X912120Y224141D01*
G01X923097Y222760D02*
G03X922163Y223147I-934J-934D01*
G01X919667D01*
G03X917702Y221972I72J-2351D01*
G02X916406Y221185I-1365J788D01*
G01X915039D01*
X914745Y220891D01*
X912927D01*
X912752Y221066D01*
G01X916337Y218860D02*
X915407D01*
X913547Y217000D01*
X907733D01*
G01X912120Y225291D02*
X912326Y225085D01*
X916396D01*
G03X917702Y225872I-59J1575D01*
G02X919666Y227035I2015J-1163D01*
G01X920144D01*
G03X920482Y227111I0J788D01*
G03X920142Y228610I-338J711D01*
G01X919717D01*
G01X912752Y219916D02*
X912977Y220141D01*
X915056D01*
X915350Y220435D01*
X916422D01*
G03X918352Y221597I-85J2325D01*
G02X919680Y222397I1387J-801D01*
G01X920392D01*
G02X920892Y221897I0J-500D01*
G01Y221309D01*
G02X920392Y220809I-500J0D01*
G01X919717D01*
G01X913644Y233156D02*
X914159Y232641D01*
X917256D01*
X919075Y234460D01*
X923097D01*
G01X912600Y230559D02*
X916337D01*
G01X926477Y384609D02*
X922147D01*
X920672Y386084D01*
X916783D01*
X916092Y385393D01*
G01X919717Y357309D02*
X915103D01*
G01X923097Y359260D02*
X922834Y359523D01*
X916105D01*
X915128Y360500D01*
G01X923097Y378760D02*
X916273D01*
G01X919717Y384609D02*
X917951Y382843D01*
X916133D01*
G01X923097Y363160D02*
X915213D01*
G01X919717Y365109D02*
X918326Y366500D01*
X915308D01*
G01X919717Y372909D02*
X920848Y372257D01*
X920939Y371916D01*
G02X919975Y371355I-1223J993D01*
G02X919788Y371335I-261J1554D01*
G01X919766Y371334D01*
X918500D01*
X918100Y371734D01*
X917500D01*
X917100Y371334D01*
X915721D01*
X915500Y371555D01*
G01X923097Y374860D02*
X921500Y374674D01*
X920000Y374500D01*
G02X919787Y374484I-281J2309D01*
G01X915270D01*
X915067Y374281D01*
X914980D01*
G01X923097Y370959D02*
X921500Y370775D01*
X920098Y370614D01*
G02X919802Y370584I-382J2295D01*
G01X915679D01*
X915500Y370405D01*
G01X919717Y376809D02*
X920848Y376157D01*
X920939Y375816D01*
G02X919763Y375235I-1222J994D01*
G01X919300Y375234D01*
X918100D01*
X917700Y375634D01*
X917100D01*
X916700Y375234D01*
X915197D01*
X915000Y375431D01*
G01X926477Y388509D02*
X922144D01*
X920570Y386935D01*
X916650D01*
X915642Y387943D01*
G01X912552Y210544D02*
X914738Y212730D01*
Y213361D01*
X916337Y214960D01*
G01X923097D02*
X919189D01*
X917693Y216456D01*
X915446D01*
X911349Y212359D01*
X910608D01*
G01X908991Y214500D02*
X912428D01*
X915284Y217356D01*
X917571D01*
X919075Y218860D01*
X923097D01*
G01X955056Y196641D02*
Y199770D01*
X953517Y201309D01*
G01X965256Y194707D02*
Y205559D01*
X963656Y207159D01*
G01X959346Y193691D02*
X959576D01*
X960436Y194551D01*
X961249Y195743D01*
X961681Y196536D01*
G03X961708Y198107I-1492J811D01*
G01X961657Y198209D01*
G02X961642Y200522I1965J1169D01*
G03X960276Y202887I-1366J788D01*
G02X959907Y207506I1J2324D01*
G02X959990Y207518I374J-2294D01*
G01X960276Y207804D01*
Y209109D01*
G01X960066Y192713D02*
Y193120D01*
X961016Y194070D01*
X961890Y195351D01*
X962340Y196177D01*
G03X962380Y198443I-2150J1171D01*
G01X962316Y198569D01*
X962302Y198593D01*
G02X962292Y200147I1320J786D01*
G03X960277Y203637I-2016J1163D01*
G01Y203638D01*
G02X960026Y206765I-1J1574D01*
G01X960641D01*
X960983Y206423D01*
Y205917D01*
X960276Y205210D01*
G01X956897Y207159D02*
X955532Y204047D01*
G02X953587Y202884I-2015J1162D01*
G01X953458D01*
G03X952133Y200556I59J-1575D01*
G01X952152Y200522D01*
X952177Y200480D01*
G02X952152Y198197I-2040J-1119D01*
G03X951943Y197489I1365J-788D01*
G01X951025Y196571D01*
X950091Y196126D01*
G01X956897Y398260D02*
Y401846D01*
X956679Y402064D01*
G01X956897Y390460D02*
X953578Y390084D01*
G02X951477Y393530I-61J2326D01*
G01X951502Y393572D01*
G03Y395146I-1365J787D01*
G02Y397472I2015J1163D01*
G03X951521Y399013I-1365J787D01*
G01X950751Y400385D01*
X949545Y401591D01*
X949206D01*
G01X963656Y390460D02*
X962358Y393457D01*
X962291Y393572D01*
G02Y395146I1365J787D01*
G03Y397472I-2015J1163D01*
G02X962272Y399013I1365J787D01*
G01X962291Y399047D01*
X962326Y399107D01*
G03X962696Y400578I-2738J1471D01*
G01Y404537D01*
X962274Y404959D01*
G01X963656Y398260D02*
Y405275D01*
X963356Y405575D01*
G01X960276Y392410D02*
Y391104D01*
X960027Y390855D01*
G02X958925Y391600I249J1555D01*
G01X958912Y391623D01*
G02Y393197I1364J787D01*
G01X958937Y393239D01*
G03X958912Y395522I-2040J1119D01*
G02Y397096I1364J787D01*
G03X958947Y399362I-2015J1164D01*
G01X958912Y399422D01*
X958893Y399456D01*
G02X958756Y399994I986J538D01*
G01Y403383D01*
X958556Y403583D01*
G01X960276Y400209D02*
Y403561D01*
X960056Y403781D01*
G01X960276Y388509D02*
Y389815D01*
X959990Y390101D01*
G02X959908Y390113I296J2307D01*
G02X958261Y391247I368J2297D01*
G02X958236Y393530I2015J1164D01*
G01X958261Y393572D01*
G03Y395146I-1364J787D01*
G01X958236Y395188D01*
G02X958261Y397473I2040J1120D01*
G03Y399047I-1364J787D01*
G01X958235Y399096D01*
X958232D01*
G02X957951Y400190I2045J1108D01*
G01Y402490D01*
X957856Y402585D01*
G01X960276Y396309D02*
X961575Y399309D01*
X961640Y399421D01*
G03X961627Y401205I-1527J881D01*
G01X961548Y401338D01*
X961026Y404509D01*
X960975Y404560D01*
G01X987700Y182563D02*
Y184551D01*
X988214Y185065D01*
Y190180D01*
X990400Y192366D01*
Y199064D01*
X990696Y199360D01*
G01X966756Y191821D02*
X967656D01*
X968661Y192826D01*
Y197136D01*
G03X968118Y198594I-2229J0D01*
G02X967036Y201309I3372J2917D01*
G01X977337Y197141D02*
Y197783D01*
X977181Y197939D01*
Y198834D01*
X977526Y199179D01*
Y199780D01*
X977181Y200125D01*
Y203989D01*
G03X976765Y206115I-5638J0D01*
G01Y206748D01*
X977176Y207159D01*
G01X978537Y197141D02*
Y197722D01*
X978950Y198135D01*
Y199414D01*
X978543Y200143D01*
X978540Y200146D01*
Y200148D01*
G02X978230Y201342I2016J1161D01*
G01X978229Y201343D01*
Y205220D01*
G02X978541Y206372I2327J-12D01*
G03Y207946I-1365J787D01*
G02Y210272I2015J1163D01*
G03X977220Y212635I-1365J788D01*
G01X977091D01*
G02X976808Y217257I85J2325D01*
G02X976891Y217269I374J-2296D01*
G01X977176Y217554D01*
Y218860D01*
G01X972820Y207216D02*
G02X972496Y206111I-1584J-136D01*
G03X972412Y205963I486J-373D01*
G03X972220Y205211I1384J-754D01*
G01Y204683D01*
X972723Y203816D01*
Y202597D01*
X972230Y201743D01*
Y200845D01*
X973737Y198233D01*
Y197141D01*
G01X971287D02*
Y198415D01*
X969856Y201128D01*
X969030Y202336D01*
G02X968818Y202995I1005J687D01*
G01X968813Y203238D01*
Y208577D01*
X968401Y209897D01*
G02X968376Y212180I2015J1164D01*
G01X968401Y212222D01*
X968467Y212338D01*
X970416Y214960D01*
G01X956897Y199360D02*
Y198096D01*
X956775Y197974D01*
Y196214D01*
G01X967036Y205210D02*
Y203904D01*
G03X967356Y203241I847J0D01*
G02X968169Y202298I-2079J-2614D01*
G01X968508Y201712D01*
G02X968611Y201340I-673J-387D01*
G03X968764Y199642I12051J230D01*
G02X969411Y198080I-1562J-1562D01*
G01Y192236D01*
X967746Y190571D01*
X966856D01*
G01X953517Y205210D02*
X951686Y202744D01*
G03X951477Y200189I1831J-1436D01*
G01X951502Y200147D01*
X951521Y200113D01*
G02X951337Y198381I-1346J-733D01*
G01X950989Y197977D01*
X949228Y197031D01*
G01X963656Y199360D02*
Y197944D01*
X963800Y197800D01*
Y195185D01*
G01X960276Y197409D02*
Y198715D01*
X960027Y198964D01*
G03X958911Y198197I247J-1555D01*
G03X958700Y197391I1363J-788D01*
G01Y195024D01*
X957916Y194240D01*
Y193959D01*
G01X960276Y201309D02*
Y200003D01*
X959992Y199719D01*
G03X959908Y199707I287J-2309D01*
G03X958261Y198573I368J-2298D01*
G03X957948Y197383I2014J-1166D01*
G01X957950Y197381D01*
Y195335D01*
X957466Y194851D01*
X957110D01*
G01X977176Y211060D02*
X975810Y207947D01*
G03X975791Y206406I1366J-787D01*
G01X975810Y206372D01*
G02X976070Y205832I-4266J-2387D01*
G02X976431Y203988I-4527J-1844D01*
G01Y197941D01*
X976137Y197647D01*
Y197141D01*
G01X977176Y214960D02*
X976467Y215802D01*
X975951D01*
G03X977117Y213385I1223J-900D01*
G01X977246D01*
G02X979191Y209897I-70J-2325D01*
G03X979172Y208356I1365J-787D01*
G01X979191Y208322D01*
G02X979216Y206039I-2015J-1164D01*
G01X979191Y205997D01*
G03X978980Y205216I1365J-788D01*
G01Y201332D01*
G03X979191Y200523I1576J-21D01*
G01X979199Y200508D01*
X979737Y199544D01*
Y197141D01*
G01X970416Y211060D02*
X971500D01*
X972000Y210560D01*
Y210118D01*
G03X972458Y208383I3516J0D01*
G02X972820Y207216I-2486J-1411D01*
G01X973796Y209109D02*
X975094Y206112D01*
X975161Y205997D01*
G02X975406Y205056I-1683J-941D01*
G01Y199516D01*
X974937Y199047D01*
Y197141D01*
G01X983936Y214960D02*
Y213654D01*
X984221Y213369D01*
G02X985951Y209897I-285J-2309D01*
G03X985932Y208356I1365J-787D01*
G01X985951Y208322D01*
G02X985976Y206039I-2015J-1164D01*
G01X985951Y205997D01*
G03X985811Y205677I1365J-788D01*
G03X985795Y205572I339J-105D01*
G01Y204776D01*
X986311Y203886D01*
Y202612D01*
X985831Y201780D01*
Y200614D01*
X986269Y199855D01*
Y197370D01*
X984587Y194854D01*
G01X972537Y197141D02*
Y198812D01*
X971480Y200643D01*
Y201945D01*
X971973Y202799D01*
Y203527D01*
X971468Y204401D01*
Y205214D01*
G02X971750Y206348I2445J-6D01*
G01X971923Y206677D01*
G03X972046Y207171I-936J495D01*
G03X971931Y207611I-901J0D01*
G02X971600Y208372I3618J2026D01*
G01X971311Y209213D01*
X970855Y209485D01*
X970357D01*
G01X973796Y216909D02*
X972497Y213910D01*
X972431Y213797D01*
G02X970501Y212635I-2015J1163D01*
G01X970372D01*
G03X970357Y209485I44J-1575D01*
G01X982137Y197141D02*
Y198950D01*
X982894Y200780D01*
Y201813D01*
X982445Y202591D01*
Y203721D01*
X982803Y204341D01*
Y206144D01*
X982360Y206907D01*
Y207158D01*
G02X982571Y207946I1576J0D01*
G03Y210272I-2015J1163D01*
G01X981921Y211424D01*
Y212222D01*
X981940Y212256D01*
G03X981921Y213797I-1384J754D01*
G01X981855Y213910D01*
X980556Y216909D01*
G01X933237Y267609D02*
X930987D01*
G01X939997Y263709D02*
X937747D01*
G01X929857Y257860D02*
X927607D01*
G01X933237Y255909D02*
X930987D01*
G01X936617Y269560D02*
X934367D01*
G01X939997Y267609D02*
X937747D01*
G01X929857Y261760D02*
X927607D01*
G01X936617Y257860D02*
X934367D01*
G01X939997Y259809D02*
X937747D01*
G01X929857Y265660D02*
X927607D01*
G01X936617Y261760D02*
X934367D01*
G01X933237Y263709D02*
X930987D01*
G01X950137Y261760D02*
X947887D01*
G01X946757Y232509D02*
X944507D01*
G01X950137Y230559D02*
X947887D01*
G01X953517Y244209D02*
X951267D01*
G01X956897Y242260D02*
X954647D01*
G01X946757Y236409D02*
X944507D01*
G01X953517Y232509D02*
X951267D01*
G01X963656Y230559D02*
X961406D01*
G01X970416Y234460D02*
X968166D01*
G01X970416Y222760D02*
X968166D01*
G01X973796Y224709D02*
X971546D01*
G01X956897Y257860D02*
X954647D01*
G01X963656Y234460D02*
X961406D01*
G01X967036Y236409D02*
X964786D01*
G01X967036Y224709D02*
X964786D01*
G01X973796Y228610D02*
X971546D01*
G01X946757Y252009D02*
X944507D01*
G01X950137Y250060D02*
X947887D01*
G01X953517Y263709D02*
X951267D01*
G01X956897Y261760D02*
X954647D01*
G01X946757Y255909D02*
X944507D01*
G01X953517Y252009D02*
X951267D01*
G01X950137Y242260D02*
X947887D01*
G01X956897Y238360D02*
X954647D01*
G01X956897Y253960D02*
X954647D01*
G01X946757Y240309D02*
X944507D01*
G01X963656Y226660D02*
X961406D01*
G01X967036Y263709D02*
X964786D01*
G01X956897Y234460D02*
X954647D01*
G01X973796Y232509D02*
X971546D01*
G01X967036Y275409D02*
X964786D01*
G01X946757Y259809D02*
X944507D01*
G01X953517Y255909D02*
X951267D01*
G01X950137Y238360D02*
X947887D01*
G01X967036Y228610D02*
X964786D01*
G01X967036Y267609D02*
X964786D01*
G01X953517Y236409D02*
X951267D01*
G01X970416Y230559D02*
X968166D01*
G01X967036Y271509D02*
X964786D01*
G01X950137Y257860D02*
X947887D01*
G01X963656Y265660D02*
X961406D01*
G01X973796Y271509D02*
X971546D01*
G01X960276Y267609D02*
X958026D01*
G01X970416Y265660D02*
X968166D01*
G01X953517Y396309D02*
X955249Y398041D01*
Y401796D01*
X955080Y401965D01*
G01X967036Y392410D02*
X965207Y394871D01*
G02X965021Y397472I1829J1438D01*
G03X965030Y398835I-1195J689D01*
G01X964939Y398998D01*
X964614Y399544D01*
G02X964466Y400083I906J539D01*
G01Y406163D01*
X964322Y406307D01*
G01X967036Y396309D02*
X965902Y398924D01*
G03X965881Y398964I-323J-144D01*
G01X965624Y399396D01*
X965216Y400126D01*
Y407181D01*
X965106Y407291D01*
G01X953517Y392410D02*
X952377Y394989D01*
G03X952152Y395522I-2240J-631D01*
G01X952133Y395556D01*
G02X952152Y397097I1384J754D01*
G03X952177Y399380I-2015J1164D01*
G01X951359Y400837D01*
X950106Y402090D01*
Y402459D01*
G01X977176Y382660D02*
G03X973752Y383034I-4019J-20937D01*
G02X972431Y383822I44J1575D01*
G02X972286Y384160I1356J782D01*
G02X972224Y384709I1510J449D01*
G03X971756Y387389I-5796J369D01*
G02X971781Y389672I2040J1119D01*
G03X971992Y390460I-1365J788D01*
G01Y390747D01*
X971310Y391929D01*
Y392958D01*
X971891Y393963D01*
Y394756D01*
X971361Y395674D01*
Y396944D01*
X971950Y397965D01*
Y398782D01*
X971666Y399423D01*
Y400644D01*
X972056Y401489D01*
Y403064D01*
X971800Y403320D01*
G01X980556Y384609D02*
Y383303D01*
X980307Y383054D01*
G02X979191Y383822I248J1556D01*
G01X979172Y383856D01*
G02X979191Y385397I1384J754D01*
G03X979216Y387680I-2015J1164D01*
G01X979191Y387722D01*
X979172Y387756D01*
G02X979191Y389297I1384J754D01*
G03X979084Y391659I-1901J1097D01*
G01X978816Y392039D01*
Y393198D01*
X979266Y393648D01*
Y395641D01*
G01X980556Y380709D02*
Y382015D01*
X980271Y382300D01*
G02X980188Y382312I291J2308D01*
G02X978541Y383447I368J2297D01*
G01X978516Y383489D01*
G02X978541Y385772I2040J1119D01*
G03X978560Y387313I-1365J787D01*
G01X978541Y387347D01*
X978516Y387389D01*
G02X978541Y389672I2040J1119D01*
G03X978470Y391226I-1251J721D01*
G01X978178Y391641D01*
X978174Y391647D01*
X978066Y391755D01*
Y395641D01*
G01X980556Y388509D02*
X981855Y391509D01*
X981920Y391621D01*
G03X982056Y392129I-882J508D01*
G01Y393297D01*
X981666Y393687D01*
Y395641D01*
G01X973796Y388509D02*
X974744Y389457D01*
Y391045D01*
X975666Y391967D01*
Y395641D01*
G01X977176Y390460D02*
X976866Y390770D01*
Y395641D01*
G01X987316Y384609D02*
Y384612D01*
X985434Y387140D01*
G02X985301Y389672I1882J1368D01*
G03X985317Y391013I-1188J685D01*
G01X984934Y391716D01*
Y393976D01*
X985266Y394308D01*
Y395641D01*
G01X973796Y384609D02*
X972499Y387605D01*
X972412Y387756D01*
G02X972431Y389297I1384J754D01*
G03X972743Y390460I-2015J1164D01*
G01Y390948D01*
X972058Y392135D01*
Y392681D01*
X972641Y393686D01*
Y394958D01*
X972111Y395876D01*
Y396742D01*
X972756Y397860D01*
Y398910D01*
X972478Y399582D01*
Y400390D01*
X972856Y401208D01*
Y402939D01*
X973106Y403189D01*
G01X983936Y382660D02*
X982411Y384185D01*
Y388160D01*
X982830Y388579D01*
Y389285D01*
G02X982552Y391213I1151J1150D01*
G01X982571Y391247D01*
X982606Y391307D01*
G03X982883Y392422I-2050J1101D01*
G01Y394162D01*
X982866Y394179D01*
Y395641D01*
G01X983936Y390460D02*
X983941Y390465D01*
Y394994D01*
X984066Y395119D01*
Y395641D01*
G01X1004215Y386560D02*
G02X1002395Y392189I4864J4681D01*
G03X1002200Y393197I-1559J221D01*
G03X1000229Y394678I-2722J-1571D01*
G02X999004Y397964I2097J2653D01*
G03X998840Y399013I-1548J295D01*
G02X998820Y399045I450J304D01*
G02X998200Y401358I4003J2313D01*
G01Y403700D01*
X999182Y404682D01*
Y406130D01*
G01X997456Y390460D02*
X995651Y392841D01*
Y397131D01*
X994586Y398196D01*
X993856D01*
X992417Y399635D01*
Y401481D01*
X992699Y401763D01*
Y402909D01*
G01X994076Y392410D02*
X991773Y394713D01*
X991014D01*
X990131Y395324D01*
X989800Y396021D01*
Y400306D01*
X990604Y401110D01*
Y402882D01*
G01X1014355Y201309D02*
X1012864Y197865D01*
G03X1012796Y197538I755J-328D01*
G01Y192003D01*
X1015490Y189310D01*
Y188215D01*
G01X1004215Y211060D02*
X1004213Y211056D01*
X1002872Y208761D01*
X1002411Y205230D01*
G02X1001376Y203730I-1575J-20D01*
G01X1000576Y203329D01*
X999031Y201784D01*
Y199396D01*
G02X998821Y198572I-1575J-37D01*
G03X998509Y197400I2015J-1164D01*
G01Y190087D01*
X995640Y187218D01*
Y186625D01*
G01X999610Y186360D02*
Y187210D01*
X1001300Y188900D01*
Y196945D01*
X1000836Y197409D01*
G01Y201309D02*
X999537Y198310D01*
X999471Y198197D01*
G03X999300Y197559I1106J-638D01*
G01Y196400D01*
X1000100Y195600D01*
Y189601D01*
X997625Y187126D01*
Y186310D01*
G01X997456Y199360D02*
X996881Y198785D01*
Y191056D01*
X993655Y187830D01*
Y186736D01*
G01X991670Y182619D02*
Y188442D01*
X994786Y191558D01*
Y196699D01*
X994076Y197409D01*
G01X989685Y182436D02*
Y184243D01*
X989899Y184457D01*
Y189268D01*
X992691Y192060D01*
Y195209D01*
X992100Y195800D01*
Y198201D01*
X994076Y200177D01*
Y201309D01*
G01X1028030Y181266D02*
Y181343D01*
X1027826Y181547D01*
Y182577D01*
X1028960Y183711D01*
Y190140D01*
X1026126Y192974D01*
Y197534D01*
X1026509Y198196D01*
X1026510Y198197D01*
G03X1026535Y200480I-2015J1164D01*
G03X1024565Y201685I-2039J-1120D01*
G01X1024436D01*
G02X1023130Y202472I59J1575D01*
G03X1021484Y203606I-2015J-1163D01*
G03X1021401Y203618I-374J-2296D01*
G01X1021115Y203904D01*
Y205210D01*
G01X1021760Y182706D02*
X1021634Y182832D01*
Y190565D01*
X1020100Y192099D01*
Y195900D01*
X1019540Y196460D01*
Y197399D01*
G02X1019750Y198198I1575J13D01*
G03Y200524I-2015J1163D01*
G02Y202098I1365J787D01*
G03Y204424I-2015J1163D01*
G02Y205998I1365J787D01*
G03X1018103Y209459I-2015J1163D01*
G03X1018019Y209471I-371J-2297D01*
G01X1017735Y209755D01*
Y211060D01*
G01X1024495Y199360D02*
X1023960D01*
X1023498Y198898D01*
Y198302D01*
X1023822Y197978D01*
Y195836D01*
X1022569Y194583D01*
Y192767D01*
X1023920Y191416D01*
Y189552D01*
X1024421Y189051D01*
X1025864D01*
X1026653Y188262D01*
Y185990D01*
X1025864Y185201D01*
X1025069D01*
X1024719Y184851D01*
Y183281D01*
X1024895Y183105D01*
G01X1018625Y184533D02*
Y184620D01*
X1018425Y184820D01*
Y190176D01*
X1017098Y191503D01*
Y197448D01*
X1016644Y198335D01*
X1016784Y198811D01*
X1017735Y199360D01*
G01X1026880Y181268D02*
Y181276D01*
X1027076Y181472D01*
Y182888D01*
X1028210Y184022D01*
Y189829D01*
X1025376Y192663D01*
Y197736D01*
X1025860Y198573D01*
G03X1025876Y200118I-1365J787D01*
G03X1024539Y200935I-1381J-758D01*
G01X1024410D01*
G02X1022480Y202097I85J2325D01*
G03X1021365Y202865I-1365J-788D01*
G01X1021115Y202615D01*
Y201309D01*
G01X1020610Y182686D02*
X1020884Y182960D01*
Y190254D01*
X1019350Y191788D01*
Y195589D01*
X1018790Y196149D01*
Y197391D01*
X1018788Y197393D01*
G02X1019100Y198573I2326J16D01*
G03Y200149I-1365J788D01*
G01Y200148D01*
G02Y202474I2015J1163D01*
G03Y204048I-1365J787D01*
G02Y206374I2015J1163D01*
G03X1017984Y208716I-1365J786D01*
G01X1017735Y208467D01*
Y207159D01*
G01X1023745Y183105D02*
Y183149D01*
X1023969Y183373D01*
Y185162D01*
X1024758Y185951D01*
X1025553D01*
X1025903Y186301D01*
Y187951D01*
X1025553Y188301D01*
X1024110D01*
X1023170Y189241D01*
Y191105D01*
X1021819Y192456D01*
Y194894D01*
X1023072Y196147D01*
Y197667D01*
X1022517Y198222D01*
X1021922D01*
X1021115Y197415D01*
Y197409D01*
G01X1017475Y184533D02*
X1017675Y184733D01*
Y189865D01*
X1016348Y191192D01*
Y197267D01*
X1015965Y198014D01*
X1015918Y198061D01*
X1015484D01*
X1014355Y197409D01*
G01X1032000Y180801D02*
Y181749D01*
X1033426Y183175D01*
Y189774D01*
X1030316Y192884D01*
Y198066D01*
X1030143Y198239D01*
G02X1029680Y199403I1121J1120D01*
G01Y203405D01*
X1027875Y205210D01*
G01X1014355D02*
X1012576Y202130D01*
X1012526Y199430D01*
X1012476Y198880D01*
X1012326Y198630D01*
X1012046Y198230D01*
Y191082D01*
X1013505Y189623D01*
Y188142D01*
G01X1011520Y188639D02*
Y189910D01*
X1011271Y190159D01*
Y199064D01*
X1010975Y199360D01*
G01Y207159D02*
X1010638Y206016D01*
X1010316Y205273D01*
X1009591Y204013D01*
G03X1009610Y202472I1384J-754D01*
G02X1009635Y200189I-2015J-1164D01*
G01X1009610Y200147D01*
X1009591Y200113D01*
G03X1009610Y198572I1384J-754D01*
G02X1010026Y197020I-2686J-1552D01*
G01Y191554D01*
X1009535Y191063D01*
Y189913D01*
G01X1007550Y189634D02*
Y190946D01*
X1009200Y192596D01*
Y197301D01*
G03X1008960Y198197I-1793J0D01*
G02X1008935Y200480I2015J1164D01*
G01X1008960Y200522D01*
X1008979Y200556D01*
G03X1008960Y202097I-1384J754D01*
G02Y204423I2015J1163D01*
G01X1009455Y205282D01*
X1009457Y205284D01*
Y206738D01*
G03X1008645Y207550I-812J0D01*
G01X1008609D01*
G03X1008075Y207329I0J-756D01*
G01X1007976Y207230D01*
G03X1007595Y206310I920J-920D01*
G01Y205210D01*
G01Y201309D02*
X1005826Y197580D01*
Y187874D01*
X1005565Y187613D01*
Y185958D01*
G01X1001595Y186312D02*
Y187393D01*
X1002678Y188476D01*
Y199705D01*
G02X1002851Y200147I1536J-346D01*
G01X1002886Y200207D01*
G03X1002851Y202473I-2050J1102D01*
G02Y204047I1364J787D01*
G01X1002914Y204155D01*
X1004215Y207159D01*
G01Y199360D02*
X1004757Y198818D01*
Y189013D01*
X1003580Y187836D01*
Y186457D01*
G01X1030015Y181141D02*
Y182384D01*
X1031826Y184195D01*
Y189974D01*
X1029500Y192300D01*
Y197557D01*
X1027875Y201309D01*
G01X1033985Y180486D02*
Y181598D01*
X1035326Y182939D01*
Y189374D01*
X1031255Y193445D01*
Y199360D01*
G01Y207159D02*
X1032400Y206014D01*
Y205358D01*
X1034308Y203450D01*
X1034666D01*
X1035971Y202145D01*
G02X1035009Y199778I-1336J-836D01*
G01X1034446Y199419D01*
X1033815Y198915D01*
X1033270Y198197D01*
G03X1033027Y197301I1572J-907D01*
G01Y194673D01*
X1037955Y189745D01*
Y179613D01*
G01X1035970Y180000D02*
Y181413D01*
X1036626Y182069D01*
Y189575D01*
X1032166Y194035D01*
Y198046D01*
X1034635Y201309D01*
G01X983936Y211060D02*
Y212366D01*
X984185Y212615D01*
G02X985301Y210272I-249J-1556D01*
G03Y207946I2015J-1163D01*
G02Y206372I-1365J-787D01*
G01X985276Y206330D01*
G03X985131Y206012I2039J-1122D01*
G01X985091Y205903D01*
G03X985030Y205561I930J-342D01*
G01Y204433D01*
X985561Y203514D01*
Y202814D01*
X985081Y201982D01*
Y200412D01*
X985519Y199653D01*
Y198318D01*
X983337Y196136D01*
Y195141D01*
G01X980556Y209109D02*
G02X980900Y210164I1792J-1D01*
G01X981327Y210286D01*
X981616Y210240D01*
G02X981921Y209897I-677J-909D01*
G02Y208323I-1365J-787D01*
G03X981609Y207156I2015J-1164D01*
G01D02*
Y206683D01*
G01D02*
X982053Y205914D01*
Y204543D01*
X981695Y203923D01*
Y202390D01*
X982144Y201611D01*
Y200939D01*
X980937Y198215D01*
Y197141D01*
G01X1031255Y211060D02*
X1030000Y209805D01*
Y208154D01*
X1029005Y207159D01*
G01X980556Y255909D02*
X978306D01*
G01X990696Y257860D02*
X988446D01*
G01X990696Y261760D02*
X988446D01*
G01X977176D02*
X974926D01*
G01X987316Y255909D02*
X985066D01*
G01X987316Y263709D02*
X985066D01*
G01X983936Y253960D02*
X981686D01*
G01X983936Y265660D02*
X981686D01*
G01X983936Y257860D02*
X981686D01*
G01X983936Y261760D02*
X981686D01*
G01X1004215Y246160D02*
X1001965D01*
G01X997456D02*
X995206D01*
G01X1010975D02*
X1008725D01*
G01X980556Y337809D02*
X978306D01*
G01X1037575Y411056D02*
Y409275D01*
X1031255Y402955D01*
Y398260D01*
G01X1000836Y396309D02*
X999539Y399305D01*
X999471Y399422D01*
G02X999395Y399595I1541J780D01*
G02X999270Y400185I1440J613D01*
G02X999269Y400197I1556J136D01*
G01X999260Y401441D01*
X999100Y401601D01*
Y403400D01*
X1001277Y405577D01*
Y407377D01*
G01X997456Y398260D02*
Y399543D01*
X997087Y399912D01*
Y405432D01*
G01X994076Y400209D02*
X994992Y401125D01*
Y403714D01*
G01X1027907Y410053D02*
X1027707Y409853D01*
Y409206D01*
X1019576Y401075D01*
Y399773D01*
X1019743Y399434D01*
X1019775Y399380D01*
G02X1019750Y397097I-2040J-1119D01*
G03X1020865Y394754I1365J-787D01*
G01X1021069Y394721D01*
G03X1021622Y395802I102J630D01*
G01X1021115Y396309D01*
G01X1020031Y410490D02*
X1020231Y410290D01*
Y409892D01*
X1012076Y401737D01*
Y399505D01*
X1012340Y399047D01*
G03X1014301Y397884I2015J1162D01*
G01X1014414D01*
G02X1015739Y395556I-59J-1575D01*
G01X1015720Y395522D01*
G03X1015695Y393239I2015J-1164D01*
G01X1015720Y393197D01*
G02Y391623I-1365J-787D01*
G03X1015786Y389187I2014J-1164D01*
G01X1016541Y388030D01*
G03X1017735Y386560I7676J5015D01*
G01X1021115Y400209D02*
X1021562Y399761D01*
G02X1022169Y398297I-1464J-1465D01*
G03X1023665Y396087I2326J-37D01*
G03X1026535Y399380I830J2173D01*
G01X1026532Y399385D01*
X1026251Y399947D01*
Y403442D01*
X1030901Y408092D01*
Y409839D01*
X1031108Y410046D01*
Y410133D01*
G01X1014355Y400209D02*
X1014964Y399600D01*
X1015690D01*
X1016051Y399961D01*
Y401645D01*
X1023800Y409394D01*
Y409904D01*
X1023618Y410086D01*
Y410158D01*
G01X1026757Y410073D02*
Y409986D01*
X1026957Y409786D01*
Y409517D01*
X1018826Y401386D01*
Y399598D01*
X1019082Y399076D01*
X1019083Y399073D01*
X1019084D01*
X1019100Y399047D01*
X1019119Y399013D01*
G02X1019100Y397472I-1384J-754D01*
G03X1019620Y394524I2014J-1165D01*
G01X1020455Y393824D01*
G02X1021115Y392410I-1185J-1414D01*
G01X1017735Y390460D02*
Y390067D01*
G02X1017500Y389500I-802J0D01*
G02X1016512I-494J494D01*
G01X1016415Y389597D01*
G02X1016370Y391248I1319J862D01*
G03X1016398Y393585I-2064J1193D01*
G01X1016328Y393725D01*
G02X1016370Y395146I1342J671D01*
G03X1014440Y398634I-2015J1163D01*
G01X1014311D01*
G02X1012990Y399422I44J1575D01*
G01X1012826Y399706D01*
Y401426D01*
X1020981Y409581D01*
Y410062D01*
X1021181Y410262D01*
G01X1029958Y410133D02*
Y410113D01*
X1030151Y409920D01*
Y408403D01*
X1025500Y403752D01*
Y399770D01*
X1025870Y399031D01*
X1025876Y399018D01*
X1025883Y399008D01*
G02X1023936Y396787I-1387J-748D01*
G01X1023935Y396788D01*
X1023933D01*
G02X1022920Y398290I563J1472D01*
G03Y398302I-2821J6D01*
G01X1022929Y398652D01*
G02X1023769Y398987I492J-13D01*
G01X1024495Y398260D01*
G01X1017735D02*
X1016801Y399194D01*
Y401334D01*
X1024550Y409083D01*
Y409935D01*
X1024768Y410153D01*
Y410161D01*
G01X1035475Y410585D02*
Y408475D01*
X1030400Y403400D01*
Y400412D01*
G02X1029925Y399107I-2030J0D01*
G01X1029890Y399047D01*
X1029871Y399013D01*
G03X1029890Y397472I1384J-754D01*
G02X1029780Y394972I-2015J-1164D01*
G01X1027875Y392410D01*
G01X1041775Y411853D02*
Y410279D01*
X1033368Y401872D01*
X1033060Y400208D01*
G03X1033270Y399422I1575J0D01*
G01X1033295Y399380D01*
X1034635Y398040D01*
Y396309D01*
G01X1039675Y410927D02*
Y409575D01*
X1032309Y402209D01*
Y400211D01*
G03X1032620Y399047I2326J-2D01*
G01X1032639Y399013D01*
G02X1032620Y397472I-1384J-754D01*
G03Y395146I2015J-1163D01*
G02Y393572I-1365J-787D01*
G01X1032595Y393530D01*
X1031255Y390460D01*
G01X1014355Y396309D02*
X1011263Y396668D01*
G03X1011026Y396685I-285J-2309D01*
G01X1010916D01*
G02X1009591Y399013I59J1575D01*
G03X1010100Y400452I-1779J1439D01*
G01Y403700D01*
X1015942Y409542D01*
Y410519D01*
G01X1010975Y398260D02*
Y402875D01*
X1018037Y409937D01*
Y410774D01*
G01X1013847Y410143D02*
Y409247D01*
X1009171Y404571D01*
Y400212D01*
G02X1008979Y399456I-1576J-2D01*
G01X1008960Y399422D01*
X1008935Y399380D01*
G03X1010924Y395934I2040J-1120D01*
G01X1011019D01*
G02X1012340Y395146I-44J-1575D01*
G01X1014355Y392410D01*
G01X1007595Y396309D02*
X1006298Y399305D01*
X1006230Y399422D01*
G02X1006017Y400206I1360J790D01*
G01Y403517D01*
X1011752Y409252D01*
Y410009D01*
G01X1010975Y390460D02*
X1009000Y393100D01*
X1008100Y394000D01*
X1006750Y394979D01*
G02X1006019Y396300I845J1330D01*
G01X1005711Y398706D01*
G03X1005300Y399300I-2849J-1532D01*
G01X1005200Y399600D01*
Y404300D01*
X1009657Y408757D01*
Y409566D01*
G01X1004215Y398260D02*
Y404716D01*
X1007562Y408063D01*
Y408976D01*
G01X1004215Y390460D02*
G03X1002876Y393530I-12824J-3766D01*
G01X1002851Y393572D01*
G02X1002666Y394641I1364J787D01*
G03X1002200Y397096I-3420J623D01*
G02X1002165Y399362I2015J1164D01*
G01X1002200Y399422D01*
G03X1002411Y400229I-1364J788D01*
G01Y406539D01*
X1003372Y407500D01*
Y408372D01*
G01X1007595Y392410D02*
G02X1005580Y395146I11179J10343D01*
G03X1004777Y395831I-1365J-787D01*
G02X1002851Y397473I1349J3533D01*
G02X1002876Y399088I1539J784D01*
G03X1003163Y400214I-2040J1120D01*
G01Y405361D01*
X1005467Y407665D01*
Y408774D01*
G01X1027875Y396309D02*
X1029083Y399095D01*
G02X1029215Y399380I2172J-833D01*
G01X1029240Y399422D01*
X1029259Y399456D01*
G03X1029451Y400214I-1384J754D01*
G01Y404100D01*
X1033375Y408024D01*
Y410585D01*
G01X980556Y392410D02*
X980466Y392500D01*
Y395641D01*
G01X987316Y388509D02*
X986206Y390998D01*
X985841Y391662D01*
Y393528D01*
X986516Y394203D01*
Y395641D01*
G01X1047880Y187498D02*
Y188920D01*
X1044000Y192800D01*
X1042470D01*
X1039736Y195534D01*
Y197100D01*
G02X1040030Y198197I2195J0D01*
G03X1040055Y200480I-2015J1164D01*
G01X1040030Y200522D01*
X1040011Y200556D01*
G02X1040030Y202097I1384J754D01*
G01X1040096Y202211D01*
X1041395Y205210D01*
G01X1048154Y201309D02*
X1050103Y198688D01*
X1050847Y197628D01*
X1055820Y192655D01*
Y190701D01*
G01X1034635Y197409D02*
Y194566D01*
X1039940Y189261D01*
Y186892D01*
G01X1049865Y187877D02*
Y189422D01*
X1044507Y194780D01*
X1044039Y195700D01*
X1043120Y197917D01*
X1041395Y201309D01*
G01X1071072Y206447D02*
X1071260Y206260D01*
X1072400Y205119D01*
Y204077D01*
X1073256Y203221D01*
Y198055D01*
X1072481Y197280D01*
G01X1074031Y196112D02*
X1074006Y196137D01*
Y204050D01*
X1074452Y204496D01*
G01X1084591Y206447D02*
X1086167Y202807D01*
Y197992D01*
X1084881Y196706D01*
Y196112D01*
G01X1084591Y210346D02*
X1086417Y206131D01*
Y204409D01*
G03X1086587Y203743I1391J0D01*
G01X1086917Y203153D01*
Y196548D01*
X1086431Y196062D01*
G01X1069331Y196112D02*
Y197268D01*
X1068175Y198424D01*
Y202336D01*
X1069035Y203827D01*
G03Y205271I-1251J722D01*
G02Y207621I2037J1175D01*
G02X1069185Y207849I2036J-1176D01*
G01X1071072Y210346D01*
G01X1070931Y196112D02*
Y197468D01*
X1068976Y199423D01*
Y202121D01*
X1069729Y203427D01*
G03Y205671I-1945J1122D01*
G02X1071030Y207996I1343J775D01*
G01X1071159D01*
G03X1073109Y209171I-87J2350D01*
G01X1073466Y210002D01*
Y211310D01*
X1074452Y212296D01*
G01X1081212Y204496D02*
X1081962Y203746D01*
Y197769D01*
X1081781Y197588D01*
Y196112D01*
G01X1081212Y212296D02*
X1082712Y210796D01*
Y197885D01*
X1083331Y197266D01*
Y196112D01*
G01X1077131D02*
X1076776Y196467D01*
Y197900D01*
X1077176Y198300D01*
Y198900D01*
X1076776Y199300D01*
Y200625D01*
X1076347Y201373D01*
Y202864D01*
G02X1076490Y203370I966J0D01*
G02X1077583Y204101I1343J-825D01*
G01X1077832Y203852D01*
Y202547D01*
G01Y206447D02*
X1076807Y205178D01*
G03X1075850Y203763I15696J-11647D01*
G01X1075851D01*
G03X1075597Y202864I1462J-899D01*
G01Y201173D01*
X1076026Y200425D01*
Y196557D01*
X1075581Y196112D01*
G01X1077832Y210346D02*
Y211168D01*
X1077417Y211583D01*
X1076882D01*
X1076717Y211418D01*
G03X1076641Y209315I1092J-1092D01*
G03X1077788Y208771I1191J1031D01*
G01X1077917D01*
G02X1079847Y205283I-85J-2325D01*
G01X1079846Y205284D01*
G03Y203708I1365J-788D01*
G02X1080155Y202657I-2014J-1163D01*
G01Y202655D01*
G02X1079654Y200619I-3666J-178D01*
G01X1079431Y200240D01*
Y199400D01*
X1079831Y199000D01*
Y198400D01*
X1079431Y198000D01*
Y197200D01*
X1080231Y196400D01*
G01X1034635Y205210D02*
X1036435Y203410D01*
Y203046D01*
G03X1036650Y202472I1829J358D01*
G02X1036675Y200189I-2015J-1164D01*
G01X1036650Y200147D01*
X1036631Y200113D01*
G03X1036376Y199111I1840J-1002D01*
G01Y194425D01*
X1041925Y188876D01*
Y187013D01*
G01X1038015Y199360D02*
Y194286D01*
X1043910Y188391D01*
Y187013D01*
G01X1051850Y188251D02*
Y190450D01*
X1047712Y194588D01*
X1046212D01*
X1044965Y195835D01*
X1044508Y196624D01*
G02X1044357Y197702I1251J725D01*
G01X1044774Y199360D01*
G01X1045895Y186770D02*
Y187904D01*
X1038926Y194873D01*
Y196877D01*
G02X1039380Y198572I3390J0D01*
G03X1039399Y200113I-1365J787D01*
G01X1039380Y200147D01*
X1039355Y200189D01*
G02X1039380Y202472I2040J1119D01*
G03X1039399Y204013I-1365J787D01*
G01X1039315Y204159D01*
X1038015Y207159D01*
G01X1044774D02*
X1046074Y204159D01*
X1046158Y204013D01*
G02X1046349Y203296I-1384J-753D01*
G01Y200848D01*
X1048213Y198984D01*
G02X1049523Y198140I-57J-1527D01*
G01X1050085Y197184D01*
Y195216D01*
X1053835Y191466D01*
Y189513D01*
G01X1077832Y214247D02*
G02X1076028Y211814I-28053J18915D01*
G03X1076073Y208824I1805J-1468D01*
G03X1077747Y208021I1760J1522D01*
G01X1077832D01*
G02X1079196Y205659I0J-1575D01*
G03Y203333I2015J-1163D01*
G02X1079405Y202637I-1363J-789D01*
G01Y202619D01*
G02X1079007Y200999I-2916J-142D01*
G01X1078681Y200445D01*
Y196400D01*
G01X1093006Y196291D02*
Y199087D01*
X1093643Y199724D01*
Y202998D01*
X1093026Y203615D01*
Y206047D01*
X1092626Y206447D01*
X1091351D01*
G01X1094731Y204496D02*
X1094393Y204158D01*
Y197256D01*
X1094556Y197093D01*
Y196691D01*
G01X1089906Y196405D02*
X1090246Y196745D01*
Y197661D01*
X1089006Y198901D01*
Y202478D01*
G02X1089336Y203709I2461J0D01*
G03Y205283I-1365J787D01*
G02Y207609I2015J1163D01*
G01X1089401Y207722D01*
X1091351Y210346D01*
G01X1094731Y212296D02*
X1093086Y209732D01*
G02X1091436Y208021I-1713J0D01*
G01X1091307D01*
G03X1089986Y205659I44J-1575D01*
G02Y203333I-2015J-1163D01*
G03X1089756Y202474I1488J-859D01*
G01Y199209D01*
X1090994Y197971D01*
Y196707D01*
X1091456Y196245D01*
G01X1077832Y233746D02*
X1075582D01*
G01X1077832Y241547D02*
X1075582D01*
G01X1087971Y235696D02*
X1085721D01*
G01X1087971Y239596D02*
X1085721D01*
G01X1074452Y235696D02*
X1072202D01*
G01X1074452Y239596D02*
X1072202D01*
G01X1084591Y233746D02*
X1082341D01*
G01X1084591Y241547D02*
X1082341D01*
G01X1094731Y235696D02*
X1092481D01*
G01X1094731Y239596D02*
X1092481D01*
G01X1081212Y231797D02*
X1078962D01*
G01X1081212Y243496D02*
X1078962D01*
G01Y235696D02*
X1081212D01*
G01Y239596D02*
X1078962D01*
G01X1034635Y400209D02*
X1036200Y401774D01*
Y403300D01*
X1043875Y410975D01*
Y413053D01*
G01X1051700Y416028D02*
Y412501D01*
X1042994Y403795D01*
Y400304D01*
G02X1042778Y399456I-1772J0D01*
G01X1042759Y399422D01*
X1042724Y399362D01*
G03X1042602Y399096I2050J-1101D01*
G01X1041395Y396309D01*
G01X1051471Y404972D02*
X1049800Y403301D01*
Y400463D01*
G02X1049519Y399422I-2067J0D01*
G01X1049451Y399305D01*
X1048300Y396646D01*
X1048154Y396309D01*
G01X1051800Y402200D02*
X1051400D01*
X1050700Y401500D01*
Y399728D01*
X1050586Y399614D01*
G03X1050169Y399047I2063J-1954D01*
G01X1050150Y399013D01*
G03X1050169Y397472I1384J-754D01*
G02Y395146I-2015J-1163D01*
G01X1050104Y395032D01*
X1048300Y392606D01*
X1048154Y392410D01*
G01X1045975Y413753D02*
Y411976D01*
X1037300Y403301D01*
Y399889D01*
X1036211Y398800D01*
Y395711D01*
X1035500Y395000D01*
Y393275D01*
X1034635Y392410D01*
G01X1053685Y417443D02*
Y413185D01*
X1044161Y403661D01*
Y399823D01*
X1043445Y399107D01*
X1043410Y399047D01*
G03Y397473I1364J-787D01*
G02X1043435Y395188I-2015J-1165D01*
G01X1043410Y395146D01*
X1041395Y392410D01*
G01X1054914Y384609D02*
X1056389Y388008D01*
Y390855D01*
X1057934Y392400D01*
X1060962D01*
X1063250Y394688D01*
Y396123D01*
G01X1077832Y401447D02*
X1078795Y401141D01*
X1080043Y401142D01*
X1080326Y401425D01*
Y402120D01*
X1079457Y402989D01*
G01X1087931Y419868D02*
X1088331Y419468D01*
Y418001D01*
X1090932Y415400D01*
Y409369D01*
X1090931Y409367D01*
Y409366D01*
X1089336Y406607D01*
G03Y404184I2098J-1211D01*
G02X1089355Y402643I-1365J-787D01*
G01X1089336Y402609D01*
X1089311Y402567D01*
G03X1091065Y399138I2040J-1120D01*
G01X1091351Y398852D01*
Y397546D01*
G01Y401447D02*
Y400141D01*
X1091101Y399891D01*
G02X1089967Y402200I250J1556D01*
G01X1089986Y402234D01*
X1090011Y402276D01*
G03X1089986Y404559I-2040J1119D01*
G02Y406235I1452J838D01*
G01X1091682Y409170D01*
Y415818D01*
X1089081Y418419D01*
Y419480D01*
X1089481Y419880D01*
G01X1081212Y395597D02*
X1077974Y395221D01*
X1077762D01*
G02X1075817Y398709I70J2325D01*
G01X1075836Y398743D01*
G03X1075934Y400033I-1384J754D01*
G03X1075816Y400284I-1413J-511D01*
G02Y402610I2015J1163D01*
G03X1075835Y404151I-1365J787D01*
G01X1075807Y404201D01*
G03X1075744Y404280I-301J-175D01*
G01X1072831Y407193D01*
Y419000D01*
X1072431Y419400D01*
G01X1077832Y397546D02*
X1077344Y398666D01*
X1076653Y400250D01*
G03X1076466Y400660I-2201J-756D01*
G01X1076447Y400694D01*
G02X1076466Y402235I1384J754D01*
G03X1076491Y404518I-2015J1164D01*
G01X1076436Y404610D01*
X1076286Y404822D01*
X1073581Y407527D01*
Y419000D01*
X1073981Y419400D01*
G01X1087971Y395597D02*
X1086778Y396790D01*
Y398353D01*
X1086672Y398597D01*
X1086606Y398711D01*
G02Y400285I1365J787D01*
G01X1086631Y400327D01*
G03X1086606Y402610I-2040J1119D01*
G01X1086587Y402644D01*
G02X1086606Y404185I1384J754D01*
G03X1087218Y406468I-3951J2283D01*
G01Y408903D01*
X1087811Y409496D01*
Y414328D01*
X1085231Y416908D01*
Y419100D01*
X1084831Y419500D01*
G01X1084591Y397546D02*
Y396241D01*
X1084341Y395991D01*
G02X1083226Y398333I250J1555D01*
G03Y400659I-2015J1163D01*
G02X1083207Y402200I1365J787D01*
G01Y402197D01*
X1083252Y402280D01*
G03X1083226Y404559I-2041J1116D01*
G01X1083225Y404560D01*
G02X1083046Y405229I1161J669D01*
G01Y411013D01*
X1079781Y414278D01*
Y419181D01*
X1080181Y419581D01*
G01X1084591Y393647D02*
Y394880D01*
X1084222Y395249D01*
G02X1082576Y398709I369J2297D01*
G01X1082595Y398743D01*
G03X1082576Y400284I-1384J754D01*
G02X1082551Y402567I2015J1164D01*
G01X1082576Y402609D01*
X1082595Y402643D01*
G03X1082576Y404184I-1384J754D01*
G02X1082296Y405230I1810J1045D01*
G01Y410702D01*
X1079031Y413967D01*
Y419231D01*
X1078631Y419631D01*
G01X1084591Y401447D02*
X1085890Y404447D01*
X1085955Y404559D01*
G03X1086126Y405198I-1107J639D01*
G01Y406470D01*
X1085506Y407090D01*
Y412855D01*
X1082881Y415480D01*
Y419181D01*
X1083281Y419581D01*
G01X1047730Y414698D02*
X1048135Y414293D01*
Y412935D01*
X1038462Y403262D01*
Y398707D01*
X1038015Y398260D01*
G01X1055670Y417690D02*
Y413969D01*
X1045361Y403660D01*
Y399771D01*
X1044774Y398260D01*
G01X1049715Y415513D02*
Y412454D01*
X1041861Y404600D01*
X1040900D01*
X1039726Y403426D01*
Y397326D01*
X1038600Y396200D01*
X1037800D01*
X1037434Y395834D01*
X1037403D01*
X1036540Y394971D01*
Y394940D01*
X1036456Y394856D01*
Y392743D01*
X1038015Y391184D01*
Y390460D01*
G01X1044774D02*
X1045794Y392813D01*
G03X1046550Y396455I-8398J3643D01*
G01Y403549D01*
X1057655Y414654D01*
Y418266D01*
G01X1079457Y402989D02*
Y409108D01*
X1075931Y412634D01*
Y419100D01*
X1075531Y419500D01*
G01X1081212Y403396D02*
X1080207Y404401D01*
Y409420D01*
X1076681Y412946D01*
Y419100D01*
X1077081Y419500D01*
G01X1087971Y403396D02*
Y408536D01*
X1088561Y409126D01*
Y414639D01*
X1085981Y417219D01*
Y419100D01*
X1086381Y419500D01*
G01X1084591Y405347D02*
Y406947D01*
X1084756Y407112D01*
Y412544D01*
X1082131Y415169D01*
Y419169D01*
X1081731Y419569D01*
G01X1101491Y395597D02*
G03X1098067Y395971I-4019J-20937D01*
G02X1096746Y396759I44J1575D01*
G02X1096601Y397097I1356J782D01*
G02X1096539Y397646I1510J449D01*
G03X1096096Y400284I-5857J373D01*
G02Y402610I2015J1163D01*
G03X1096107Y404182I-1379J796D01*
G01X1095187Y405759D01*
X1094359Y407178D01*
Y408860D01*
X1096080Y410581D01*
Y416420D01*
X1095680Y416820D01*
G01X1098111Y397546D02*
G03X1096746Y400660I-16771J-5495D01*
G01X1096727Y400694D01*
G02X1096746Y402235I1384J754D01*
G03X1096740Y404587I-2027J1171D01*
G01X1096055Y405759D01*
X1095109Y407378D01*
Y408509D01*
X1096830Y410230D01*
Y416430D01*
X1097230Y416830D01*
G01X1104871Y206447D02*
X1106349Y203033D01*
Y201854D01*
X1105923Y201117D01*
Y199836D01*
X1106446Y198930D01*
Y197096D01*
X1105406Y196056D01*
G01X1104871Y210346D02*
X1106171Y207346D01*
X1106236Y207234D01*
G02X1106675Y204491I-8350J-2743D01*
G03X1106867Y203743I1576J6D01*
G01X1107099Y203329D01*
Y201653D01*
X1106673Y200915D01*
Y200036D01*
X1107696Y198262D01*
Y197401D01*
G01X1101491Y204496D02*
X1102006Y203981D01*
Y196994D01*
X1102306Y196694D01*
G01X1101491Y212296D02*
X1102789Y209299D01*
X1102856Y209184D01*
G02Y207610I-1365J-787D01*
G03Y205284I2015J-1163D01*
G02X1102875Y203743I-1365J-787D01*
G01X1102756Y203530D01*
Y198845D01*
X1103206Y198395D01*
Y197393D01*
X1103856Y196743D01*
G01X1097656Y195343D02*
X1097250Y195749D01*
Y200707D01*
X1096601Y201356D01*
Y202622D01*
G02X1097862Y204101I1498J0D01*
G01X1098111Y203852D01*
Y202547D01*
G01X1099206Y195305D02*
X1099596Y195695D01*
Y202886D01*
G03X1099476Y203334I-896J0D01*
G02Y205660I2015J1163D01*
G01Y205659D01*
G03X1098155Y208021I-1365J787D01*
G01X1098026D01*
G02X1096263Y211764I83J2326D01*
G01X1098111Y214247D01*
G01X1096106Y195305D02*
X1096500Y195699D01*
Y200396D01*
X1095851Y201045D01*
Y202623D01*
G02X1097744Y204842I2248J-1D01*
G01X1098111Y205140D01*
Y206447D01*
G01X1100756Y195244D02*
X1100346Y195654D01*
Y202885D01*
G03X1100126Y203709I-1646J2D01*
G02X1100125Y205283I1365J788D01*
G01X1100126D01*
G03X1098196Y208771I-2015J1163D01*
G01X1098067D01*
G02X1096861Y211305I43J1575D01*
G02X1097395Y211749I1249J-959D01*
G01X1097720Y211544D01*
X1098111Y210346D01*
G01X1111631Y206447D02*
X1113196Y204882D01*
Y203872D01*
X1113856Y203212D01*
Y194574D01*
G01X1115011Y204496D02*
X1114606Y204091D01*
Y196017D01*
X1115249Y195374D01*
G01X1125150Y206447D02*
X1126381Y203604D01*
G03X1126515Y203333I2148J894D01*
G01X1127852Y201006D01*
Y198122D01*
X1128787Y197187D01*
G01X1125150Y210346D02*
X1126450Y207346D01*
X1126534Y207200D01*
G02X1126515Y205659I-1384J-754D01*
G01X1127165Y203709D01*
X1128602Y201215D01*
Y199171D01*
X1129173Y198600D01*
X1129567D01*
G01X1111631Y210346D02*
X1109681Y207724D01*
X1109616Y207610D01*
G03Y205284I2015J-1163D01*
G02X1109827Y204494I-1365J-788D01*
G01Y203993D01*
X1109359Y203183D01*
Y201719D01*
X1109823Y200914D01*
Y200080D01*
X1109212Y199022D01*
Y196785D01*
X1111276Y194721D01*
Y193459D01*
X1111686Y193049D01*
Y192358D01*
G01X1110578Y203769D02*
X1110109Y202956D01*
Y201931D01*
X1110573Y201126D01*
Y199879D01*
X1109962Y198820D01*
Y197097D01*
X1112026Y195033D01*
Y193771D01*
X1112326Y193471D01*
X1112766D01*
G01X1110578Y203769D02*
Y204491D01*
G01X1115011Y212296D02*
X1113713Y209299D01*
X1113646Y209184D01*
G02X1111701Y208021I-2015J1162D01*
G01X1111560D01*
G03X1110266Y205659I71J-1574D01*
G02X1110578Y204491I-2015J-1164D01*
G01X1121771Y204496D02*
X1122496Y203771D01*
Y198531D01*
X1124176Y196851D01*
X1124737D01*
X1125547Y196041D01*
G01X1121771Y212296D02*
X1123246Y210821D01*
Y198842D01*
X1124487Y197601D01*
X1126180D01*
X1126473Y197308D01*
G01X1118391Y202547D02*
Y203852D01*
X1118142Y204101D01*
G03X1117295Y203677I249J-1556D01*
G01X1117294Y203679D01*
X1117228Y203615D01*
G03X1116950Y201622I1139J-1175D01*
G01X1117386Y200869D01*
Y197018D01*
X1120904Y193500D01*
X1121509D01*
G01X1118391Y214247D02*
X1117392Y212130D01*
X1116915D01*
X1116525Y211740D01*
X1116497Y211701D01*
G03X1118306Y208021I1893J-1354D01*
G01X1118391D01*
G02X1119755Y205659I0J-1575D01*
G03Y203333I2015J-1163D01*
G01X1119756Y203334D01*
X1119779Y203294D01*
G02X1119778Y201683I-1396J-805D01*
G01X1119779Y201682D01*
X1119413Y201047D01*
Y197482D01*
X1122195Y194700D01*
X1122502D01*
X1122803Y194399D01*
G01X1118391Y206447D02*
G02X1116772Y204218I-7840J3992D01*
G01X1116706Y204154D01*
G03X1116300Y201246I1661J-1714D01*
G01X1116636Y200667D01*
Y196707D01*
X1120300Y193043D01*
Y192517D01*
G01X1118391Y210346D02*
X1117797Y211380D01*
X1117226D01*
X1117111Y211265D01*
Y211262D01*
G03X1118347Y208771I1281J-917D01*
G01X1118476D01*
G02X1120406Y205283I-85J-2325D01*
G03Y203709I1364J-787D01*
G01X1120429Y203669D01*
G02Y201307I-2046J-1181D01*
G01X1120163Y200846D01*
Y197793D01*
X1122356Y195600D01*
X1123795D01*
G01X1098111Y233746D02*
X1095861D01*
G01X1098111Y241547D02*
X1095861D01*
G01X1108251Y235696D02*
X1106001D01*
G01X1108251Y239596D02*
X1106001D01*
G01X1104871Y233746D02*
X1102621D01*
G01X1104871Y241547D02*
X1102621D01*
G01X1108251Y247396D02*
X1106001D01*
G01X1108251Y255196D02*
X1106001D01*
G01X1118391Y249347D02*
X1116141D01*
G01X1118391Y253247D02*
X1116141D01*
G01X1104871Y249347D02*
X1102621D01*
G01X1104871Y253247D02*
X1102621D01*
G01X1115011Y247396D02*
X1112761D01*
G01X1115011Y255196D02*
X1112761D01*
G01X1128530Y247396D02*
X1126280D01*
G01X1128530Y255196D02*
X1126280D01*
G01X1138670Y249347D02*
X1136420D01*
G01X1138670Y253247D02*
X1136420D01*
G01X1122900Y249347D02*
X1125150D01*
G01X1122900Y253247D02*
X1125150D01*
G01X1133040Y247396D02*
X1135290D01*
G01X1133040Y255196D02*
X1135290D01*
G01X1101491Y231797D02*
X1099241D01*
G01X1111631Y245447D02*
X1109381D01*
G01X1131910D02*
X1129660D01*
G01X1101491Y243496D02*
X1099241D01*
G01X1111631Y257147D02*
X1109381D01*
G01X1131910D02*
X1129660D01*
G01X1101491Y235696D02*
X1099241D01*
G01X1111631Y249347D02*
X1109381D01*
G01X1131910D02*
X1129660D01*
G01X1101491Y239596D02*
X1099241D01*
G01X1111631Y253247D02*
X1109381D01*
G01X1131910D02*
X1129660D01*
G01X1098111Y401447D02*
X1099242Y402099D01*
X1099347Y402491D01*
G02X1099476Y404559I2144J904D01*
G01X1099954Y405388D01*
Y407335D01*
X1099180Y408109D01*
Y416466D01*
X1098780Y416866D01*
G01X1101491Y403396D02*
X1100360Y402744D01*
X1100018Y402836D01*
G02X1100126Y404184I1473J560D01*
G01X1100704Y405187D01*
Y407646D01*
X1099930Y408420D01*
Y416466D01*
X1100330Y416866D01*
G01X1111631Y397546D02*
X1109547Y400411D01*
G02X1109591Y402567I2084J1036D01*
G01X1109616Y402609D01*
X1109635Y402643D01*
G03X1109616Y404184I-1384J754D01*
G02X1109386Y405042I1486J858D01*
G01Y406921D01*
X1111580Y409115D01*
Y416420D01*
X1111180Y416820D01*
G01X1111631Y401447D02*
X1110398Y404292D01*
G03X1110266Y404559I-2147J-896D01*
G02X1110136Y405045I842J486D01*
G01Y406610D01*
X1112330Y408804D01*
Y416420D01*
X1112730Y416820D01*
G01X1108251Y395597D02*
X1106952Y398597D01*
X1106886Y398711D01*
G02Y400285I1365J787D01*
G01X1106911Y400327D01*
G03X1106886Y402610I-2040J1119D01*
G01X1106867Y402644D01*
G02X1106886Y404185I1384J754D01*
G03X1107216Y405415I-2129J1230D01*
G01X1107501Y405700D01*
Y408562D01*
X1108453Y409514D01*
Y416493D01*
X1108080Y416866D01*
G01X1118391Y401447D02*
X1120123Y403179D01*
Y407576D01*
X1119200Y408499D01*
Y414932D01*
X1120000Y415732D01*
Y416292D01*
G01X1129556Y407535D02*
Y404523D01*
X1129895Y404184D01*
G02X1129914Y402643I-1365J-787D01*
G01X1129895Y402609D01*
X1129870Y402567D01*
G03X1131624Y399138I2040J-1120D01*
G01X1131910Y398852D01*
Y397546D01*
G01Y401447D02*
Y400141D01*
X1131660Y399891D01*
G02X1130526Y402200I250J1556D01*
G01X1130545Y402234D01*
X1130570Y402276D01*
G03X1130545Y404559I-2040J1119D01*
G01Y404652D01*
X1130356Y404841D01*
Y406141D01*
G01X1121771Y395597D02*
G03X1118347Y395971I-4019J-20937D01*
G02X1117026Y396759I44J1575D01*
G02X1116881Y397097I1356J782D01*
G02X1116819Y397646I1510J449D01*
G03X1116376Y400284I-5857J373D01*
G02Y402610I2015J1163D01*
G03X1116372Y404204I-1377J794D01*
G01X1115465Y405759D01*
X1114900Y406728D01*
Y408899D01*
X1116000Y409999D01*
Y416200D01*
X1116800Y417000D01*
Y417480D01*
G01X1118391Y397546D02*
G03X1117026Y400660I-16771J-5495D01*
G01X1117007Y400694D01*
G02X1117026Y402235I1384J754D01*
G03X1117020Y404587I-2027J1171D01*
G01X1116335Y405759D01*
X1115686Y406870D01*
Y408521D01*
X1116750Y409585D01*
Y415850D01*
X1117500Y416600D01*
X1118113D01*
G01X1128530Y395597D02*
X1127230Y398597D01*
X1127146Y398743D01*
G02X1127165Y400284I1384J754D01*
G03X1127190Y402567I-2015J1164D01*
G01X1127165Y402609D01*
X1127146Y402643D01*
G02X1127165Y404184I1384J754D01*
G03X1127536Y405568I-2397J1384D01*
G01Y409901D01*
G01X1130780Y364396D02*
X1128530D01*
G01X1104871Y397546D02*
X1105628Y396789D01*
Y396293D01*
X1105326Y395991D01*
X1104621D01*
G02X1103506Y398333I250J1555D01*
G03Y400659I-2015J1163D01*
G02X1103487Y402200I1365J787D01*
G01X1103506Y402234D01*
X1103531Y402276D01*
G03X1103506Y404559I-2040J1119D01*
G01X1103379Y404779D01*
X1103378Y404780D01*
G02X1103284Y405649I940J541D01*
G01X1103314Y405759D01*
X1103326Y405801D01*
Y408886D01*
X1103030Y409182D01*
Y416547D01*
X1103430Y416947D01*
G01X1125150Y397546D02*
Y396241D01*
X1124901Y395992D01*
G02X1123786Y398333I249J1555D01*
G03Y400660I-2017J1164D01*
G02Y402234I1364J787D01*
G01X1123785Y402236D01*
G03X1123751Y404618I-2014J1162D01*
G01X1123596Y404949D01*
Y409055D01*
X1123150Y409501D01*
Y413350D01*
X1124300Y414500D01*
G01X1104871Y393647D02*
X1104502Y395249D01*
G02X1102856Y398709I369J2297D01*
G01X1102875Y398743D01*
G03X1102856Y400284I-1384J754D01*
G02X1102831Y402567I2015J1164D01*
G01X1102856Y402609D01*
X1102875Y402643D01*
G03X1102856Y404184I-1384J754D01*
G01X1102729Y404404D01*
G02X1102568Y405874I1589J918D01*
G01X1102576Y405903D01*
Y408575D01*
X1102280Y408871D01*
Y416597D01*
X1101880Y416997D01*
G01X1123750Y415082D02*
X1122400Y413732D01*
Y409149D01*
X1122846Y408703D01*
Y404783D01*
X1123122Y404190D01*
X1123135Y404185D01*
G02Y402611I-1364J-787D01*
G03X1123110Y400326I2015J-1165D01*
G01X1123135Y400284D01*
G02Y398709I-1363J-787D01*
G03X1124782Y395249I2014J-1163D01*
G03X1124865Y395237I374J2296D01*
G01X1125150Y394952D01*
Y393647D01*
G01X1104871Y401447D02*
X1106170Y404447D01*
X1106235Y404559D01*
G03X1106223Y406309I-1500J865D01*
G01X1106070Y406567D01*
X1105621Y407016D01*
Y409060D01*
X1106130Y409569D01*
Y416547D01*
X1106530Y416947D01*
G01X1125150Y401447D02*
X1126449Y404447D01*
X1126514Y404559D01*
G03X1126502Y406273I-1468J847D01*
G01X1125900Y407284D01*
Y411700D01*
X1127100Y412900D01*
G01X1108251Y403396D02*
Y408251D01*
X1109203Y409203D01*
Y416439D01*
X1109630Y416866D01*
G01X1121771Y403396D02*
Y407278D01*
X1119950Y409099D01*
Y414550D01*
X1120700Y415300D01*
X1121201D01*
G01X1128530Y403396D02*
Y408702D01*
G01X1104871Y405347D02*
Y409371D01*
X1105380Y409880D01*
Y416535D01*
X1104980Y416935D01*
G01X1125150Y405347D02*
Y412082D01*
X1126500Y413432D01*
G01X1211373Y289058D02*
X1211347Y289267D01*
X1210031Y291116D01*
X1209475Y291209D01*
X1209069Y291780D01*
X1209162Y292335D01*
X1208757Y292905D01*
X1208201Y292999D01*
X1207795Y293570D01*
X1207888Y294125D01*
X1207483Y294695D01*
X1206374Y295771D01*
X1204788D01*
X1204544Y295527D01*
X1203844D01*
X1203600Y295771D01*
X1202819D01*
G02X1200874Y296934I70J2325D01*
G03X1199553Y297722I-1365J-787D01*
G01X1199424D01*
G02X1197494Y298884I85J2325D01*
G03X1196723Y299556I-1365J-788D01*
G01X1196129Y298096D01*
G01X1206269Y261047D02*
X1208073D01*
X1208447Y261421D01*
X1211288D01*
X1211759Y260950D01*
X1225058D01*
X1225908Y261800D01*
G01X1206269Y245447D02*
X1206878Y246056D01*
G02X1207793Y245993I430J-430D01*
G03X1209579Y245071I1855J1403D01*
G01X1212838D01*
X1213109Y244800D01*
X1213607D01*
X1213878Y245071D01*
X1215638D01*
X1215801Y244908D01*
Y244565D01*
X1214732Y243496D01*
G01X1209649Y270796D02*
Y269960D01*
X1210388Y269221D01*
X1211079D01*
X1213150Y267150D01*
X1215329D01*
X1216234Y268055D01*
G01X1209649Y259096D02*
X1208962D01*
X1208408Y259650D01*
Y260321D01*
X1208758Y260671D01*
X1210977D01*
X1211448Y260200D01*
X1225008D01*
X1225908Y259300D01*
G01X1209649Y247396D02*
X1208518Y246744D01*
X1208427Y246403D01*
G03X1209605Y245821I1223J993D01*
G01X1215949D01*
X1216551Y245219D01*
Y244407D01*
X1217476Y243482D01*
G01X1209649Y266896D02*
Y267740D01*
X1210380Y268471D01*
X1210768D01*
X1212839Y266400D01*
X1215389D01*
X1216234Y265555D01*
G01X1199509Y319547D02*
X1198378Y318894D01*
X1198287Y318553D01*
G03X1199450Y317972I1223J994D01*
G01X1199579D01*
G02X1201524Y316809I-70J-2325D01*
G03X1202832Y316021I1365J787D01*
G01X1204155D01*
X1204955Y315221D01*
X1206067D01*
X1206417Y315571D01*
X1207467D01*
X1207817Y315221D01*
X1208867D01*
X1209217Y315571D01*
X1210267D01*
X1210617Y315221D01*
X1214000D01*
X1214100Y315321D01*
X1214187D01*
G01X1199509Y315647D02*
X1200640Y314994D01*
X1200745Y314601D01*
G03X1200714Y314525I2138J-917D01*
G03X1202819Y311371I2174J-829D01*
G01X1202820Y311372D01*
X1212035D01*
X1215849Y309362D01*
X1216532Y308403D01*
X1216558Y308192D01*
G01X1199509Y311747D02*
X1200178Y310076D01*
G02X1200386Y310003I-666J-2229D01*
G02X1201524Y309010I-878J-2155D01*
G01X1201523D01*
G03X1202845Y308222I1365J787D01*
G01X1210706D01*
X1214107Y306497D01*
X1215228Y304925D01*
X1215414Y304832D01*
G01X1214071Y300076D02*
X1213883Y300170D01*
X1213008Y301400D01*
X1213007D01*
X1211939Y302901D01*
X1211400Y303181D01*
X1209300Y304273D01*
X1209208Y304321D01*
X1202845D01*
G02X1201524Y305109I44J1575D01*
G03X1199579Y306272I-2015J-1162D01*
G01X1199439D01*
G03X1196129Y305896I0J-14757D01*
G01X1199509Y300047D02*
X1200640Y300699D01*
X1201033Y300593D01*
G03X1202819Y299671I1855J1403D01*
G01X1207758D01*
X1209861Y297961D01*
X1210399Y297205D01*
X1210425Y296996D01*
G01X1212147Y289609D02*
X1211958Y289703D01*
X1208055Y295186D01*
X1206679Y296521D01*
X1202832D01*
G02X1201524Y297309I57J1575D01*
G03X1199579Y298472I-2015J-1162D01*
G01X1199450D01*
G02X1198144Y299259I59J1575D01*
G03X1197007Y300252I-2016J-1161D01*
G03X1196807Y300323I-878J-2155D01*
G01X1196129Y301996D01*
G01X1214220Y335621D02*
X1214120Y335521D01*
X1213070D01*
X1212720Y335871D01*
X1211670D01*
X1211320Y335521D01*
X1209647D01*
G02X1208284Y336309I1J1574D01*
G03X1206333Y337472I-2015J-1162D01*
G01X1206210D01*
G02X1205047Y338053I60J1575D01*
G01X1205138Y338394D01*
X1206269Y339047D01*
G01X1213164Y325871D02*
X1213064Y325771D01*
X1211868D01*
X1211518Y326121D01*
X1210468D01*
X1210118Y325771D01*
X1209068D01*
X1208718Y326121D01*
X1207668D01*
X1207318Y325771D01*
X1206268D01*
G02X1204904Y326559I0J1575D01*
G03X1202976Y327721I-2015J-1163D01*
G01X1202845D01*
G02X1201667Y328303I45J1575D01*
G01X1201758Y328644D01*
X1202889Y329296D01*
G01X1206269Y323446D02*
X1205138Y324098D01*
X1204622Y323547D01*
G03X1204627Y323283I331J-126D01*
G01X1204819Y322830D01*
G03X1206268Y321871I1449J615D01*
G01X1207619D01*
X1207969Y322221D01*
X1209019D01*
X1209369Y321871D01*
X1210419D01*
X1210769Y322221D01*
X1211819D01*
X1212169Y321871D01*
X1213219D01*
X1213569Y322221D01*
X1214619D01*
X1214969Y321871D01*
X1216019D01*
X1216119Y321971D01*
X1216206D01*
G01X1202889Y321496D02*
X1204023Y319694D01*
X1206017Y317700D01*
X1217222D01*
X1217322Y317800D01*
G01X1196129Y317596D02*
X1197260Y318249D01*
X1197653Y318143D01*
G03X1199424Y317222I1855J1404D01*
G01X1199553D01*
G02X1200874Y316434I-44J-1575D01*
G03X1202819Y315271I2015J1162D01*
G01X1203844D01*
X1204644Y314471D01*
X1214000D01*
X1214100Y314371D01*
X1214187D01*
G01X1202889Y313696D02*
X1201758Y314349D01*
X1201417Y314257D01*
G03X1202818Y312122I1473J-561D01*
G01X1204113D01*
X1204471Y312480D01*
X1205521D01*
X1205879Y312122D01*
X1206929D01*
X1207287Y312480D01*
X1208337D01*
X1208695Y312122D01*
X1209745D01*
X1210103Y312480D01*
X1211153D01*
X1211511Y312122D01*
X1212221D01*
X1216357Y309943D01*
X1217144Y308837D01*
X1217332Y308743D01*
G01X1199509Y307847D02*
X1200102Y309306D01*
G02X1200874Y308634I-592J-1460D01*
G03X1202835Y307472I2014J1163D01*
G01X1203593D01*
X1203850Y307215D01*
X1204550D01*
X1204807Y307472D01*
X1206134D01*
X1206532Y307074D01*
X1207232D01*
X1207630Y307472D01*
X1208330D01*
X1208728Y307074D01*
X1209428D01*
X1209826Y307472D01*
X1210526D01*
X1213603Y305911D01*
X1214638Y304459D01*
X1214640Y304281D01*
G01X1199509Y303947D02*
X1198944Y304273D01*
X1198378Y304599D01*
X1198287Y304940D01*
G02X1199462Y305521I1222J-994D01*
G02X1199557I47J-1575D01*
G02X1200874Y304734I-47J-1575D01*
G03X1202835Y303571I2015J1162D01*
G01X1203896D01*
X1204187Y303280D01*
X1205237D01*
X1205528Y303571D01*
X1206637D01*
X1206901Y303307D01*
X1207951D01*
X1208215Y303571D01*
X1209024D01*
X1209369Y303391D01*
X1209520Y302910D01*
X1210454Y302424D01*
X1210935Y302577D01*
X1211400Y302335D01*
X1211432Y302318D01*
X1211846Y301737D01*
X1211774Y301320D01*
X1212384Y300463D01*
X1212801Y300395D01*
X1213266Y299742D01*
X1213267Y299740D01*
X1213271Y299735D01*
X1213295Y299701D01*
X1213297Y299525D01*
G01X1211199Y297547D02*
X1211010Y297641D01*
X1210413Y298479D01*
X1208025Y300421D01*
X1202845D01*
G02X1201667Y301003I45J1575D01*
G01X1201758Y301344D01*
X1202889Y301996D01*
G01Y337096D02*
G03X1206184Y336722I3295J14328D01*
G01X1206313D01*
G02X1207634Y335934I-44J-1575D01*
G03X1209648Y334771I2014J1162D01*
G01X1214076D01*
X1214176Y334671D01*
X1214220D01*
G01X1199509Y327347D02*
G03X1202819Y326971I3310J14381D01*
G01X1202960D01*
G02X1204254Y326184I-71J-1575D01*
G03X1206267Y325021I2014J1162D01*
G01X1213064D01*
X1213164Y324921D01*
X1213251D01*
G01X1202889Y325396D02*
G02X1203929Y323006I-175371J-77733D01*
G03X1203936Y322990I1015J435D01*
G01X1204128Y322537D01*
G03X1206269Y321121I2139J908D01*
G01X1216019D01*
X1216119Y321021D01*
G01X1217322Y316850D02*
X1217235D01*
X1217135Y316950D01*
X1214553D01*
X1214203Y316600D01*
X1213153D01*
X1212803Y316950D01*
X1211753D01*
X1211403Y316600D01*
X1210353D01*
X1210003Y316950D01*
X1205706D01*
X1204222Y318434D01*
X1203727D01*
X1202889Y317596D01*
G01X1219459Y355121D02*
X1219372D01*
X1219272Y355021D01*
X1217714D01*
X1217324Y355411D01*
X1216224D01*
X1215834Y355021D01*
X1214734D01*
X1214344Y355411D01*
X1213244D01*
X1212854Y355021D01*
X1209646D01*
G03X1207634Y353859I0J-2323D01*
G02X1206328Y353072I-1365J788D01*
G01X1206210D01*
G02X1204904Y353859I59J1575D01*
G03X1202974Y355021I-2015J-1163D01*
G01X1202845D01*
G02X1201667Y355603I45J1575D01*
G01X1201758Y355944D01*
X1202889Y356596D01*
G01X1221366Y349871D02*
X1221288Y349909D01*
X1221244Y350043D01*
X1220585Y350371D01*
X1209590D01*
G03X1208284Y349584I59J-1575D01*
G02X1204094Y351574I-2015J1163D01*
G02X1204125Y351652I2177J-820D01*
G01X1204020Y352044D01*
X1202889Y352696D01*
G01X1217325Y347338D02*
X1217238D01*
X1217138Y347238D01*
X1216088D01*
X1215738Y347588D01*
X1214688D01*
X1214338Y347238D01*
X1213288D01*
X1212938Y347588D01*
X1211888D01*
X1211538Y347238D01*
X1209613D01*
G02X1208427Y347803I0J1528D01*
G01X1208518Y348144D01*
X1209649Y348796D01*
G01X1215187Y343421D02*
X1215100D01*
X1215000Y343321D01*
X1209605D01*
G02X1208284Y344109I44J1575D01*
G03X1206339Y345272I-2015J-1162D01*
G01X1206210D01*
G02X1204904Y346059I59J1575D01*
G03X1203662Y347092I-2016J-1161D01*
G03X1203486Y347146I-770J-2196D01*
G01X1202889Y348796D01*
G01X1219459Y354171D02*
X1219372D01*
X1219272Y354271D01*
X1209647D01*
G03X1208284Y353484I0J-1573D01*
G02X1206341Y352322I-2015J1163D01*
G01X1206184D01*
G02X1204254Y353484I85J2325D01*
G03X1202948Y354271I-1365J-788D01*
G01X1202819D01*
G02X1201033Y355193I69J2325D01*
G01X1200640Y355299D01*
X1199509Y354647D01*
G01X1206269Y350747D02*
X1205298Y351307D01*
X1204796D01*
G03X1207634Y349959I1473J-560D01*
G02X1209564Y351121I2015J-1163D01*
G01X1212832D01*
X1213182Y351471D01*
X1214232D01*
X1214582Y351121D01*
X1215632D01*
X1215982Y351471D01*
X1217032D01*
X1217382Y351121D01*
X1218432D01*
X1218782Y351471D01*
X1219832D01*
X1220182Y351121D01*
X1220762D01*
X1221579Y350715D01*
X1221711Y350760D01*
X1221789Y350722D01*
G01X1217325Y346388D02*
X1217238D01*
X1217138Y346488D01*
X1209612D01*
G02X1207793Y347393I0J2281D01*
G01X1207400Y347499D01*
X1206269Y346847D01*
G01X1215100Y342471D02*
X1215000Y342571D01*
X1209579D01*
G02X1207634Y343734I70J2325D01*
G03X1206313Y344522I-1365J-787D01*
G01X1206184D01*
G02X1204254Y345684I85J2325D01*
G03X1203412Y346383I-1365J-788D01*
G01X1202889Y344896D01*
G01X1199509Y393647D02*
Y392341D01*
X1199759Y392091D01*
G03X1200874Y392859I-250J1556D01*
G02X1202838Y394022I2015J-1163D01*
G01X1202839Y394021D01*
X1202924D01*
G03X1203058Y394030I-39J1576D01*
G03X1203863Y394416I-145J1335D01*
G01X1205823Y396376D01*
Y396870D01*
X1206566Y397613D01*
X1207061D01*
X1207803Y398355D01*
Y398850D01*
X1208546Y399593D01*
X1209042D01*
X1211381Y401932D01*
Y402073D01*
X1211413Y402105D01*
G01X1214737Y410199D02*
X1214676Y410138D01*
X1214536D01*
X1205450Y401052D01*
Y398910D01*
X1203823Y397283D01*
X1203079D01*
G03X1201524Y396384I1J-1796D01*
G02X1199613Y395222I-2015J1162D01*
G01X1199460D01*
X1199438Y395221D01*
G03X1198144Y392859I71J-1574D01*
G02X1196199Y389371I-2015J-1163D01*
G01X1196059D01*
G02X1194324Y390229I70J2325D01*
G02X1194273Y390293I1793J1481D01*
G01X1193880Y390399D01*
X1192749Y389747D01*
G01X1189369Y391696D02*
X1189702Y390530D01*
X1189711Y390527D01*
G03X1190734Y390909I280J812D01*
G02X1192679Y392072I2015J-1162D01*
G01X1192808D01*
G03X1194133Y394400I-59J1575D01*
G01X1194114Y394434D01*
G02X1194089Y396717I2015J1164D01*
G01X1194114Y396759D01*
G03Y398333I-1365J787D01*
G01X1193900Y398702D01*
Y400454D01*
X1195366Y401920D01*
X1196805D01*
X1197493Y402607D01*
X1197494Y402609D01*
X1197971Y403436D01*
G02X1198128Y403548I1538J-1990D01*
G02X1199084Y403925I1381J-2102D01*
G01X1199306Y403963D01*
X1200048Y404705D01*
Y405200D01*
X1200791Y405943D01*
X1201286D01*
X1202028Y406685D01*
Y407180D01*
X1202771Y407923D01*
X1203266D01*
X1204008Y408665D01*
Y409160D01*
X1204751Y409903D01*
X1205246D01*
X1205669Y410326D01*
Y410468D01*
X1205731Y410530D01*
G01X1189369Y395597D02*
X1190500Y394945D01*
X1190841Y395037D01*
G03X1190734Y396384I-1472J561D01*
G01X1190721Y396405D01*
G02X1190734Y398708I2028J1140D01*
G03Y400284I-1365J788D01*
G02X1190995Y402934I1978J1143D01*
G01Y402953D01*
X1191091Y403049D01*
G03X1191180Y403529I-304J305D01*
G01X1190507Y405028D01*
Y406252D01*
X1192119Y407864D01*
X1192753D01*
X1195090Y410201D01*
X1195171D01*
X1200244Y412302D01*
X1201839Y413897D01*
Y414039D01*
X1201900Y414100D01*
G01X1204272Y423616D02*
X1204211Y423555D01*
Y423414D01*
X1192715Y411917D01*
X1191212D01*
X1188215Y408920D01*
X1187677Y407621D01*
Y405120D01*
X1187354Y404559D01*
G03X1187329Y402276I2015J-1164D01*
G01X1187354Y402234D01*
X1187373Y402200D01*
G02X1187354Y400659I-1384J-754D01*
G03X1187194Y398669I2015J-1163D01*
G03X1187225Y398591I2177J820D01*
G01X1187120Y398198D01*
X1185989Y397546D01*
G01X1182609Y403396D02*
X1183740Y402744D01*
X1184082Y402836D01*
G03X1183974Y404184I-1473J560D01*
G02X1183663Y405363I2015J1162D01*
G01Y408275D01*
X1184121Y409381D01*
X1186009Y411270D01*
X1187231Y412087D01*
X1195153Y420009D01*
Y420147D01*
G01X1216901Y390850D02*
X1216814D01*
X1216714Y390750D01*
X1214860D01*
X1208637Y388172D01*
X1206215D01*
G03X1204254Y387009I54J-2325D01*
G02X1202946Y386221I-1365J787D01*
G01X1202828D01*
G02X1201528Y387006I59J1567D01*
G01X1201478Y387092D01*
X1201466Y387104D01*
G03X1199579Y388172I-1957J-1257D01*
G01X1199439D01*
G03X1196129Y387796I0J-14757D01*
G01X1202889Y391696D02*
X1204020Y391044D01*
X1204413Y391150D01*
G02X1206199Y392072I1855J-1403D01*
G01X1209561D01*
X1212431Y393261D01*
X1213337Y394167D01*
X1214503Y394650D01*
X1215260D01*
X1215360Y394750D01*
X1215447D01*
G01X1199509Y389747D02*
Y391053D01*
X1199793Y391337D01*
G03X1199879Y391349I-278J2310D01*
G03X1201524Y392484I-371J2297D01*
G02X1202830Y393271I1365J-788D01*
G01X1202942D01*
G03X1203139Y393283I-43J2326D01*
G01Y393284D01*
G03X1204393Y393885I-226J2081D01*
G01X1204395D01*
X1211882Y401372D01*
X1212024D01*
X1212085Y401433D01*
G01X1196129Y391696D02*
X1194998Y391044D01*
X1194907Y390703D01*
G03X1196082Y390121I1223J993D01*
G03X1196177I47J1575D01*
G03X1197494Y392484I-47J1575D01*
G02X1199424Y395972I2015J1163D01*
G01X1199580D01*
G03X1200874Y396759I-71J1574D01*
G02X1203079Y398033I2205J-1272D01*
G01X1203512D01*
X1204700Y399221D01*
Y401364D01*
X1205442Y402106D01*
Y402601D01*
X1206185Y403344D01*
X1206680D01*
X1207422Y404086D01*
Y404581D01*
X1208165Y405324D01*
X1208660D01*
X1209402Y406066D01*
Y406561D01*
X1210145Y407304D01*
X1210640D01*
X1211382Y408046D01*
Y408541D01*
X1212125Y409284D01*
X1212620D01*
X1214004Y410668D01*
Y410810D01*
X1214065Y410871D01*
G01X1206403Y409858D02*
X1206342Y409797D01*
X1206202D01*
X1199667Y403263D01*
X1199211Y403185D01*
G03X1198540Y402921I297J-1739D01*
G01X1198539Y402919D01*
X1198540D01*
X1198095Y402148D01*
X1197116Y401170D01*
X1195677D01*
X1194650Y400143D01*
Y398905D01*
X1194764Y398709D01*
G02X1194789Y396426I-2015J-1164D01*
G01X1194764Y396384D01*
G03Y394810I1365J-787D01*
G02X1192834Y391322I-2015J-1163D01*
G01X1192705D01*
G03X1191384Y390534I44J-1575D01*
G02X1191190Y390248I-2017J1159D01*
G01X1189369Y387796D01*
G01X1202572Y413428D02*
X1202511Y413367D01*
X1202370D01*
X1200669Y411666D01*
X1199699Y411264D01*
X1199510Y410807D01*
X1198539Y410405D01*
X1198082Y410594D01*
X1195457Y409507D01*
X1193064Y407114D01*
X1192430D01*
X1191257Y405941D01*
Y405189D01*
X1191865Y403836D01*
G02X1191621Y402518I-1077J-482D01*
G01X1191616Y402513D01*
X1191617D01*
X1191623Y402507D01*
G03X1191559Y402439I1085J-1085D01*
G03X1191384Y400659I1153J-1012D01*
G02Y398333I-2015J-1163D01*
G03Y396759I1365J-787D01*
G01X1191409Y396717D01*
G02X1191544Y394769I-2039J-1120D01*
G02X1191513Y394692I-2173J830D01*
G01X1191618Y394299D01*
X1192749Y393647D01*
G01X1204945Y422945D02*
X1204884Y422884D01*
X1204743D01*
X1200946Y419087D01*
Y418592D01*
X1200203Y417849D01*
X1199708D01*
X1198966Y417107D01*
Y416612D01*
X1198223Y415869D01*
X1197728D01*
X1196986Y415127D01*
Y414632D01*
X1196243Y413889D01*
X1195748D01*
X1195006Y413147D01*
Y412652D01*
X1194263Y411909D01*
X1193768D01*
X1193026Y411167D01*
X1191523D01*
X1188851Y408495D01*
X1188427Y407471D01*
Y404919D01*
X1188004Y404184D01*
Y404183D01*
G03X1187985Y402643I1365J-787D01*
G01X1188004Y402609D01*
X1188029Y402567D01*
G02X1188004Y400284I-2040J-1119D01*
G03X1187896Y398936I1365J-788D01*
G01X1188238Y398844D01*
X1189369Y399496D01*
G01X1185989Y401447D02*
X1184858Y402099D01*
X1184753Y402491D01*
G03X1184784Y402569I-2146J898D01*
G03X1184624Y404559I-2175J827D01*
G02X1184413Y405360I1365J788D01*
G01Y408125D01*
X1184757Y408956D01*
X1186488Y410687D01*
X1187710Y411504D01*
X1193701Y417495D01*
X1194196D01*
X1194939Y418238D01*
Y418733D01*
X1195681Y419475D01*
X1195825D01*
G01X1216901Y389900D02*
X1216814D01*
X1216714Y390000D01*
X1215010D01*
X1214040Y389598D01*
X1213851Y389141D01*
X1212881Y388738D01*
X1212423Y388928D01*
X1211453Y388526D01*
X1211264Y388068D01*
X1210294Y387666D01*
X1209837Y387856D01*
X1208791Y387422D01*
X1206225D01*
G03X1204904Y386634I44J-1575D01*
G02X1202959Y385471I-2015J1162D01*
G01X1202815D01*
G02X1200877Y386631I71J2317D01*
G01X1200874Y386634D01*
G03X1200835Y386698I-1364J-788D01*
G03X1199557Y387421I-1325J-852D01*
G03X1198287Y386840I-48J-1575D01*
G01X1198378Y386499D01*
X1199509Y385847D01*
G01X1206269Y389747D02*
X1205138Y390399D01*
X1205047Y390740D01*
G02X1206225Y391322I1223J-993D01*
G01X1207144D01*
X1207542Y390924D01*
X1208592D01*
X1208990Y391322D01*
X1209711D01*
X1210354Y391588D01*
X1210869Y391373D01*
X1211840Y391776D01*
X1212053Y392291D01*
X1212856Y392625D01*
X1213762Y393531D01*
X1214653Y393900D01*
X1215260D01*
X1215360Y393800D01*
X1215447D01*
G01X1217364Y359491D02*
X1217277D01*
X1217177Y359391D01*
X1211714D01*
X1211244Y358921D01*
X1209564D01*
G03X1207634Y357759I85J-2325D01*
G02X1206519Y356991I-1365J788D01*
G01X1206269Y357241D01*
Y358547D01*
G01Y362447D02*
X1207400Y361794D01*
X1207793Y361900D01*
G02X1209540Y362820I1855J-1404D01*
G01X1217028D01*
X1217431Y363223D01*
X1220129D01*
X1220229Y363323D01*
X1220316D01*
G01X1206269Y366347D02*
X1205138Y365694D01*
X1205047Y365353D01*
G03X1206210Y364772I1223J994D01*
G01X1207826D01*
X1208216Y365162D01*
X1209316D01*
X1209706Y364772D01*
X1210899D01*
X1211362Y365235D01*
Y365786D01*
X1212140Y366564D01*
X1212691D01*
X1213287Y367160D01*
X1216926D01*
X1217026Y367260D01*
X1217113D01*
G01X1215721Y371142D02*
X1215634D01*
X1215534Y371042D01*
X1212678D01*
X1210308Y368672D01*
X1206199D01*
G03X1204254Y367509I70J-2325D01*
G02X1202933Y366721I-1365J787D01*
G01X1202804D01*
G03X1200874Y365559I85J-2325D01*
G02X1200078Y364877I-1365J788D01*
G01X1199509Y366347D01*
G01Y370247D02*
X1200640Y369594D01*
X1201033Y369700D01*
G02X1202838Y370622I1855J-1404D01*
G01X1202933D01*
G03X1204254Y371410I-44J1575D01*
G02X1206184Y372572I2015J-1163D01*
G01X1206185Y372571D01*
X1211049D01*
X1213389Y374911D01*
X1221602D01*
X1221702Y375011D01*
X1221789D01*
G01X1202889Y376096D02*
X1203414Y374611D01*
G03X1204254Y375309I-525J1486D01*
G02X1206218Y376472I2015J-1163D01*
G01X1206219Y376471D01*
X1210510D01*
X1211590Y377551D01*
X1214179D01*
X1215300Y378672D01*
X1217568D01*
X1217668Y378772D01*
X1217755D01*
G01X1215795Y382579D02*
X1215708D01*
X1215608Y382479D01*
X1213722D01*
X1211493Y380250D01*
X1207558D01*
X1207436Y380372D01*
X1206199D01*
G03X1202889Y379996I0J-14757D01*
G01X1216124Y385487D02*
X1216037D01*
X1215937Y385587D01*
X1214350D01*
X1212285Y383522D01*
X1206225D01*
G03X1204904Y382734I44J-1575D01*
G02X1202959Y381571I-2015J1162D01*
G02X1199509Y381947I-378J12549D01*
G01X1217364Y358541D02*
X1217277D01*
X1217177Y358641D01*
X1212025D01*
X1211555Y358171D01*
X1209590D01*
G03X1208284Y357384I59J-1575D01*
G02X1206639Y356249I-2016J1162D01*
G02X1206553Y356237I-364J2298D01*
G01X1206269Y355953D01*
Y354647D01*
G01X1209649Y360496D02*
X1208518Y361149D01*
X1208427Y361490D01*
G02X1209568Y362070I1223J-994D01*
G01X1210668D01*
X1211058Y361680D01*
X1212158D01*
X1212548Y362070D01*
X1213648D01*
X1214038Y361680D01*
X1215138D01*
X1215528Y362070D01*
X1217339D01*
X1217742Y362473D01*
X1220129D01*
X1220229Y362373D01*
X1220316D01*
G01X1217113Y366310D02*
X1217026D01*
X1216926Y366410D01*
X1213598D01*
X1211210Y364022D01*
X1206184D01*
G02X1204413Y364943I84J2325D01*
G01X1204020Y365049D01*
X1202889Y364396D01*
G01X1215721Y370192D02*
X1215634D01*
X1215534Y370292D01*
X1212989D01*
X1210619Y367922D01*
X1206212D01*
G03X1204904Y367134I57J-1575D01*
G02X1202959Y365971I-2015J1162D01*
G01X1202830D01*
G03X1201524Y365184I59J-1575D01*
G02X1200349Y364177I-2015J1162D01*
G02X1200110Y364099I-840J2169D01*
G01X1199509Y362447D01*
G01X1221789Y374061D02*
X1221702D01*
X1221602Y374161D01*
X1219660D01*
X1219270Y373771D01*
X1218170D01*
X1217780Y374161D01*
X1216680D01*
X1216290Y373771D01*
X1215190D01*
X1214800Y374161D01*
X1213700D01*
X1211360Y371821D01*
X1206198D01*
G03X1204904Y371034I71J-1574D01*
G02X1202940Y369871I-2015J1163D01*
G01X1202830D01*
G03X1201667Y369290I60J-1575D01*
G01X1201758Y368949D01*
X1202889Y368296D01*
G01Y372197D02*
X1203500Y373850D01*
G03X1203665Y373902I-616J2243D01*
G03X1204904Y374933I-777J2193D01*
G02X1206225Y375721I1365J-787D01*
G01X1210821D01*
X1211901Y376801D01*
X1214490D01*
X1215611Y377922D01*
X1217568D01*
X1217668Y377822D01*
X1217755D01*
G01X1215795Y381629D02*
X1215708D01*
X1215608Y381729D01*
X1214033D01*
X1211804Y379500D01*
X1210704D01*
X1210314Y379110D01*
X1209214D01*
X1208824Y379500D01*
X1207247D01*
X1207125Y379622D01*
X1206225D01*
G03X1205047Y379040I45J-1575D01*
G01X1205138Y378699D01*
X1206269Y378047D01*
G01X1216124Y386437D02*
X1216037D01*
X1215937Y386337D01*
X1214039D01*
X1211974Y384272D01*
X1206215D01*
G03X1204254Y383109I54J-2325D01*
G02X1202937Y382322I-1364J788D01*
G02X1201862Y382703I-47J1575D01*
G02X1202889Y383896I513J597D01*
G01X1425130Y471133D02*
X1425215Y471150D01*
X1425334Y471069D01*
X1427397Y471481D01*
X1427671Y471893D01*
X1428701Y472099D01*
X1429113Y471824D01*
Y471825D01*
X1430143Y472031D01*
X1430417Y472442D01*
X1431447Y472648D01*
X1431859Y472373D01*
X1432889Y472579D01*
X1433163Y472991D01*
X1434193Y473196D01*
X1434605Y472922D01*
X1436312Y473263D01*
Y473262D01*
X1436587Y473674D01*
X1437617Y473880D01*
X1438028Y473605D01*
X1439058Y473811D01*
X1439333Y474223D01*
X1440363Y474429D01*
X1440774Y474154D01*
X1442136Y474426D01*
X1444713Y476144D01*
X1444810Y476629D01*
X1445684Y477212D01*
X1446169Y477115D01*
X1447043Y477697D01*
X1447140Y478182D01*
X1448014Y478765D01*
X1448499Y478668D01*
X1449373Y479250D01*
X1450423D01*
X1450773Y479600D01*
X1451823D01*
X1452173Y479250D01*
X1453223D01*
X1453573Y479600D01*
X1454623D01*
X1454973Y479250D01*
X1456023D01*
X1456373Y479600D01*
X1457423D01*
X1457773Y479250D01*
X1458823D01*
X1459173Y479600D01*
X1460223D01*
X1460573Y479250D01*
X1463722D01*
X1471624Y475977D01*
X1473855Y473746D01*
X1476639D01*
X1476732Y473839D01*
G01X1475098Y479744D02*
X1474347D01*
X1473141Y480950D01*
X1469911Y482288D01*
X1469169Y483030D01*
Y483525D01*
X1468426Y484268D01*
X1467931D01*
X1467189Y485010D01*
Y485505D01*
X1466446Y486248D01*
X1465951D01*
X1465100Y487099D01*
Y488849D01*
X1465450Y489199D01*
Y490249D01*
X1465100Y490599D01*
Y492000D01*
X1464358Y492742D01*
Y493237D01*
X1463615Y493980D01*
X1463120D01*
X1462378Y494722D01*
Y495217D01*
X1461635Y495960D01*
X1461140D01*
X1459650Y497450D01*
X1458600D01*
X1458250Y497800D01*
X1457200D01*
X1456850Y497450D01*
X1455800D01*
X1455450Y497800D01*
X1454400D01*
X1454050Y497450D01*
X1453000D01*
X1452650Y497800D01*
X1451600D01*
X1451250Y497450D01*
X1449550D01*
X1448608Y498392D01*
Y498887D01*
X1447865Y499630D01*
X1447370D01*
X1445350Y501650D01*
X1444300D01*
X1443950Y502000D01*
X1442900D01*
X1442550Y501650D01*
X1441500D01*
X1441150Y502000D01*
X1440100D01*
X1439750Y501650D01*
X1438700D01*
X1438350Y502000D01*
X1437300D01*
X1436950Y501650D01*
X1435523D01*
X1435423Y501750D01*
X1435336D01*
G01X1480000Y477776D02*
X1477417Y476757D01*
X1477193Y476533D01*
X1476511D01*
X1475547Y476932D01*
X1473957D01*
X1472613Y478276D01*
X1468432Y480008D01*
X1461320Y487120D01*
X1460600D01*
X1458650Y489070D01*
Y489350D01*
X1457400Y490600D01*
X1447639D01*
X1444450Y493789D01*
Y495449D01*
X1443099Y496800D01*
X1433000D01*
X1432900Y496700D01*
X1432813D01*
G01X1478366Y479744D02*
X1476042Y478920D01*
X1475740Y478618D01*
X1474412D01*
X1472716Y480314D01*
X1469486Y481652D01*
X1464350Y486788D01*
Y491689D01*
X1459339Y496700D01*
X1449239D01*
X1445039Y500900D01*
X1435523D01*
X1435423Y500800D01*
X1435336D01*
G01X1444813Y505000D02*
X1444900D01*
X1445000Y505100D01*
X1446739D01*
X1452789Y499050D01*
X1461350D01*
X1469850Y490550D01*
Y484692D01*
X1470206Y483833D01*
X1471170Y482869D01*
X1474516Y481483D01*
X1474869Y481130D01*
X1476512Y480449D01*
X1476513Y480450D01*
X1476886D01*
X1477592Y480742D01*
X1477700Y480850D01*
X1480000Y481713D01*
G01X1425315Y470201D02*
X1425400Y470218D01*
X1425480Y470333D01*
X1442429Y473719D01*
X1449600Y478500D01*
X1463572D01*
X1471199Y475341D01*
X1473544Y472996D01*
X1475506D01*
X1476458Y472602D01*
X1477228D01*
X1477545Y472919D01*
X1480000Y473839D01*
G01X1476732Y481713D02*
Y481633D01*
X1476405Y481306D01*
X1475294Y481766D01*
X1474941Y482119D01*
X1471595Y483505D01*
X1470842Y484259D01*
X1470600Y484842D01*
Y486026D01*
X1470990Y486416D01*
Y487116D01*
X1470600Y487506D01*
Y488206D01*
X1470990Y488596D01*
Y489296D01*
X1470600Y489686D01*
Y490861D01*
X1469858Y491603D01*
Y492098D01*
X1469115Y492841D01*
X1468620D01*
X1467878Y493583D01*
Y494078D01*
X1467135Y494821D01*
X1466640D01*
X1465898Y495563D01*
Y496058D01*
X1465155Y496801D01*
X1464660D01*
X1463918Y497543D01*
Y498038D01*
X1463175Y498781D01*
X1462680D01*
X1461661Y499800D01*
X1460911D01*
X1460561Y500150D01*
X1459511D01*
X1459161Y499800D01*
X1458111D01*
X1457761Y500150D01*
X1456711D01*
X1456361Y499800D01*
X1455311D01*
X1455097Y500014D01*
X1453775D01*
X1453561Y499800D01*
X1453100D01*
X1451980Y500920D01*
Y501414D01*
X1451238Y502157D01*
X1450743D01*
X1450001Y502899D01*
Y503394D01*
X1449258Y504137D01*
X1448763D01*
X1447050Y505850D01*
X1445000D01*
X1444900Y505950D01*
X1444813D01*
G01X1482673Y374030D02*
X1481574Y372931D01*
X1480329D01*
X1479750Y372352D01*
Y370752D01*
G01X1476732Y402972D02*
X1475514D01*
X1475144Y403342D01*
X1474384D01*
X1474014Y402972D01*
X1473438D01*
X1471645Y404765D01*
X1469382D01*
X1468817Y404200D01*
X1467100D01*
X1466450Y403550D01*
Y402899D01*
X1465921Y402370D01*
X1465048D01*
G01X1480000Y391161D02*
X1478548D01*
X1477285Y389898D01*
X1476135D01*
X1475715Y390318D01*
X1473648D01*
X1472415Y389085D01*
G01X1460500Y389000D02*
X1466400D01*
X1467900Y390500D01*
X1472500D01*
X1473161Y391161D01*
X1476732D01*
G01X1475098Y436437D02*
X1474417D01*
X1474167Y436687D01*
X1471659D01*
X1471309Y437037D01*
X1470259D01*
X1469909Y436687D01*
X1468859D01*
X1467496Y435324D01*
X1466446D01*
X1466096Y435674D01*
X1465046D01*
X1464696Y435324D01*
X1461885D01*
X1459478Y432917D01*
Y432851D01*
G01X1478366Y436437D02*
X1475973Y435551D01*
X1475964Y435542D01*
X1475945D01*
X1475715Y435312D01*
X1474481D01*
X1473856Y435937D01*
X1469170D01*
X1467807Y434574D01*
X1463760D01*
X1462131Y432945D01*
Y432851D01*
G01X1480000Y442343D02*
X1477606Y441454D01*
X1477135Y441105D01*
X1476315D01*
X1475391Y441593D01*
X1472400D01*
X1470347Y439540D01*
X1463430D01*
X1457390Y433500D01*
X1455386D01*
X1454500Y432614D01*
Y431500D01*
G01X1449032Y439175D02*
X1449119D01*
X1449219Y439275D01*
X1459233D01*
X1461992Y442034D01*
X1469122D01*
X1470249Y443161D01*
X1475740D01*
X1476030Y443451D01*
X1478366Y444311D01*
G01X1480000Y446280D02*
X1477426Y445264D01*
X1477215Y445053D01*
X1476454D01*
X1475529Y445436D01*
X1474441D01*
X1474122Y445117D01*
X1469108D01*
X1468467Y444476D01*
X1455532D01*
X1454500Y443444D01*
Y442500D01*
G01X1478366Y448248D02*
X1475472Y447123D01*
X1458323D01*
X1455071Y450375D01*
X1449533D01*
X1449433Y450275D01*
X1449346D01*
G01X1476732Y442343D02*
X1472089D01*
X1471586Y441840D01*
X1471025D01*
X1470530Y441346D01*
Y440784D01*
X1470036Y440290D01*
X1469406D01*
X1469007Y440689D01*
X1468377D01*
X1467978Y440290D01*
X1467348D01*
X1466949Y440689D01*
X1466319D01*
X1465920Y440290D01*
X1465290D01*
X1464891Y440689D01*
X1464261D01*
X1463862Y440290D01*
X1463119D01*
X1462667Y439838D01*
X1462105D01*
X1461652Y439385D01*
Y438823D01*
X1461200Y438371D01*
X1460638D01*
X1460185Y437918D01*
Y437356D01*
X1459733Y436904D01*
X1459171D01*
X1458718Y436451D01*
Y435889D01*
X1458266Y435437D01*
X1457704D01*
X1457251Y434984D01*
Y434600D01*
X1456901Y434250D01*
X1455037D01*
X1454500Y434787D01*
Y437000D01*
G01X1475098Y444311D02*
X1474698Y443911D01*
X1474036D01*
X1473684Y444263D01*
X1472984D01*
X1472632Y443911D01*
X1471932D01*
X1471580Y444263D01*
X1470880D01*
X1470528Y443911D01*
X1469938D01*
X1468811Y442784D01*
X1468296D01*
X1467938Y443142D01*
X1467238D01*
X1466880Y442784D01*
X1466180D01*
X1465822Y443142D01*
X1465122D01*
X1464764Y442784D01*
X1464064D01*
X1463706Y443142D01*
X1463006D01*
X1462648Y442784D01*
X1461681D01*
X1460928Y442031D01*
X1460364D01*
X1459869Y441536D01*
Y440972D01*
X1458922Y440025D01*
X1458319D01*
X1457921Y440423D01*
X1457221D01*
X1456823Y440025D01*
X1456123D01*
X1455725Y440423D01*
X1455025D01*
X1454627Y440025D01*
X1453714D01*
X1453316Y440423D01*
X1452616D01*
X1452218Y440025D01*
X1451400D01*
X1451002Y440423D01*
X1450302D01*
X1449904Y440025D01*
X1449219D01*
X1449119Y440125D01*
X1449032D01*
G01X1476732Y446280D02*
X1476638Y446186D01*
X1474130D01*
X1473811Y445867D01*
X1473099D01*
X1472701Y446265D01*
X1472001D01*
X1471603Y445867D01*
X1470903D01*
X1470505Y446265D01*
X1469805D01*
X1469407Y445867D01*
X1468797D01*
X1468156Y445226D01*
X1467456D01*
X1467058Y445624D01*
X1466358D01*
X1465960Y445226D01*
X1465260D01*
X1464862Y445624D01*
X1464162D01*
X1463764Y445226D01*
X1463064D01*
X1462666Y445624D01*
X1461966D01*
X1461568Y445226D01*
X1460868D01*
X1460470Y445624D01*
X1459770D01*
X1459372Y445226D01*
X1458539D01*
X1458141Y445624D01*
X1457441D01*
X1457043Y445226D01*
X1455150D01*
X1454500Y445876D01*
Y448000D01*
G01X1475098Y448248D02*
Y448223D01*
X1474748Y447873D01*
X1474048D01*
X1473649Y448272D01*
X1472949D01*
X1472550Y447873D01*
X1471850D01*
X1471451Y448272D01*
X1470751D01*
X1470352Y447873D01*
X1469652D01*
X1469253Y448272D01*
X1468553D01*
X1468154Y447873D01*
X1467454D01*
X1467055Y448272D01*
X1466355D01*
X1465956Y447873D01*
X1465256D01*
X1464857Y448272D01*
X1464157D01*
X1463758Y447873D01*
X1463058D01*
X1462659Y448272D01*
X1461959D01*
X1461560Y447873D01*
X1460860D01*
X1460461Y448272D01*
X1459761D01*
X1459362Y447873D01*
X1458634D01*
X1456980Y449527D01*
Y450091D01*
X1456485Y450586D01*
X1455921D01*
X1455382Y451125D01*
X1454682D01*
X1454283Y451524D01*
X1453583D01*
X1453184Y451125D01*
X1452484D01*
X1452085Y451524D01*
X1451385D01*
X1450986Y451125D01*
X1449533D01*
X1449433Y451225D01*
X1449346D01*
G01X1476732Y430531D02*
X1476101Y431162D01*
X1462896D01*
G01X1480000Y430531D02*
X1478601D01*
X1477376Y429306D01*
X1476133D01*
X1475722Y429717D01*
X1464073D01*
X1461294Y426938D01*
G01X1475098Y416752D02*
X1475099D01*
X1475195Y416656D01*
Y416162D01*
X1473911Y414876D01*
X1472861D01*
X1472511Y415226D01*
X1471461D01*
X1471111Y414876D01*
X1470061D01*
X1469711Y415226D01*
X1468661D01*
X1468311Y414876D01*
X1467358D01*
X1465019Y412537D01*
Y409408D01*
X1464557Y408946D01*
X1464062D01*
X1463320Y408203D01*
Y407709D01*
X1462833Y407222D01*
X1461733D01*
X1461383Y407572D01*
X1460283D01*
X1459933Y407222D01*
X1456659D01*
X1456309Y407572D01*
X1455209D01*
X1454859Y407222D01*
X1453759D01*
X1453409Y407572D01*
X1452309D01*
X1451959Y407222D01*
X1450859D01*
X1450509Y407572D01*
X1449409D01*
X1449059Y407222D01*
X1447959D01*
X1447609Y407572D01*
X1446509D01*
X1446159Y407222D01*
X1445059D01*
X1443252Y409029D01*
G01X1478366Y416752D02*
X1475968Y415873D01*
X1474222Y414126D01*
X1467669D01*
X1465769Y412226D01*
Y409097D01*
X1463144Y406472D01*
X1442830D01*
G01X1476732Y418720D02*
X1476497Y418485D01*
X1475981D01*
X1475822Y418644D01*
X1474116D01*
X1473068Y417596D01*
X1472670D01*
X1472271Y417995D01*
X1471641D01*
X1471242Y417596D01*
X1470612D01*
X1470213Y417995D01*
X1469583D01*
X1469184Y417596D01*
X1468554D01*
X1468155Y417995D01*
X1467525D01*
X1467126Y417596D01*
X1466496D01*
X1466097Y417995D01*
X1465467D01*
X1465068Y417596D01*
X1464270D01*
X1463825Y417151D01*
X1463260D01*
X1462815Y416705D01*
Y416141D01*
X1462369Y415695D01*
X1461805D01*
X1461360Y415250D01*
Y414686D01*
X1460909Y414235D01*
Y413163D01*
X1460145Y412399D01*
X1457994D01*
X1457569Y412824D01*
Y414166D01*
G01X1480000Y418720D02*
X1477769Y417834D01*
X1477484Y417653D01*
X1476847Y417480D01*
X1476442D01*
X1475442Y417894D01*
X1474427D01*
X1473379Y416846D01*
X1464581D01*
X1461659Y413924D01*
Y412852D01*
X1460456Y411649D01*
X1458552D01*
X1457569Y410666D01*
G01X1480000Y454154D02*
X1477598Y453250D01*
X1477273Y452925D01*
X1476430D01*
X1475499Y453310D01*
X1470076D01*
X1468441Y451675D01*
X1464633D01*
X1464200Y451242D01*
Y449997D01*
G01X1478366Y456122D02*
X1475954Y455231D01*
X1475720Y454997D01*
X1468946D01*
X1468268Y455675D01*
X1464649D01*
X1464400Y455426D01*
Y454100D01*
G01X1480000Y458091D02*
X1477605Y457210D01*
X1477258Y456863D01*
X1476445D01*
X1475519Y457247D01*
X1469342D01*
X1469114Y457475D01*
X1462643D01*
X1461053Y455885D01*
X1456648D01*
X1456298Y455535D01*
Y454402D01*
X1456600Y454100D01*
G01X1478366Y460059D02*
X1476058Y459268D01*
X1475724Y458934D01*
X1470305D01*
X1467864Y461375D01*
X1464442D01*
X1464249Y461182D01*
Y459951D01*
X1464400Y459800D01*
G01X1480000Y462028D02*
X1477529Y461093D01*
X1477236Y460800D01*
X1476447D01*
X1475520Y461184D01*
X1471154D01*
X1469163Y463175D01*
X1462643D01*
X1461053Y461585D01*
X1456648D01*
X1456298Y461235D01*
Y460102D01*
X1456600Y459800D01*
G01X1476732Y454154D02*
X1476501Y453923D01*
X1476018D01*
X1475695Y454246D01*
X1474995D01*
X1474809Y454060D01*
X1474171D01*
X1473986Y454245D01*
X1473286D01*
X1473101Y454060D01*
X1472521D01*
X1472336Y454245D01*
X1471636D01*
X1471451Y454060D01*
X1470914D01*
X1470732Y454242D01*
X1469947D01*
X1469534Y453829D01*
X1468973D01*
X1468478Y453334D01*
Y452773D01*
X1468130Y452425D01*
X1463027D01*
X1461600Y450998D01*
Y449997D01*
G01X1475098Y456122D02*
X1474723Y455747D01*
X1473683D01*
X1473285Y456145D01*
X1472585D01*
X1472187Y455747D01*
X1471487D01*
X1471089Y456145D01*
X1470389D01*
X1469991Y455747D01*
X1469257D01*
X1468579Y456425D01*
X1464338D01*
X1462990Y455077D01*
Y454794D01*
X1462296Y454100D01*
X1461800D01*
G01X1476732Y458091D02*
X1476543Y457902D01*
X1475921D01*
X1475639Y458184D01*
X1474939D01*
X1474752Y457997D01*
X1474084D01*
X1473897Y458184D01*
X1473197D01*
X1473010Y457997D01*
X1469653D01*
X1469425Y458225D01*
X1466375D01*
X1466081Y458519D01*
X1465381D01*
X1465087Y458225D01*
X1462332D01*
X1461956Y457849D01*
X1461597D01*
X1461102Y457354D01*
Y456995D01*
X1460742Y456635D01*
X1460168D01*
X1459810Y456993D01*
X1459110D01*
X1458752Y456635D01*
X1458052D01*
X1457694Y456993D01*
X1456994D01*
X1456636Y456635D01*
X1456337D01*
X1455548Y455846D01*
Y455292D01*
X1454356Y454100D01*
X1454000D01*
G01X1475098Y460059D02*
Y459885D01*
X1474897Y459684D01*
X1473893D01*
X1473495Y460082D01*
X1472795D01*
X1472397Y459684D01*
X1470616D01*
X1470005Y460295D01*
Y460790D01*
X1469510Y461285D01*
X1469015D01*
X1467875Y462425D01*
X1466871D01*
X1466571Y462125D01*
X1465896D01*
X1465596Y462425D01*
X1464795D01*
X1464495Y462125D01*
X1464131D01*
X1463499Y461493D01*
Y461123D01*
X1462176Y459800D01*
X1461800D01*
G01X1476732Y462028D02*
X1476533Y461829D01*
X1475932D01*
X1475827Y461934D01*
X1474084D01*
X1473897Y462121D01*
X1473197D01*
X1473010Y461934D01*
X1471465D01*
X1469474Y463925D01*
X1466392D01*
X1466123Y464194D01*
X1465423D01*
X1465154Y463925D01*
X1462332D01*
X1461956Y463549D01*
X1461597D01*
X1461102Y463054D01*
Y462695D01*
X1460742Y462335D01*
X1460168D01*
X1459810Y462693D01*
X1459110D01*
X1458752Y462335D01*
X1458052D01*
X1457694Y462693D01*
X1456994D01*
X1456636Y462335D01*
X1454773D01*
X1454000Y461562D01*
Y459800D01*
G01X1478366Y467933D02*
X1475910Y467009D01*
X1475709Y466808D01*
X1472691D01*
X1468899Y470600D01*
X1454200D01*
X1442555Y458955D01*
X1440387D01*
X1440287Y458855D01*
X1440200D01*
G01X1480000Y469902D02*
X1477513Y468946D01*
X1477242Y468675D01*
X1476444D01*
X1475501Y469066D01*
X1473058D01*
X1469607Y472517D01*
X1451854D01*
X1443191Y463854D01*
X1435908D01*
X1433973Y462790D01*
X1433185Y462615D01*
X1433184Y462614D01*
X1433182D01*
X1433108Y462496D01*
X1433023Y462477D01*
G01X1475098Y467933D02*
X1474723Y467558D01*
X1473002D01*
X1472224Y468336D01*
Y468831D01*
X1471446Y469609D01*
X1470951D01*
X1469210Y471350D01*
X1468160D01*
X1467810Y471700D01*
X1466760D01*
X1466410Y471350D01*
X1465360D01*
X1465010Y471700D01*
X1463960D01*
X1463610Y471350D01*
X1462560D01*
X1462210Y471700D01*
X1461160D01*
X1460810Y471350D01*
X1459760D01*
X1459410Y471700D01*
X1458360D01*
X1458010Y471350D01*
X1456960D01*
X1456610Y471700D01*
X1455560D01*
X1455210Y471350D01*
X1453889D01*
X1453147Y470608D01*
X1452652D01*
X1451909Y469865D01*
Y469370D01*
X1451167Y468628D01*
X1450672D01*
X1449929Y467885D01*
Y467390D01*
X1449187Y466648D01*
X1448692D01*
X1447949Y465905D01*
Y465410D01*
X1447207Y464668D01*
X1446712D01*
X1445969Y463925D01*
Y463430D01*
X1445227Y462688D01*
X1444732D01*
X1443989Y461945D01*
Y461450D01*
X1442244Y459705D01*
X1440388D01*
X1440288Y459805D01*
X1440200D01*
G01X1476732Y469902D02*
X1476646Y469816D01*
X1473369D01*
X1469918Y473267D01*
X1468868D01*
X1468518Y473617D01*
X1467468D01*
X1467118Y473267D01*
X1466068D01*
X1465718Y473617D01*
X1464668D01*
X1464318Y473267D01*
X1463268D01*
X1462918Y473617D01*
X1461868D01*
X1461518Y473267D01*
X1460468D01*
X1460118Y473617D01*
X1459068D01*
X1458718Y473267D01*
X1457668D01*
X1457318Y473617D01*
X1456268D01*
X1455918Y473267D01*
X1454868D01*
X1454518Y473617D01*
X1453468D01*
X1453118Y473267D01*
X1451543D01*
X1450801Y472525D01*
X1450306D01*
X1449563Y471782D01*
Y471287D01*
X1448821Y470545D01*
X1448326D01*
X1447583Y469802D01*
Y469307D01*
X1446841Y468565D01*
X1446346D01*
X1445603Y467822D01*
Y467327D01*
X1444861Y466585D01*
X1444366D01*
X1443623Y465842D01*
Y465347D01*
X1442880Y464604D01*
X1441830D01*
X1441480Y464954D01*
X1440430D01*
X1440080Y464604D01*
X1435715D01*
X1433708Y463501D01*
X1433023Y463348D01*
X1433021Y463347D01*
X1432902Y463424D01*
X1432817Y463405D01*
G01X1478366Y463996D02*
X1475985Y463133D01*
X1475723Y462871D01*
X1472028D01*
X1467824Y467075D01*
X1464442D01*
X1464249Y466882D01*
Y465651D01*
X1464400Y465500D01*
G01X1480000Y465965D02*
X1477578Y465055D01*
X1477262Y464739D01*
X1476394D01*
X1475472Y465121D01*
X1472218D01*
X1468289Y469050D01*
X1462818D01*
X1461053Y467285D01*
X1456648D01*
X1456298Y466935D01*
Y466230D01*
X1456600Y465500D01*
G01X1475098Y463996D02*
Y463821D01*
X1474898Y463621D01*
X1474211D01*
X1473888Y463944D01*
X1473188D01*
X1472865Y463621D01*
X1472339D01*
X1467744Y468216D01*
X1466962D01*
X1466571Y467825D01*
X1465936D01*
X1465545Y468216D01*
X1464846D01*
X1464455Y467825D01*
X1464131D01*
X1463499Y467193D01*
Y466823D01*
X1462176Y465500D01*
X1461800D01*
G01X1476732Y465965D02*
X1476500Y465733D01*
X1475964D01*
X1475639Y466058D01*
X1474939D01*
X1474752Y465871D01*
X1474083D01*
X1473897Y466057D01*
X1473197D01*
X1473011Y465871D01*
X1472529D01*
X1468600Y469800D01*
X1462507D01*
X1462103Y469396D01*
X1461616D01*
X1461121Y468901D01*
Y468414D01*
X1460742Y468035D01*
X1460168D01*
X1459810Y468393D01*
X1459110D01*
X1458752Y468035D01*
X1458052D01*
X1457694Y468393D01*
X1456994D01*
X1456636Y468035D01*
X1456337D01*
X1455548Y467246D01*
Y466692D01*
X1454356Y465500D01*
X1454000D01*
G01X1478366Y471870D02*
X1476635Y471258D01*
X1475724Y470743D01*
X1473555D01*
X1470289Y474009D01*
X1468837Y474493D01*
X1450850D01*
X1442785Y469117D01*
X1432666Y467092D01*
X1432662Y467091D01*
X1432585Y466975D01*
X1432500Y466959D01*
G01X1478366Y475807D02*
X1475951Y474918D01*
X1475715Y474682D01*
X1474057D01*
X1471774Y476965D01*
X1458549Y482400D01*
X1445739D01*
X1442739Y485400D01*
X1428829D01*
X1428729Y485300D01*
X1428642D01*
G01X1475098Y471870D02*
X1474721Y471493D01*
X1473866D01*
X1470694Y474665D01*
X1468959Y475243D01*
X1467909D01*
X1467519Y475633D01*
X1466469D01*
X1466079Y475243D01*
X1465029D01*
X1464639Y475633D01*
X1463589D01*
X1463199Y475243D01*
X1462149D01*
X1461759Y475633D01*
X1460709D01*
X1460319Y475243D01*
X1459269D01*
X1458879Y475633D01*
X1457829D01*
X1457439Y475243D01*
X1456389D01*
X1455999Y475633D01*
X1454949D01*
X1454559Y475243D01*
X1453509D01*
X1453119Y475633D01*
X1452069D01*
X1451679Y475243D01*
X1450622D01*
X1449598Y474561D01*
X1449113Y474658D01*
X1448239Y474075D01*
X1448142Y473590D01*
X1447268Y473008D01*
X1446783Y473105D01*
X1445909Y472522D01*
X1445812Y472037D01*
X1444938Y471455D01*
X1444453Y471552D01*
X1443579Y470969D01*
X1443482Y470484D01*
X1442492Y469824D01*
X1441462Y469618D01*
X1441051Y469892D01*
X1440021Y469686D01*
X1439746Y469275D01*
X1438716Y469069D01*
X1438305Y469343D01*
X1437275Y469137D01*
X1437000Y468725D01*
X1432518Y467828D01*
X1432399Y467908D01*
X1432314Y467891D01*
G01X1475098Y475807D02*
X1473993D01*
X1472198Y477602D01*
X1467438Y479558D01*
X1467247Y480015D01*
X1466276Y480414D01*
X1465819Y480224D01*
X1464848Y480623D01*
X1464657Y481080D01*
X1463686Y481479D01*
X1463229Y481288D01*
X1462258Y481687D01*
X1462067Y482144D01*
X1461096Y482543D01*
X1460639Y482352D01*
X1458698Y483150D01*
X1457648D01*
X1457298Y483500D01*
X1456248D01*
X1455898Y483150D01*
X1454848D01*
X1454498Y483500D01*
X1453448D01*
X1453098Y483150D01*
X1452048D01*
X1451698Y483500D01*
X1450648D01*
X1450298Y483150D01*
X1449248D01*
X1448898Y483500D01*
X1447848D01*
X1447498Y483150D01*
X1446050D01*
X1445308Y483892D01*
Y484387D01*
X1444565Y485130D01*
X1444070D01*
X1443050Y486150D01*
X1442000D01*
X1441650Y486500D01*
X1440600D01*
X1440250Y486150D01*
X1439200D01*
X1438850Y486500D01*
X1437800D01*
X1437450Y486150D01*
X1436400D01*
X1436050Y486500D01*
X1435000D01*
X1434650Y486150D01*
X1432229D01*
X1431879Y486500D01*
X1430829D01*
X1430479Y486150D01*
X1428829D01*
X1428729Y486250D01*
X1428642D01*
G01X1476732Y477776D02*
X1476475Y477519D01*
X1476091D01*
X1475697Y477682D01*
X1474268D01*
X1473038Y478912D01*
X1472068Y479314D01*
X1471879Y479771D01*
X1470908Y480173D01*
X1470451Y479984D01*
X1468857Y480644D01*
X1467637Y481864D01*
Y482359D01*
X1466894Y483102D01*
X1466399D01*
X1465657Y483844D01*
Y484339D01*
X1464914Y485082D01*
X1464419D01*
X1463677Y485824D01*
Y486319D01*
X1462934Y487062D01*
X1462439D01*
X1461631Y487870D01*
X1460911D01*
X1459400Y489381D01*
Y489661D01*
X1457711Y491350D01*
X1456661D01*
X1456311Y491700D01*
X1455261D01*
X1454911Y491350D01*
X1453861D01*
X1453511Y491700D01*
X1452461D01*
X1452111Y491350D01*
X1451061D01*
X1450711Y491700D01*
X1449661D01*
X1449311Y491350D01*
X1447950D01*
X1447208Y492092D01*
Y492587D01*
X1446465Y493330D01*
X1445970D01*
X1445200Y494100D01*
Y495760D01*
X1443410Y497550D01*
X1442360D01*
X1442010Y497900D01*
X1440960D01*
X1440610Y497550D01*
X1439560D01*
X1439210Y497900D01*
X1438160D01*
X1437810Y497550D01*
X1436760D01*
X1436410Y497900D01*
X1435360D01*
X1435010Y497550D01*
X1433000D01*
X1432900Y497650D01*
X1432813D01*
G01X1480000Y485650D02*
Y486500D01*
X1479300Y487200D01*
Y488189D01*
X1478471Y489018D01*
X1477296Y489505D01*
X1476600Y490201D01*
Y490850D01*
X1475652Y491798D01*
X1474512D01*
X1474238Y491911D01*
X1473296Y492853D01*
X1472230Y495426D01*
Y496833D01*
X1472286Y496889D01*
Y501053D01*
X1472061Y501278D01*
G01X1481634Y487618D02*
X1481618D01*
X1481050Y487050D01*
X1480511D01*
X1480050Y487511D01*
Y488500D01*
X1479350Y489200D01*
Y491550D01*
X1478850Y492050D01*
X1477345D01*
X1476849Y492546D01*
Y494319D01*
X1475397Y495771D01*
Y496585D01*
X1473036Y498946D01*
Y501053D01*
X1473261Y501278D01*
G01X1499941Y368287D02*
X1499816Y368162D01*
Y364275D01*
X1498246Y362705D01*
G01X1505536Y360686D02*
X1506400Y361550D01*
Y363514D01*
X1507815Y364929D01*
Y368287D01*
G01X1488130Y371555D02*
X1486253Y369678D01*
Y364753D01*
X1486000Y364500D01*
G01X1492067Y371555D02*
Y370157D01*
X1490903Y368993D01*
Y367626D01*
X1491615Y366914D01*
Y366913D01*
G01X1486161Y373189D02*
X1484099D01*
X1482788Y371878D01*
Y370219D01*
X1482970Y370037D01*
Y367574D01*
X1481500Y366104D01*
Y365500D01*
G01X1514265Y355542D02*
X1513306Y356501D01*
Y360338D01*
X1513431Y360463D01*
Y365178D01*
X1514564Y366311D01*
Y369031D01*
X1514992Y369459D01*
Y370492D01*
X1513721Y371763D01*
Y373188D01*
X1513720Y373189D01*
G01X1497972D02*
X1497973Y373188D01*
Y371685D01*
X1496753Y370465D01*
Y370435D01*
X1496747Y370429D01*
Y369413D01*
X1497129Y369031D01*
Y367670D01*
X1496471Y367012D01*
X1496454D01*
X1495552Y366110D01*
Y364865D01*
G01X1512520Y355283D02*
Y360612D01*
X1512682Y360774D01*
Y365765D01*
X1513627Y366710D01*
Y366711D01*
X1513720Y366804D01*
Y369921D01*
G01X1478366Y393130D02*
X1477648Y392412D01*
X1476165D01*
X1475758Y392005D01*
X1470445D01*
X1470100Y392350D01*
G01X1519889Y363635D02*
X1520583Y364329D01*
X1520603D01*
X1521212Y364938D01*
Y366447D01*
X1520844Y366815D01*
Y366818D01*
X1520789Y366873D01*
Y368993D01*
X1520323Y369459D01*
Y370492D01*
X1521594Y371763D01*
Y373189D01*
G01X1480000Y402972D02*
X1478543D01*
X1477315Y401744D01*
X1476206D01*
X1475728Y402222D01*
X1473127D01*
X1471334Y404015D01*
X1469693D01*
X1468048Y402370D01*
G01X1518942Y361258D02*
Y364258D01*
X1518207Y364993D01*
Y365017D01*
X1518057Y365167D01*
Y366464D01*
X1518408Y366815D01*
Y366818D01*
X1518463Y366873D01*
Y368993D01*
X1518929Y369459D01*
Y370492D01*
X1517658Y371763D01*
Y373188D01*
X1517657Y373189D01*
G01X1524114Y363985D02*
X1523563Y364536D01*
Y368287D01*
G01X1501909Y373189D02*
Y371790D01*
X1500683Y370564D01*
Y369287D01*
X1501122Y368848D01*
Y367707D01*
X1500760Y367345D01*
Y362456D01*
X1498309Y360005D01*
G01X1511614Y351241D02*
Y360766D01*
X1511933Y361085D01*
Y366077D01*
X1512877Y367021D01*
Y368967D01*
X1512213Y369631D01*
Y371094D01*
X1511752Y371555D01*
G01X1497972Y369921D02*
X1497973Y369920D01*
Y367416D01*
X1496580Y366023D01*
Y353971D01*
X1498246Y352305D01*
G01X1496004Y371555D02*
X1495520Y371071D01*
Y369579D01*
X1494481Y368540D01*
G01X1478366Y401004D02*
X1475973Y400138D01*
X1475385Y399550D01*
X1469450D01*
X1469100Y399200D01*
Y398421D01*
X1469873Y397648D01*
G01X1475098Y401004D02*
Y400530D01*
X1474868Y400300D01*
X1474000D01*
X1473630Y400670D01*
X1472870D01*
X1472500Y400300D01*
X1471870D01*
X1471521Y400649D01*
X1470791D01*
X1470442Y400300D01*
X1469139D01*
X1468350Y399511D01*
Y398034D01*
X1467964Y397648D01*
X1466873D01*
G01X1505400Y357732D02*
Y359200D01*
X1508940Y362740D01*
Y368944D01*
X1507815Y370069D01*
Y371555D01*
G01X1494656Y365457D02*
Y366939D01*
X1496004Y368287D01*
G01X1504509Y361109D02*
X1505651Y362251D01*
Y363825D01*
X1505700Y363874D01*
Y363930D01*
X1506262Y364492D01*
Y366929D01*
X1505847Y367344D01*
Y369920D01*
X1505846Y369921D01*
G01X1490098D02*
Y367202D01*
G01X1503878Y371555D02*
X1503134Y370811D01*
Y369413D01*
X1502736Y369015D01*
Y367077D01*
X1502309Y366650D01*
Y360353D01*
X1500563Y358607D01*
Y357222D01*
X1498246Y354905D01*
G01X1510807Y353208D02*
Y361019D01*
X1511184Y361396D01*
Y366583D01*
X1511752Y367151D01*
Y368287D01*
G01X1507154Y353100D02*
X1509956Y355902D01*
Y361228D01*
X1510435Y361707D01*
Y364332D01*
X1509956Y364811D01*
Y369748D01*
X1509783Y369921D01*
G01X1525531D02*
Y365307D01*
X1525869Y364969D01*
Y360515D01*
X1526315Y360069D01*
Y358286D01*
X1524746Y356717D01*
G01X1523563Y371555D02*
X1523102Y371094D01*
Y369696D01*
X1522399Y368993D01*
Y367548D01*
X1522771Y367176D01*
Y364243D01*
X1522476Y363948D01*
Y361907D01*
G01X1499941Y371555D02*
X1499724Y371338D01*
Y369940D01*
X1498841Y369057D01*
Y368929D01*
X1498816Y368904D01*
Y367670D01*
X1498841Y367645D01*
Y366063D01*
X1498183Y365405D01*
G01X1490098Y373189D02*
Y371654D01*
X1488873Y370429D01*
Y369413D01*
X1489204Y369082D01*
Y366929D01*
X1489609Y366524D01*
G01X1501909Y369921D02*
Y367433D01*
X1501510Y367034D01*
Y360769D01*
X1498246Y357505D01*
G01X1514925Y358844D02*
Y359824D01*
X1517324Y362223D01*
Y363623D01*
X1517212Y363735D01*
Y363788D01*
X1516445Y364555D01*
Y367140D01*
X1516853Y367548D01*
Y368937D01*
X1516150Y369640D01*
Y371094D01*
X1515689Y371555D01*
G01X1520865Y361500D02*
Y363530D01*
X1521962Y364627D01*
Y366758D01*
X1521594Y367126D01*
Y369921D01*
G01X1525531Y373189D02*
Y371763D01*
X1524260Y370492D01*
Y369459D01*
X1524708Y369011D01*
Y364956D01*
X1525119Y364545D01*
Y359590D01*
X1524746Y359217D01*
G01X1515328Y363389D02*
Y367926D01*
X1515689Y368287D01*
G01X1518000Y364060D02*
Y364100D01*
X1517290Y364810D01*
Y366758D01*
X1517658Y367126D01*
Y369920D01*
X1517657Y369921D01*
G01X1480000Y422657D02*
X1477539Y421704D01*
X1477257Y421422D01*
X1476436D01*
X1475488Y421814D01*
X1473926D01*
X1473481Y422259D01*
X1471810D01*
X1470262Y420711D01*
G01X1476732Y422657D02*
X1476639Y422564D01*
X1475957D01*
X1475757Y422764D01*
X1475057D01*
X1474857Y422564D01*
X1474237D01*
X1473792Y423009D01*
X1473263D01*
X1473063Y423209D01*
X1472363D01*
X1472163Y423009D01*
X1471499D01*
X1470794Y422304D01*
X1468855D01*
X1467262Y420711D01*
G01X1476732Y406909D02*
X1475242D01*
X1472932Y409219D01*
X1470781D01*
X1470062Y408500D01*
X1468200D01*
X1467813Y408113D01*
Y407123D01*
X1467463Y406773D01*
X1466382D01*
G01X1480000Y406909D02*
X1478543D01*
X1477315Y405681D01*
X1476119D01*
X1475641Y406159D01*
X1474931D01*
X1472621Y408469D01*
X1471092D01*
X1470215Y407592D01*
X1470201D01*
X1469382Y406773D01*
G01X1476732Y434469D02*
X1474100D01*
X1473519Y435050D01*
X1469486D01*
X1467355Y432919D01*
G01X1480000Y434469D02*
X1478469D01*
X1477244Y433244D01*
X1476121D01*
X1475646Y433719D01*
X1473953D01*
X1473952Y433720D01*
X1473760D01*
X1473180Y434300D01*
X1471389D01*
X1469931Y432842D01*
G01X1478366Y452185D02*
X1476433Y451416D01*
X1476103Y451353D01*
X1475584Y450834D01*
X1472837D01*
X1472000Y449997D01*
G01X1475098Y452185D02*
X1474497Y451584D01*
X1473399D01*
X1473035Y451948D01*
X1472335D01*
X1471971Y451584D01*
X1471315D01*
X1469728Y449997D01*
X1469400D01*
G01X1480000Y426594D02*
X1477795Y427461D01*
X1477232Y427825D01*
X1476428D01*
X1475300Y427357D01*
X1475268Y427344D01*
X1474606D01*
X1473662Y426400D01*
X1471513D01*
X1469900Y428013D01*
G01X1476732Y426594D02*
X1474917D01*
X1473973Y425650D01*
X1473384D01*
X1472986Y425252D01*
X1472286D01*
X1471888Y425650D01*
X1471202D01*
X1470444Y426408D01*
X1468291D01*
X1467290Y427409D01*
Y428013D01*
G01X1475098Y408878D02*
Y409485D01*
X1474133Y410450D01*
X1471808D01*
X1470106Y412152D01*
G01X1478366Y408878D02*
X1476289Y409477D01*
X1473866Y411900D01*
X1472843D01*
X1472688Y412055D01*
G01X1523563Y493445D02*
Y493583D01*
X1524860Y496717D01*
Y499660D01*
X1526500Y501300D01*
G01X1523563Y496713D02*
X1524110Y497260D01*
Y499971D01*
X1524890Y500751D01*
Y502900D01*
X1525790Y503800D01*
X1526500D01*
G01X1564771Y522361D02*
X1564684D01*
X1564584Y522461D01*
X1548991D01*
G03X1548406Y522218I0J-826D01*
G01X1540689Y514501D01*
G02X1539602Y514051I-1087J1088D01*
G01X1531518D01*
G03X1531016Y513842I1J-710D01*
G01X1530773Y513599D01*
X1530772D01*
X1523343Y506169D01*
G03X1523000Y505341I828J-828D01*
G01Y498000D01*
X1522403Y497403D01*
Y496347D01*
X1522831Y495313D01*
Y494652D01*
X1522370Y493889D01*
X1521594Y491811D01*
G01Y495079D02*
X1521653Y495138D01*
Y497714D01*
X1522250Y498311D01*
Y505341D01*
G02X1522812Y506700I1921J1D01*
G01X1523554Y507443D01*
G03X1523678Y507814I-425J348D01*
G02X1523802Y508185I550J23D01*
G01X1524544Y508928D01*
G02X1524915Y509051I347J-427D01*
G03X1525287Y509175I23J550D01*
G01X1526029Y509918D01*
G03X1526153Y510289I-425J348D01*
G02X1526277Y510660I550J23D01*
G01X1527019Y511403D01*
G02X1527390Y511526I347J-427D01*
G03X1527762Y511650I23J550D01*
G01X1528504Y512393D01*
G03X1528628Y512764I-425J348D01*
G02X1528752Y513135I549J23D01*
G01X1529494Y513878D01*
G02X1529865Y514001I347J-426D01*
G03X1530236Y514125I22J550D01*
G01X1530242Y514130D01*
X1530485Y514373D01*
G02X1531518Y514801I1033J-1033D01*
G01X1532568D01*
G03X1532918Y514976I-55J547D01*
G02X1533268Y515151I405J-372D01*
G01X1534318D01*
G02X1534668Y514976I-55J-547D01*
G03X1535018Y514801I405J372D01*
G01X1536068D01*
G03X1536418Y514976I-55J547D01*
G02X1536768Y515151I405J-372D01*
G01X1537818D01*
G02X1538168Y514976I-55J-547D01*
G03X1538518Y514801I405J372D01*
G01X1539602D01*
G03X1540158Y515032I-1J787D01*
G01X1540672Y515546D01*
G03X1540796Y515918I-425J348D01*
G02X1540920Y516289I550J23D01*
G01X1541662Y517031D01*
G02X1542034Y517155I348J-425D01*
G03X1542405Y517279I23J550D01*
G01X1543147Y518021D01*
G03X1543271Y518393I-425J348D01*
G02X1543395Y518764I550J23D01*
G01X1544137Y519506D01*
G02X1544509Y519630I348J-425D01*
G03X1544880Y519754I23J550D01*
G01X1545623Y520496D01*
G03X1545746Y520868I-427J347D01*
G02X1545870Y521239I550J22D01*
G01X1546613Y521981D01*
G02X1546984Y522105I348J-426D01*
G03X1547355Y522228I24J549D01*
G01X1547875Y522748D01*
G02X1548990Y523211I1116J-1113D01*
G01X1550040D01*
G03X1550390Y523386I-55J547D01*
G02X1550740Y523561I405J-372D01*
G01X1551790D01*
G02X1552140Y523386I-55J-547D01*
G03X1552490Y523211I405J372D01*
G01X1553540D01*
G03X1553890Y523386I-55J547D01*
G02X1554240Y523561I405J-372D01*
G01X1555290D01*
G02X1555640Y523386I-55J-547D01*
G03X1555990Y523211I405J372D01*
G01X1557040D01*
G03X1557390Y523386I-55J547D01*
G02X1557740Y523561I405J-372D01*
G01X1558790D01*
G02X1559140Y523386I-55J-547D01*
G03X1559490Y523211I405J372D01*
G01X1560540D01*
G03X1560890Y523386I-55J547D01*
G02X1561240Y523561I405J-372D01*
G01X1562290D01*
G02X1562640Y523386I-55J-547D01*
G03X1562990Y523211I405J372D01*
G01X1564584D01*
X1564684Y523311D01*
X1564771D01*
G01X1505846Y491811D02*
X1505131Y493625D01*
X1505045Y493842D01*
X1504958Y494038D01*
X1504620Y494799D01*
Y495407D01*
X1505003Y496332D01*
X1505242Y497160D01*
Y498866D01*
X1507206Y500830D01*
G02X1508088Y501195I883J-885D01*
G01X1509033D01*
G03X1509501Y501663I0J468D01*
G01Y501956D01*
G03X1509355Y502309I-500J0D01*
G01X1508626Y503038D01*
G01X1503878Y493445D02*
X1503811Y493625D01*
X1503656Y494038D01*
X1503134Y495432D01*
X1502753Y496320D01*
Y500835D01*
G02X1503119Y501718I1248J0D01*
G01X1505448Y504047D01*
X1505447D01*
X1507304Y505904D01*
G03X1507635Y506701I-797J798D01*
G01Y509076D01*
X1506985Y510645D01*
G01X1501909Y491811D02*
X1501266Y493471D01*
X1501199Y493625D01*
X1501020Y494038D01*
X1500676Y494830D01*
Y495364D01*
X1500919Y495952D01*
G02X1500924Y495963I1005J-450D01*
G01X1501095Y496375D01*
Y501890D01*
G02X1501418Y502669I1101J0D01*
G01X1503277Y504528D01*
G03X1503380Y504776I-247J248D01*
G01Y510793D01*
G02X1503703Y511572I1101J0D01*
G01X1507387Y515256D01*
G03X1507490Y515504I-247J248D01*
G01Y516963D01*
G03X1507405Y518155I-8399J0D01*
G01X1499941Y493445D02*
X1499293Y495216D01*
X1498808Y496104D01*
Y497223D01*
X1498855Y497270D01*
Y506515D01*
X1498872Y506512D01*
X1498855Y506847D01*
X1498277Y508239D01*
G01X1497972Y491811D02*
X1497293Y493625D01*
X1497138Y494038D01*
X1497062Y494241D01*
X1496918Y494385D01*
X1496737Y494822D01*
Y495363D01*
X1497129Y496309D01*
Y497109D01*
X1496688Y498174D01*
Y502256D01*
G03X1496585Y502504I-350J0D01*
G01X1495404Y503685D01*
G02X1494767Y505225I1540J1539D01*
G01Y509542D01*
G02X1495255Y510720I1666J0D01*
G01X1497952Y513417D01*
G03X1498055Y513666I-249J249D01*
G01Y516122D01*
G01X1496004Y493445D02*
X1495940Y493625D01*
X1495793Y494038D01*
X1495161Y495807D01*
X1494879Y496089D01*
Y498061D01*
X1494500Y498440D01*
Y501213D01*
X1494499Y501212D01*
G03X1494325Y501633I-595J0D01*
G01X1492862Y503097D01*
G02X1492539Y503876I778J779D01*
G01Y507947D01*
G03X1492436Y508195I-350J0D01*
G01X1490599Y510032D01*
G02X1490276Y510811I778J779D01*
G01Y518276D01*
X1490100Y520000D01*
G01X1494035Y491811D02*
X1493393Y493625D01*
X1493247Y494038D01*
X1492805Y494480D01*
Y495391D01*
X1493194Y496331D01*
Y497390D01*
X1492708Y497876D01*
G02X1492385Y498655I778J779D01*
G01Y499950D01*
G03X1492282Y500198I-350J0D01*
G01X1489242Y503238D01*
G03X1488994Y503341I-248J-247D01*
G01X1486793D01*
G02X1485693Y504441I0J1100D01*
G01Y508000D01*
G01X1492067Y493445D02*
X1492011Y493625D01*
X1491883Y494038D01*
X1491585Y495001D01*
X1491092Y495819D01*
X1490150Y496761D01*
Y499693D01*
X1490149Y499692D01*
G03X1490047Y499939I-349J0D01*
G01X1489180Y500807D01*
G03X1488932Y500910I-248J-247D01*
G01X1480762D01*
G02X1479375Y502297I0J1387D01*
G01Y507975D01*
G01X1505846Y495079D02*
Y494256D01*
X1506118Y493984D01*
X1506621D01*
X1507142Y494505D01*
Y495643D01*
X1506567Y496218D01*
X1506333D01*
X1505992Y496559D01*
Y498555D01*
X1507736Y500299D01*
G02X1508089Y500445I353J-354D01*
G01X1509033D01*
G03X1510251Y501663I0J1218D01*
G01Y501956D01*
G02X1510397Y502309I500J0D01*
G01X1511126Y503038D01*
G01X1503878Y496713D02*
X1503503Y497088D01*
Y497541D01*
G02X1503678Y497891I547J-55D01*
G03X1503853Y498241I-372J405D01*
G01Y499291D01*
G03X1503678Y499641I-547J-55D01*
G02X1503503Y499991I372J405D01*
G01Y500835D01*
G02X1503650Y501187I498J-1D01*
G01X1504250Y501787D01*
G02X1504617Y501907I344J-429D01*
G03X1504988Y502031I23J550D01*
G01X1505730Y502773D01*
G03X1505854Y503145I-425J348D01*
G02X1505978Y503516I550J23D01*
G01X1507835Y505373D01*
G03X1508385Y506701I-1328J1328D01*
G01Y508249D01*
G02X1509191Y509055I806J0D01*
G01X1510108D01*
G03X1510567Y509245I0J649D01*
G01X1510836Y509514D01*
G03X1511041Y510009I-495J495D01*
G03X1510405Y510645I-636J0D01*
G01X1509585D01*
G01X1501909Y495079D02*
X1501694Y495294D01*
G02X1501618Y495676I248J248D01*
G01X1501845Y496226D01*
Y501890D01*
G02X1501948Y502138I350J0D01*
G01X1503807Y503997D01*
G03X1504130Y504776I-778J779D01*
G01Y507231D01*
G02X1504305Y507581I547J-55D01*
G03X1504480Y507931I-372J405D01*
G01Y508981D01*
G03X1504305Y509331I-547J-55D01*
G02X1504130Y509681I372J405D01*
G01Y510793D01*
G02X1504233Y511041I350J0D01*
G01X1504975Y511783D01*
G02X1505347Y511907I348J-425D01*
G03X1505718Y512031I23J550D01*
G01X1506460Y512773D01*
G03X1506584Y513145I-425J348D01*
G02X1506708Y513516I550J23D01*
G01X1507917Y514725D01*
G03X1508240Y515504I-778J779D01*
G01Y515700D01*
G02X1508590Y516242I595J0D01*
G01X1510169D01*
G03Y518085I0J922D01*
G01X1510075D01*
X1510005Y518155D01*
G01X1499941Y496713D02*
X1499605Y497049D01*
Y498099D01*
G02X1499780Y498449I547J-55D01*
G03X1499955Y498799I-372J405D01*
G01Y499849D01*
G03X1499780Y500199I-547J-55D01*
G02X1499605Y500549I372J405D01*
G01Y501599D01*
G02X1499780Y501949I547J-55D01*
G03X1499955Y502299I-372J405D01*
G01Y503349D01*
G03X1499780Y503699I-547J-55D01*
G02X1499605Y504049I372J405D01*
G01Y506315D01*
G02X1499955Y506665I350J0D01*
G01X1501393D01*
G03X1501943Y507215I0J550D01*
G01Y508089D01*
G03X1501593Y508439I-350J0D01*
G01X1501077D01*
X1500877Y508239D01*
G01X1497972Y495079D02*
X1498024Y495131D01*
Y495626D01*
X1497879Y495771D01*
Y497259D01*
X1497438Y498324D01*
Y499374D01*
G02X1497613Y499724I547J-55D01*
G03X1497788Y500074I-372J405D01*
G01Y501124D01*
G03X1497613Y501474I-547J-55D01*
G02X1497438Y501824I372J405D01*
G01Y502256D01*
G03X1497116Y503034I-1101J0D01*
G01X1495935Y504216D01*
G02X1495517Y505225I1009J1009D01*
G01Y506042D01*
G02X1495692Y506392I547J-55D01*
G03X1495867Y506742I-372J405D01*
G01Y507792D01*
G03X1495692Y508142I-547J-55D01*
G02X1495517Y508492I372J405D01*
G01Y509542D01*
G02X1495786Y510189I915J-1D01*
G01X1496528Y510932D01*
G02X1496900Y511055I347J-427D01*
G03X1497271Y511179I22J550D01*
G01X1498013Y511922D01*
G03X1498137Y512293I-426J348D01*
G02X1498260Y512664I549J24D01*
G01X1498483Y512887D01*
G03X1498805Y513666I-781J779D01*
G01Y513991D01*
G02X1499160Y514346I355J0D01*
G01X1500806D01*
G03X1501432Y514972I0J626D01*
G01Y515772D01*
G03X1501082Y516122I-350J0D01*
G01X1500655D01*
G01X1496004Y496713D02*
X1495629Y497088D01*
Y498372D01*
X1495250Y498751D01*
Y501212D01*
G03X1494856Y502164I-1346J0D01*
G01X1493392Y503628D01*
G02X1493289Y503876I247J248D01*
G01Y504674D01*
G02X1493464Y505024I547J-55D01*
G03X1493639Y505374I-372J405D01*
G01Y506424D01*
G03X1493464Y506774I-547J-55D01*
G02X1493289Y507124I372J405D01*
G01Y507947D01*
G03X1492966Y508726I-1101J0D01*
G01X1491129Y510563D01*
G02X1491026Y510811I247J248D01*
G01Y511861D01*
G02X1491201Y512211I547J-55D01*
G03X1491376Y512561I-372J405D01*
G01Y513611D01*
G03X1491201Y513961I-547J-55D01*
G02X1491026Y514311I372J405D01*
G01Y517687D01*
G02X1491542Y518203I516J0D01*
G01X1493011D01*
G03X1493736Y518928I0J725D01*
G01Y519373D01*
G03X1493109Y520000I-627J0D01*
G01X1492700D01*
G01X1494035Y495079D02*
X1493944Y495170D01*
Y497701D01*
X1493238Y498407D01*
G02X1493135Y498655I247J248D01*
G01Y499950D01*
G03X1492812Y500729I-1101J0D01*
G01X1492248Y501293D01*
G02X1492124Y501664I426J348D01*
G03X1492000Y502036I-549J24D01*
G01X1491258Y502778D01*
G03X1490887Y502902I-348J-426D01*
G02X1490515Y503026I-24J549D01*
G01X1489773Y503768D01*
G03X1488994Y504091I-779J-778D01*
G01X1486793D01*
G02X1486443Y504441I0J350D01*
G01Y505859D01*
G02X1486893Y506309I450J0D01*
G01X1488995D01*
G03X1489345Y506659I0J350D01*
G01Y507650D01*
G03X1488995Y508000I-350J0D01*
G01X1488293D01*
G01X1492067Y496713D02*
X1491259D01*
X1490900Y497072D01*
Y499692D01*
G03X1490578Y500470I-1100J0D01*
G01X1489711Y501337D01*
G03X1488932Y501660I-779J-777D01*
G01X1487762D01*
G02X1487412Y501835I55J547D01*
G03X1487062Y502010I-405J-372D01*
G01X1486012D01*
G03X1485662Y501835I55J-547D01*
G02X1485312Y501660I-405J372D01*
G01X1484262D01*
G02X1483912Y501835I55J547D01*
G03X1483562Y502010I-405J-372D01*
G01X1482512D01*
G03X1482162Y501835I55J-547D01*
G02X1481812Y501660I-405J372D01*
G01X1480762D01*
G02X1480125Y502297I0J637D01*
G01Y505603D01*
G02X1480600Y506078I475J0D01*
G01X1481975D01*
G03X1482654Y506757I0J679D01*
G01Y507296D01*
G03X1481975Y507975I-679J0D01*
G01X1560965Y373189D02*
Y371763D01*
X1559740Y370538D01*
Y369413D01*
X1560160Y368993D01*
Y366909D01*
X1560565Y366504D01*
Y357023D01*
G01X1560965Y369921D02*
Y367240D01*
X1561163Y367042D01*
Y367021D01*
G01X1557028Y369921D02*
Y367454D01*
X1556557Y366983D01*
Y357993D01*
X1557360Y357190D01*
G01X1545217Y369921D02*
X1545122Y369826D01*
Y369344D01*
X1545123Y369343D01*
Y367484D01*
X1545168Y367439D01*
Y367438D01*
X1545910Y366696D01*
Y363510D01*
X1543300Y360900D01*
G01X1587683Y397414D02*
X1586097Y399000D01*
X1583493D01*
X1583458Y399035D01*
X1578268D01*
G01X1551964Y361283D02*
X1552286Y361605D01*
Y368993D01*
X1551122Y370157D01*
Y371555D01*
G01X1541280Y373189D02*
Y371791D01*
X1540055Y370566D01*
Y369413D01*
X1540436Y369032D01*
Y366936D01*
X1538200Y364700D01*
G01X1529469Y373189D02*
Y371763D01*
X1528198Y370492D01*
Y369331D01*
X1528625Y368904D01*
Y367273D01*
X1528215Y366863D01*
Y361940D01*
X1529054Y361101D01*
Y354102D01*
X1529274Y353882D01*
G01X1575000Y395098D02*
X1576449D01*
X1577674Y396323D01*
X1578872D01*
X1579380Y395815D01*
X1580201D01*
X1581425Y394591D01*
X1582903D01*
G01X1582382Y392430D02*
X1580412Y394400D01*
X1578966D01*
X1578268Y395098D01*
G01X1556350Y356949D02*
X1555794Y357505D01*
Y367280D01*
X1555807Y367293D01*
Y367294D01*
X1556223Y367710D01*
Y368993D01*
X1555757Y369459D01*
Y370857D01*
X1555059Y371555D01*
G01X1547185D02*
X1546735Y371105D01*
Y369706D01*
X1545918Y368889D01*
Y367749D01*
X1547017Y366650D01*
Y362923D01*
X1546406Y362312D01*
G01X1586302Y403975D02*
X1584718Y402391D01*
X1581515D01*
X1580934Y402972D01*
X1578268D01*
G01X1555577Y355142D02*
X1554859Y355860D01*
Y368087D01*
X1555059Y368287D01*
G01X1554069Y355069D02*
Y359150D01*
X1554020Y359199D01*
Y367423D01*
X1553895Y367548D01*
Y368901D01*
X1554348Y369354D01*
Y370506D01*
X1553091Y371763D01*
Y373189D01*
G01X1545217D02*
Y371654D01*
X1543992Y370429D01*
Y369413D01*
X1544373Y369032D01*
Y364473D01*
X1543300Y363400D01*
G01X1551122Y368287D02*
Y367076D01*
X1550417Y366371D01*
Y362607D01*
G01X1575000Y399035D02*
X1576465D01*
X1577696Y397804D01*
X1578858D01*
X1579304Y398250D01*
X1583350D01*
X1584169Y397431D01*
X1585150D01*
Y397400D01*
G01X1558477Y357732D02*
X1557307Y358902D01*
Y366632D01*
X1557833Y367158D01*
Y368993D01*
X1558299Y369459D01*
Y370492D01*
X1557028Y371763D01*
Y373189D01*
G01X1587968Y403368D02*
Y403228D01*
X1586250Y401510D01*
X1581245D01*
X1580536Y402219D01*
X1579336D01*
X1578858Y401741D01*
X1577696D01*
X1576465Y402972D01*
X1575000D01*
G01X1589586Y402063D02*
X1589122Y401599D01*
X1587883D01*
X1587044Y400760D01*
X1580890D01*
X1580646Y401004D01*
X1579902D01*
G01X1529469Y369921D02*
Y363015D01*
X1529829Y362655D01*
G01X1549154Y373189D02*
Y371763D01*
X1547883Y370492D01*
Y369459D01*
X1548343Y368999D01*
Y368190D01*
X1548622Y367911D01*
Y360796D01*
X1549852Y359566D01*
Y355028D01*
X1549851Y355027D01*
Y353950D01*
X1548697Y352796D01*
Y345280D01*
X1548343Y344926D01*
G01X1527500Y368287D02*
Y367209D01*
X1527465Y367174D01*
Y361629D01*
X1528042Y361052D01*
Y356063D01*
G01X1531437Y368287D02*
Y365974D01*
X1532150Y365261D01*
Y361258D01*
X1531852Y360960D01*
G01X1531437Y371555D02*
Y370129D01*
X1530301Y368993D01*
Y366049D01*
X1531398Y364952D01*
Y361849D01*
X1531177Y361628D01*
G01X1564735Y360626D02*
X1563141Y362220D01*
Y368079D01*
X1562933Y368287D01*
G01X1568839Y373189D02*
Y361657D01*
X1569395Y361101D01*
G01X1564902Y369921D02*
Y367194D01*
X1564667Y366959D01*
Y363954D01*
X1564925Y363696D01*
G01X1583984Y384616D02*
X1581216D01*
X1580732Y384132D01*
X1580520D01*
X1580519Y384131D01*
X1579285D01*
X1578904Y384512D01*
X1577623D01*
X1576398Y383287D01*
X1575000D01*
G01X1585101Y382099D02*
X1583399Y383801D01*
X1581462D01*
X1581144Y383483D01*
X1581142D01*
X1580848Y383189D01*
X1578366D01*
X1578268Y383287D01*
G01Y387224D02*
X1580876D01*
X1580893Y387207D01*
X1580895D01*
X1581412Y386690D01*
X1584409D01*
G01X1564902Y373189D02*
Y371763D01*
X1563631Y370492D01*
Y369459D01*
X1564089Y369001D01*
Y367442D01*
X1563917Y367270D01*
Y362686D01*
X1564003Y362600D01*
G01X1566870Y371555D02*
X1566409Y371094D01*
Y369628D01*
X1565796Y369015D01*
Y367028D01*
X1565547Y366779D01*
Y364791D01*
X1567121Y363217D01*
G01X1583400Y372300D02*
X1582200D01*
X1581273Y373227D01*
X1578095D01*
X1577028Y374294D01*
G01X1575000Y379350D02*
Y377536D01*
X1576479Y376057D01*
X1578992D01*
X1579141Y376206D01*
X1583276D01*
G01X1574200Y361365D02*
X1571952Y363613D01*
Y367478D01*
X1572020Y367546D01*
Y370099D01*
X1572327Y370406D01*
Y374030D01*
G01X1576634Y385256D02*
X1575236D01*
X1573775Y383795D01*
Y382643D01*
X1574591Y381827D01*
Y380811D01*
X1573775Y379995D01*
Y379524D01*
X1572141Y377890D01*
Y375968D01*
X1575220Y372889D01*
Y369621D01*
X1574992Y369393D01*
Y367204D01*
X1575220Y366976D01*
Y364670D01*
X1574700Y364150D01*
Y362350D01*
X1575790Y361260D01*
G01X1584876Y378252D02*
X1583691Y379437D01*
X1579083D01*
X1577028Y377382D01*
G01X1584712Y380905D02*
X1582884Y382733D01*
X1581453D01*
X1581113Y382393D01*
X1579192D01*
X1578118Y381319D01*
X1576634D01*
G01X1562266Y363959D02*
Y367115D01*
X1561808Y367573D01*
Y368964D01*
X1562472Y369628D01*
Y371094D01*
X1562933Y371555D01*
G01X1573366Y377382D02*
Y376082D01*
X1576516Y372932D01*
X1577273D01*
X1578177Y372028D01*
Y370368D01*
X1580049Y368496D01*
G01X1547872Y353547D02*
Y367600D01*
X1547185Y368287D01*
G01X1576634Y401004D02*
X1577133Y400505D01*
X1578627D01*
X1579295Y399837D01*
X1587893D01*
X1588382Y400326D01*
X1590116D01*
X1592808Y403018D01*
G01X1576634Y456122D02*
X1577064Y455692D01*
X1578552D01*
X1579309Y454935D01*
X1581246D01*
X1581550Y454631D01*
X1582850D01*
X1583154Y454935D01*
X1583804D01*
G01X1576634Y424626D02*
X1576952Y424944D01*
X1578446D01*
X1579193Y425691D01*
X1579225D01*
X1579285Y425751D01*
X1580563D01*
X1581289Y425025D01*
X1582589D01*
X1583898Y426334D01*
X1585570D01*
X1587416Y428180D01*
X1589292D01*
G01X1575000Y422657D02*
X1576465D01*
X1577713Y423905D01*
X1578825D01*
X1579089Y423641D01*
X1579145D01*
X1579285Y423501D01*
X1580519D01*
X1580543Y423525D01*
X1583211D01*
X1584428Y424742D01*
X1586242D01*
X1587174Y425674D01*
X1589396D01*
G01X1588099Y429914D02*
X1585847D01*
X1585255Y430506D01*
X1582000D01*
X1581275Y429781D01*
X1580059D01*
X1580058Y429780D01*
X1579345D01*
X1578446Y428881D01*
X1576952D01*
X1576634Y428563D01*
G01X1587942Y436568D02*
X1586568D01*
X1584469Y434469D01*
X1578268D01*
G01X1576634Y408878D02*
X1577113Y408399D01*
X1578607D01*
X1579253Y407753D01*
X1580519D01*
X1580880Y408114D01*
X1585399D01*
X1586880Y409595D01*
X1589298D01*
X1590817Y411114D01*
G01X1575000Y434469D02*
X1575001Y434468D01*
X1576465D01*
X1577713Y435716D01*
X1578825D01*
X1579289Y435252D01*
X1582888D01*
X1583773Y436137D01*
G01X1578268Y414783D02*
X1581489D01*
X1581888Y414384D01*
X1584841D01*
X1585394Y414937D01*
G01X1576634Y416752D02*
X1577417D01*
X1577422Y416757D01*
X1578107D01*
X1579227Y417877D01*
X1582114D01*
X1582558Y418321D01*
X1583858D01*
X1584831Y417348D01*
X1585480D01*
G01X1575000Y414783D02*
X1576508D01*
X1577733Y416008D01*
X1578776D01*
X1579244Y415540D01*
X1582201D01*
X1582558Y415183D01*
X1584214D01*
X1584706Y415675D01*
G01X1590698Y422198D02*
X1588255Y419755D01*
X1584910D01*
X1584686Y419979D01*
X1581043D01*
X1580628Y419564D01*
X1579229D01*
X1578848Y419945D01*
X1577690D01*
X1576465Y418720D01*
X1575000D01*
G01X1576634Y420689D02*
X1576952Y421007D01*
X1578446D01*
X1579345Y421906D01*
X1583907D01*
X1584910Y422909D01*
X1586217D01*
X1586931Y422195D01*
X1588834D01*
X1589184Y422545D01*
G01X1579902Y428563D02*
X1580370Y429031D01*
X1582721D01*
X1583216Y429526D01*
X1584995D01*
X1585485Y429036D01*
X1587324D01*
G01X1579902Y440374D02*
X1580132Y440604D01*
X1586517D01*
X1588071Y442158D01*
X1594108D01*
G01X1575000Y426594D02*
X1576465D01*
X1577713Y427842D01*
X1578825D01*
X1579229Y427438D01*
X1580519D01*
X1581244Y428163D01*
X1584017D01*
X1584233Y427947D01*
G01X1585674Y404720D02*
X1584326Y403372D01*
X1582329D01*
X1581927Y403774D01*
X1579295D01*
X1578652Y404417D01*
X1577158D01*
X1576634Y404941D01*
G01X1587238Y432593D02*
X1586651Y432006D01*
X1581150D01*
X1580519Y431375D01*
X1579285D01*
X1578833Y431827D01*
X1577761D01*
X1576465Y430531D01*
X1575000D01*
G01X1578268Y406909D02*
X1580760D01*
X1581214Y407363D01*
X1585721D01*
X1587090Y408732D01*
X1590232D01*
X1590940Y409440D01*
X1591430D01*
G01X1591344Y452134D02*
X1589090Y449880D01*
X1585904D01*
X1585059Y449035D01*
X1580857D01*
X1580519Y449373D01*
X1579285D01*
X1578627Y448715D01*
Y448714D01*
X1578161Y448248D01*
X1576634D01*
G01X1579902Y408878D02*
X1585092D01*
X1586621Y410407D01*
X1587650D01*
X1587664Y410421D01*
X1587771D01*
X1589385Y412035D01*
X1589500D01*
G01X1576634Y452185D02*
X1577086Y452637D01*
X1578613D01*
X1579826Y453850D01*
X1585183D01*
X1585333Y454000D01*
X1588066D01*
G01X1575000Y410846D02*
X1576465D01*
X1577696Y409615D01*
X1578858D01*
X1579162Y409919D01*
X1579201D01*
X1579285Y410003D01*
X1580519D01*
X1580832Y409690D01*
X1584753D01*
X1587039Y411976D01*
X1587000D01*
G01X1578268Y442343D02*
X1584616D01*
X1587573Y445300D01*
G01X1575000Y450217D02*
X1576535D01*
X1577760Y451442D01*
X1578903D01*
X1579285Y451060D01*
X1581906D01*
X1582390Y450576D01*
X1584128D01*
X1585920Y452368D01*
G01X1579902Y448248D02*
X1580359Y447791D01*
X1585141D01*
X1585598Y448248D01*
G01X1575000Y458091D02*
X1576535D01*
X1577760Y456866D01*
X1578776D01*
X1579679Y457769D01*
X1583232D01*
X1584451Y456550D01*
X1587550D01*
G01X1588632Y452151D02*
X1587257Y450776D01*
X1585646D01*
X1584696Y449826D01*
X1581127D01*
X1580830Y450123D01*
X1580829D01*
X1580800Y450152D01*
X1578333D01*
X1578268Y450217D01*
G01X1579902Y444311D02*
X1580317Y443896D01*
X1582445D01*
X1584330Y445781D01*
G01X1576634Y444311D02*
X1578128D01*
X1579292Y443147D01*
X1582897D01*
X1586784Y447034D01*
X1593034D01*
X1594580Y448580D01*
G01X1579902Y424626D02*
X1580253Y424275D01*
X1582900D01*
X1584169Y425544D01*
X1585898D01*
X1587597Y427243D01*
X1590208D01*
G01X1576634Y432500D02*
X1576952Y432818D01*
X1578446D01*
X1579345Y433717D01*
X1584917D01*
X1585800Y434600D01*
G01X1576634Y436437D02*
X1576952Y436755D01*
X1578446D01*
X1579991Y438300D01*
X1581005D01*
X1581540Y438835D01*
X1589378D01*
X1591015Y440472D01*
X1591446D01*
G01X1576634Y440374D02*
X1577093Y439915D01*
X1578587D01*
X1579253Y439249D01*
X1580574D01*
X1581111Y439786D01*
X1588110D01*
X1588870Y440546D01*
G01X1578268Y418720D02*
X1578361Y418627D01*
X1580751D01*
X1580938Y418814D01*
X1580939D01*
X1581354Y419229D01*
X1584189D01*
X1584530Y418888D01*
X1589198D01*
X1591841Y421531D01*
G01X1578268Y422657D02*
X1583532D01*
X1584710Y423835D01*
X1587559D01*
G01X1578268Y430531D02*
X1578341Y430604D01*
X1580915D01*
X1581567Y431256D01*
X1586412D01*
X1586660Y431008D01*
X1588530D01*
X1590037Y432515D01*
G01X1583945Y406524D02*
X1581682D01*
X1581314Y406156D01*
X1579336D01*
X1578864Y405684D01*
X1577690D01*
X1576465Y406909D01*
X1575000D01*
G01X1584628Y438012D02*
X1582761D01*
X1581186Y436437D01*
X1579902D01*
G01X1529469Y491811D02*
X1530200Y493750D01*
X1530700Y494783D01*
Y495365D01*
X1530250Y496454D01*
X1529699Y497419D01*
X1528958Y498162D01*
Y502931D01*
X1532376Y506349D01*
X1532776D01*
X1533595Y505530D01*
G01X1529469Y495079D02*
X1529588Y495120D01*
X1529805Y495566D01*
X1529574Y496123D01*
X1529097Y496960D01*
X1528208Y497851D01*
Y503242D01*
X1528443Y503477D01*
Y503973D01*
X1529186Y504716D01*
X1529681D01*
X1530423Y505458D01*
Y505953D01*
X1531166Y506696D01*
X1531662D01*
X1532065Y507099D01*
X1533317D01*
X1533595Y507377D01*
Y509030D01*
G01X1531437Y493445D02*
X1531508Y493625D01*
X1531671Y494038D01*
X1532600Y496397D01*
Y497301D01*
X1531375Y498526D01*
Y499230D01*
X1531685Y499540D01*
G01X1531437Y496713D02*
Y497371D01*
X1530100Y498708D01*
Y500455D01*
X1531685Y502040D01*
G01X1543248Y496713D02*
X1542950Y497011D01*
Y497551D01*
X1544100Y498701D01*
Y499959D01*
X1543779Y500280D01*
Y500990D01*
X1544100Y501311D01*
Y503670D01*
X1544390Y503960D01*
Y504848D01*
X1544000Y505238D01*
Y505938D01*
X1544390Y506328D01*
Y507525D01*
X1543996Y507919D01*
Y508619D01*
X1544390Y509013D01*
Y509861D01*
X1545179Y510650D01*
X1545650D01*
X1546020Y511020D01*
X1546710D01*
X1547080Y510650D01*
X1547660D01*
X1548300Y511290D01*
Y511800D01*
G01X1541280Y495079D02*
Y495881D01*
X1541350Y495951D01*
Y498249D01*
X1540900Y498699D01*
Y501549D01*
X1541251Y501900D01*
X1542475D01*
G01X1539311Y496713D02*
X1538647D01*
X1538350Y497010D01*
Y497631D01*
X1538669Y497950D01*
X1538904D01*
X1539310Y498356D01*
Y498973D01*
X1538961Y499322D01*
Y500372D01*
X1539311Y500722D01*
Y501772D01*
X1538961Y502122D01*
Y503172D01*
X1539311Y503522D01*
Y504572D01*
X1538961Y504922D01*
Y505972D01*
X1539311Y506322D01*
Y507372D01*
X1540489Y508550D01*
X1542125D01*
X1542475Y508900D01*
Y509600D01*
G01X1543248Y493445D02*
X1543314Y493625D01*
X1543465Y494038D01*
X1544104Y495781D01*
X1544373Y496050D01*
Y497913D01*
X1544850Y498390D01*
Y503359D01*
X1545140Y503649D01*
Y509550D01*
X1545490Y509900D01*
X1547600D01*
X1548300Y509200D01*
G01X1541280Y491811D02*
X1541821Y493625D01*
X1541905Y493905D01*
X1542515Y494515D01*
Y495342D01*
X1542100Y496344D01*
Y499025D01*
X1542475Y499400D01*
G01X1539311Y493445D02*
Y494911D01*
X1540500Y496100D01*
Y497408D01*
X1540061Y497847D01*
Y507061D01*
X1540800Y507800D01*
X1541675D01*
X1542475Y507000D01*
G01X1545217Y495079D02*
X1545288Y495150D01*
Y497687D01*
X1545940Y498339D01*
Y501851D01*
X1546394Y502305D01*
Y504144D01*
X1546800Y504550D01*
X1547750D01*
X1548300Y504000D01*
G01X1545217Y491811D02*
X1545911Y493625D01*
X1546043Y493969D01*
X1546077Y494038D01*
X1546453Y494809D01*
Y495468D01*
X1546038Y496313D01*
Y497376D01*
X1546690Y498028D01*
Y501540D01*
X1547060Y501910D01*
X1547890D01*
X1548300Y501500D01*
G01X1578268Y473839D02*
X1578342Y473765D01*
X1582082D01*
X1583652Y475335D01*
X1584877D01*
X1585227Y475685D01*
X1586277D01*
X1586627Y475335D01*
X1587677D01*
X1588027Y475685D01*
X1589077D01*
X1589427Y475335D01*
X1590965D01*
X1592100Y474200D01*
Y472800D01*
X1592530Y472370D01*
X1594280D01*
G01X1575000Y473839D02*
X1577362Y472938D01*
X1577686Y472614D01*
X1578776D01*
X1579177Y473015D01*
X1582393D01*
X1583963Y474585D01*
X1590654D01*
X1591350Y473889D01*
Y473140D01*
X1590580Y472370D01*
G01X1553091Y495079D02*
X1553120Y495108D01*
Y497611D01*
X1554000Y498491D01*
Y499011D01*
X1553750Y499261D01*
Y500479D01*
X1554321Y501050D01*
X1555250D01*
X1555510Y501310D01*
Y501975D01*
G01X1553091Y491811D02*
X1553923Y494038D01*
X1554001Y494248D01*
X1554325Y494572D01*
Y495672D01*
X1553870Y496127D01*
Y497300D01*
X1554750Y498180D01*
Y498661D01*
X1555100Y499011D01*
X1555278D01*
X1555510Y499243D01*
Y499475D01*
G01X1555438Y507217D02*
X1554005Y508650D01*
X1551310D01*
X1551122Y508462D01*
Y507645D01*
X1551500Y507267D01*
Y506567D01*
X1551122Y506189D01*
Y505489D01*
X1551500Y505111D01*
Y504411D01*
X1551122Y504033D01*
Y503333D01*
X1551500Y502955D01*
Y502255D01*
X1551122Y501877D01*
Y501177D01*
X1551500Y500799D01*
Y500099D01*
X1551122Y499721D01*
Y498700D01*
X1551622Y498200D01*
X1551967D01*
X1552317Y497850D01*
Y496310D01*
X1551967Y495960D01*
X1551472D01*
X1551122Y496310D01*
Y496713D01*
G01Y493445D02*
X1551059Y493625D01*
X1550915Y494038D01*
X1550336Y495697D01*
X1549991Y496042D01*
Y497405D01*
X1550200Y498399D01*
Y508601D01*
X1550999Y509400D01*
X1553550D01*
X1555438Y509717D01*
G01X1600457Y476708D02*
X1599132D01*
X1598782Y476358D01*
Y474920D01*
X1598432Y474570D01*
X1597938D01*
X1597068Y475440D01*
Y475935D01*
X1596325Y476678D01*
X1595830D01*
X1595088Y477420D01*
X1593993D01*
X1593643Y477770D01*
X1592593D01*
X1592243Y477420D01*
X1591193D01*
X1590843Y477770D01*
X1589793D01*
X1589443Y477420D01*
X1588393D01*
X1588043Y477770D01*
X1586993D01*
X1586643Y477420D01*
X1585593D01*
X1585243Y477770D01*
X1584193D01*
X1583843Y477420D01*
X1582793D01*
X1580805Y475432D01*
X1580277D01*
X1579902Y475807D01*
G01X1600457Y473508D02*
X1600145Y473820D01*
X1597627D01*
X1594777Y476670D01*
X1583104D01*
X1581116Y474682D01*
X1579258D01*
X1578900Y475040D01*
X1576634Y475807D01*
G01X1578268Y469902D02*
X1586506D01*
X1586856Y469552D01*
X1587906D01*
X1588256Y469902D01*
X1589306D01*
X1589656Y469552D01*
X1590706D01*
X1591056Y469902D01*
X1592106D01*
X1592456Y469552D01*
X1593506D01*
X1593856Y469902D01*
X1594906D01*
X1595256Y469552D01*
X1596306D01*
X1596656Y469902D01*
X1597706D01*
X1598056Y469552D01*
X1599106D01*
X1599456Y469902D01*
X1600506D01*
X1600856Y469552D01*
X1601906D01*
X1602256Y469902D01*
X1603568D01*
X1604323Y469147D01*
G01X1607557Y468708D02*
X1605823D01*
X1603879Y470652D01*
X1579348D01*
X1578800Y471200D01*
X1577700D01*
X1576402Y469902D01*
X1575000D01*
G01X1605313Y483559D02*
X1603840D01*
X1603588Y483307D01*
Y482088D01*
X1603340Y481840D01*
X1601910D01*
X1601560Y482190D01*
X1600510D01*
X1600160Y481840D01*
X1599110D01*
X1598760Y482190D01*
X1597710D01*
X1597360Y481840D01*
X1596383D01*
X1595818Y481275D01*
X1595323D01*
X1594581Y480533D01*
Y480038D01*
X1594119Y479576D01*
X1592676D01*
X1592326Y479926D01*
X1591276D01*
X1590926Y479576D01*
X1589876D01*
X1589526Y479926D01*
X1588476D01*
X1588126Y479576D01*
X1587076D01*
X1586726Y479926D01*
X1585676D01*
X1585326Y479576D01*
X1584276D01*
X1583926Y479926D01*
X1582876D01*
X1582526Y479576D01*
X1581476D01*
X1579676Y477776D01*
X1579226D01*
X1578949Y477590D01*
X1578454D01*
X1578268Y477776D01*
G01X1605313Y480359D02*
X1604211D01*
X1603480Y481090D01*
X1596694D01*
X1594430Y478826D01*
X1581787D01*
X1579987Y477026D01*
X1579455D01*
X1578749Y476551D01*
X1577914D01*
X1577040Y477083D01*
X1575000Y477776D01*
G01X1560965Y495079D02*
X1561163Y495277D01*
Y495680D01*
X1560452Y496391D01*
Y497385D01*
X1560102Y497735D01*
Y498785D01*
X1560452Y499135D01*
Y500185D01*
X1560102Y500535D01*
Y501585D01*
X1560452Y501935D01*
Y502985D01*
X1561546Y504079D01*
X1563530D01*
X1564321Y504870D01*
X1564550D01*
X1564900Y505220D01*
Y506229D01*
X1565000Y506329D01*
G01X1560965Y491811D02*
X1561641Y493625D01*
X1561795Y494038D01*
X1561866Y494228D01*
X1562200Y494562D01*
Y495320D01*
X1561929Y495975D01*
X1561202Y496702D01*
Y502674D01*
X1561857Y503329D01*
X1565000D01*
G01X1630418Y189307D02*
X1630148Y189037D01*
Y188031D01*
X1630499Y187680D01*
X1631598D01*
X1631948Y187330D01*
Y186015D01*
X1631598Y185665D01*
Y184615D01*
X1631948Y184265D01*
Y183215D01*
X1631598Y182865D01*
Y181815D01*
X1631948Y181465D01*
Y180677D01*
X1632948Y179677D01*
X1634874D01*
X1635166Y179385D01*
Y178918D01*
X1634916Y178668D01*
Y177618D01*
X1635266Y177268D01*
Y176218D01*
X1634916Y175868D01*
Y174818D01*
X1635266Y174468D01*
Y173418D01*
X1634916Y173068D01*
Y172018D01*
X1635266Y171668D01*
Y170959D01*
X1634916Y170609D01*
X1634213D01*
G01X1633711Y189304D02*
X1632698Y188291D01*
Y181130D01*
X1633301Y180527D01*
X1634358D01*
G01D02*
X1635227D01*
X1636016Y179738D01*
Y170744D01*
X1634213Y167459D01*
G01X1637363Y170609D02*
X1638066D01*
X1638416Y170959D01*
Y171668D01*
X1638066Y172018D01*
Y173068D01*
X1638416Y173418D01*
Y174468D01*
X1638066Y174818D01*
Y175868D01*
X1638416Y176218D01*
Y177268D01*
X1638066Y177618D01*
Y178668D01*
X1638416Y179018D01*
Y180068D01*
X1638066Y180418D01*
Y181468D01*
X1638316Y181718D01*
Y182331D01*
X1637715Y182932D01*
Y184986D01*
X1637257Y185444D01*
X1635351D01*
G01X1637363Y167459D02*
X1639166Y170488D01*
Y182684D01*
X1638465Y183385D01*
Y184827D01*
X1639258Y185620D01*
G01X1604323Y469147D02*
X1605190Y468280D01*
Y466060D01*
X1605742Y465508D01*
X1607557D01*
G54D91*
X94973Y338279D03*
X98590Y367850D03*
X98540Y352760D03*
X98563Y345171D03*
X98520Y360280D03*
X96528Y384042D03*
X744020Y255170D03*
X750900Y260500D03*
X745400Y278300D03*
X751700Y273300D03*
X745200Y266900D03*
X1359512Y42334D03*
G54D157*
X700515Y98272D03*
X1768770Y136750D03*
Y132250D03*
Y127750D03*
Y123250D03*
Y150750D03*
Y146250D03*
Y141250D03*
X1727278Y604617D03*
X1743536Y603249D03*
X1803148Y155437D03*
X1777270Y141250D03*
Y136750D03*
Y132250D03*
Y127750D03*
Y123250D03*
Y150750D03*
Y146250D03*
G54D73*
X49150Y6112D03*
Y4537D03*
Y2962D03*
Y1387D03*
Y-188D03*
Y-1762D03*
Y-3337D03*
Y-4912D03*
Y-6487D03*
Y-8062D03*
G54D247*
X1586547Y5502D03*
X1592453D03*
G54D139*
X649819Y303981D03*
Y305950D03*
Y307919D03*
Y309888D03*
Y311857D03*
Y313826D03*
Y315795D03*
Y317764D03*
Y319733D03*
Y321702D03*
Y323671D03*
Y325640D03*
Y327609D03*
Y329578D03*
Y331547D03*
Y333516D03*
G54D256*
X1595602Y3337D03*
Y1369D03*
Y-600D03*
Y-2569D03*
Y-4537D03*
G54D175*
X1265720Y287844D03*
X1269395Y310026D03*
G54D274*
X1670306Y231988D03*
X1676982Y227010D03*
X1902513Y197965D03*
G54D37*
X45012Y-10625D03*
X43437D03*
X41862D03*
X40287D03*
X38713D03*
X37138D03*
X35563D03*
X33988D03*
X32413D03*
X46587D03*
G54D64*
X34126Y519000D03*
X47874D03*
X1393388Y86754D03*
X1395515Y405921D03*
X1381767D03*
X1407136Y86754D03*
G54D283*
X1766145Y460603D03*
X1769295Y441754D03*
Y460603D03*
X1772445Y441754D03*
Y460603D03*
X1734649Y441754D03*
Y460603D03*
X1737799Y441754D03*
Y460603D03*
X1740948Y441754D03*
Y460603D03*
X1744098Y441754D03*
Y460603D03*
X1747248Y441754D03*
Y460603D03*
X1750397Y441754D03*
Y460603D03*
X1753547Y441754D03*
Y460603D03*
X1756696Y441754D03*
Y460603D03*
X1759846Y441754D03*
Y460603D03*
X1762996Y441754D03*
Y460603D03*
X1766145Y441754D03*
X1775594D03*
Y460603D03*
X1778744Y441754D03*
Y460603D03*
X1781893Y441754D03*
Y460603D03*
X1785043Y441754D03*
Y460603D03*
X1788193Y441754D03*
Y460603D03*
X1791342Y441754D03*
Y460603D03*
X1794492Y441754D03*
Y460603D03*
X1797641Y441754D03*
Y460603D03*
X1800791Y441754D03*
Y460603D03*
X1803941Y441754D03*
Y460603D03*
X1807090Y441754D03*
Y460603D03*
X1810240Y441754D03*
Y460603D03*
X1813389Y441754D03*
Y460603D03*
X1816539Y441754D03*
Y460603D03*
X1819689Y441754D03*
Y460603D03*
X1822838Y441754D03*
Y460603D03*
X1825988Y441754D03*
Y460603D03*
X1829137Y441754D03*
Y460603D03*
X1832287Y441754D03*
Y460603D03*
X1835437Y441754D03*
Y460603D03*
X1838586Y441754D03*
Y460603D03*
X1841736Y441754D03*
Y460603D03*
X1844885Y441754D03*
Y460603D03*
X1848035Y441754D03*
Y460603D03*
X1851185Y441754D03*
Y460603D03*
X1854334Y441754D03*
Y460603D03*
X1857484Y441754D03*
Y460603D03*
X1860633Y441754D03*
Y460603D03*
X1863783Y441754D03*
Y460603D03*
X1866933Y441754D03*
Y460603D03*
X1870082Y441754D03*
Y460603D03*
X1873232Y441754D03*
Y460603D03*
X1876382Y441754D03*
Y460603D03*
X1879531Y441754D03*
Y460603D03*
X1882681Y441754D03*
Y460603D03*
X1885830Y441754D03*
Y460603D03*
X1888980Y441754D03*
Y460603D03*
X1892130Y441754D03*
Y460603D03*
X1895279Y441754D03*
Y460603D03*
X1907878D03*
X1911027Y441754D03*
Y460603D03*
X1914177Y441754D03*
Y460603D03*
X1917326Y441754D03*
Y460603D03*
X1920476Y441754D03*
X1898429D03*
Y460603D03*
X1901578Y441754D03*
Y460603D03*
X1904728Y441754D03*
Y460603D03*
X1907878Y441754D03*
X1920476Y460603D03*
G54D82*
X83000Y257700D03*
Y252700D03*
Y247700D03*
Y262700D03*
X83553Y234800D03*
Y229800D03*
Y224800D03*
Y239800D03*
G54D265*
X1599227Y388133D03*
X1607495Y394433D03*
X1599227D03*
X1607495Y388133D03*
G54D148*
X665396Y12500D03*
Y14469D03*
Y16437D03*
Y18406D03*
Y20374D03*
X676700D03*
Y18406D03*
Y16437D03*
Y14469D03*
Y12500D03*
X665795Y576493D03*
Y578462D03*
Y580430D03*
Y582399D03*
Y584367D03*
X677099D03*
Y582399D03*
Y580430D03*
Y578462D03*
Y576493D03*
X1782548Y89000D03*
Y90968D03*
Y92937D03*
X1793852Y90968D03*
Y89000D03*
Y87031D03*
Y92937D03*
X1782548Y85063D03*
X1793852D03*
X1782548Y87031D03*
X1812848Y155563D03*
X1824152D03*
X1812848Y159500D03*
Y161468D03*
Y163437D03*
X1824152Y161468D03*
Y159500D03*
Y157531D03*
Y163437D03*
X1812848Y157531D03*
G54D328*
X1955531Y155984D03*
Y152047D03*
Y148110D03*
Y144173D03*
Y175669D03*
Y171732D03*
Y167795D03*
Y163858D03*
Y159921D03*
Y191417D03*
Y187480D03*
Y183543D03*
Y179606D03*
G54D337*
X1933900Y487210D03*
Y482090D03*
Y484650D03*
Y479530D03*
X1923900Y487210D03*
Y484650D03*
Y482090D03*
Y479530D03*
G54D19*
X-14722Y452578D03*
X-5722D03*
X97600Y167800D03*
X88600D03*
X83820Y478080D03*
X74820D03*
X85865Y470975D03*
X76865D03*
X1683500Y82500D03*
X1692500D03*
X1883000Y554600D03*
X1890400D03*
X1883000Y557160D03*
X1890400D03*
X1883000Y552040D03*
X1890400D03*
G54D46*
X19421Y27947D03*
X17649D03*
X15878D03*
X14106D03*
X12334D03*
X10563D03*
X19746Y59314D03*
X17974D03*
X16203D03*
X14431D03*
X12659D03*
X10888D03*
X9321Y534603D03*
X7549D03*
X5778D03*
X4006D03*
X2234D03*
X463D03*
X9321Y570603D03*
X7549D03*
X5778D03*
X4006D03*
X2234D03*
X463D03*
X133445Y215136D03*
X131673D03*
X129902D03*
X128130D03*
X126358D03*
X124587D03*
X133445Y279136D03*
X131673D03*
X129902D03*
X128130D03*
X126358D03*
X124587D03*
X133445Y247136D03*
X131673D03*
X129902D03*
X128130D03*
X126358D03*
X124587D03*
X133445Y311136D03*
X131673D03*
X129902D03*
X128130D03*
X126358D03*
X124587D03*
X133445Y343136D03*
X131673D03*
X129902D03*
X128130D03*
X126358D03*
X124587D03*
X133445Y375136D03*
X131673D03*
X129902D03*
X128130D03*
X126358D03*
X124587D03*
X698679Y223397D03*
X700451D03*
X702222D03*
X703994D03*
X705766D03*
X707537D03*
X783053Y215136D03*
X781281D03*
X779510D03*
X777738D03*
X775966D03*
X774195D03*
X783053Y247136D03*
X781281D03*
X779510D03*
X777738D03*
X775966D03*
X774195D03*
X783053Y279136D03*
X781281D03*
X779510D03*
X777738D03*
X775966D03*
X774195D03*
X783053Y311136D03*
X781281D03*
X779510D03*
X777738D03*
X775966D03*
X774195D03*
X783053Y343136D03*
X781281D03*
X779510D03*
X777738D03*
X775966D03*
X774195D03*
X783003Y375136D03*
X781231D03*
X779460D03*
X777688D03*
X775916D03*
X774145D03*
X1363768Y2573D03*
X1365540D03*
X1367311D03*
X1369083D03*
X1370855D03*
X1372626D03*
X1364079Y34597D03*
X1365851D03*
X1367622D03*
X1369394D03*
X1371166D03*
X1372937D03*
X1366386Y393465D03*
X1368158D03*
X1369929D03*
X1371701D03*
X1373473D03*
X1375244D03*
X1368079Y581453D03*
X1369851D03*
X1371622D03*
X1373394D03*
X1375166D03*
X1376937D03*
X1368079Y612653D03*
X1369851D03*
X1371622D03*
X1373394D03*
X1375166D03*
X1376937D03*
G54D229*
X1507076Y93586D03*
Y91618D03*
Y89649D03*
Y87681D03*
Y85712D03*
Y83744D03*
Y154610D03*
Y152641D03*
Y150673D03*
Y148704D03*
Y138862D03*
Y136893D03*
Y134925D03*
Y132956D03*
Y130988D03*
Y129019D03*
Y127051D03*
Y125082D03*
Y123114D03*
Y121145D03*
Y119177D03*
Y117208D03*
Y115240D03*
Y113271D03*
Y111303D03*
Y109334D03*
Y107366D03*
Y105397D03*
Y103429D03*
Y101460D03*
Y99492D03*
Y97523D03*
Y95555D03*
Y156578D03*
X1536801Y94570D03*
Y92602D03*
Y90633D03*
Y88665D03*
Y86696D03*
Y84728D03*
Y155594D03*
Y153626D03*
Y151657D03*
Y149689D03*
Y139846D03*
Y137878D03*
Y135909D03*
Y133941D03*
Y131972D03*
Y130004D03*
Y128035D03*
Y126067D03*
Y124098D03*
Y122130D03*
Y120161D03*
Y118192D03*
Y116224D03*
Y114255D03*
Y112287D03*
Y110318D03*
Y108350D03*
Y106381D03*
Y104413D03*
Y102444D03*
Y100476D03*
Y98507D03*
Y96539D03*
G54D346*
X1970071Y540467D03*
X1963071D03*
X1970071Y545979D03*
X1963071D03*
G54D184*
X1262771Y355220D03*
G54D166*
X721319Y492850D03*
X1394664Y540952D03*
X1541300Y313400D03*
X1634350Y201350D03*
X1736689Y169831D03*
X1732189D03*
X1727689D03*
X1723189D03*
Y162331D03*
X1727689D03*
X1732189D03*
X1736689D03*
X1718689D03*
Y169781D03*
X1714189Y162331D03*
X1855663Y142248D03*
G54D319*
X1851250Y561000D03*
G54D55*
X3937Y204370D03*
X-3937D03*
X-11811D03*
X35433D03*
X27559D03*
X19685D03*
X3937Y227992D03*
X-3937D03*
X-11811D03*
X35433D03*
X27559D03*
X19685D03*
X3937Y313504D03*
X-3937D03*
X-11811D03*
X3937Y337126D03*
X-3937D03*
X-11811D03*
X35433D03*
X27559D03*
X19685D03*
X35433Y313504D03*
X27559D03*
X19685D03*
G54D28*
X16117Y-43892D03*
X38500Y613000D03*
X8543Y636173D03*
X136670Y159840D03*
X166595Y431153D03*
X572500Y105000D03*
X719000Y331200D03*
X796000Y103000D03*
X827000Y181000D03*
X828000Y417500D03*
X1440000Y513000D03*
X1567200Y88000D03*
X1573000Y576900D03*
X1684907Y203562D03*
X1712205Y536791D03*
X1707205D03*
X1702205D03*
X1697205D03*
X1692205D03*
X1687205D03*
X1712205D03*
X1707205D03*
X1702205D03*
X1697205D03*
X1692205D03*
X1687205D03*
X1717205D03*
D03*
X1926693Y646063D03*
G54D193*
X1239722Y474778D03*
X1232141Y467872D03*
G54D292*
X1736245Y594742D03*
Y598679D03*
Y596711D03*
Y592773D03*
Y590805D03*
X1923700Y176053D03*
Y178021D03*
Y187864D03*
Y183927D03*
Y181958D03*
Y179990D03*
Y185895D03*
Y170147D03*
Y172116D03*
Y174084D03*
Y166210D03*
Y168179D03*
Y162273D03*
Y160305D03*
Y158336D03*
Y164242D03*
G54D238*
X1481729Y592414D03*
X1517267Y593682D03*
G54D365*
G01X1563575Y414694D02*
X1565192Y415445D01*
X1565525Y415600D01*
G01X1569425D02*
X1567475Y414694D01*
G01X1557725Y422360D02*
X1559675Y421454D01*
G01X1553825Y422360D02*
X1555775Y421454D01*
G01Y418980D02*
X1553825Y418074D01*
G01X1559675Y418980D02*
X1557725Y418074D01*
G01X1565525Y408840D02*
X1567475Y407934D01*
G01X1569425Y408840D02*
X1571375Y407934D01*
G01X1598878Y376346D02*
X1600033Y377501D01*
X1601051D01*
X1601829Y376723D01*
G01X1598878Y380344D02*
X1600074Y379148D01*
X1601054D01*
X1601829Y379923D01*
G01X1608146Y376171D02*
X1606968Y377349D01*
X1605955D01*
X1605329Y376723D01*
G01X1608146Y380322D02*
X1606973Y379149D01*
X1606103D01*
X1605329Y379923D01*
G01X1677649Y90301D02*
Y94751D01*
X1671854Y100546D01*
G01X1702500Y87083D02*
X1699341Y90242D01*
X1695993D01*
X1694465Y91770D01*
X1688695D01*
X1685578Y94887D01*
G01X1695236Y138938D02*
G02X1693377Y138181I-1859J1904D01*
G01X1689991D01*
G03X1687908Y133152I0J-2946D01*
G01X1691657Y129403D01*
G03X1695895I2119J2119D01*
G01X1698501Y132009D01*
G02X1700195Y130315I847J-847D01*
G01X1697269Y127389D01*
G02X1690285I-3492J3492D01*
G01X1680073Y137602D01*
G03X1678050Y138438I-2021J-2025D01*
G01X1670489D01*
G02X1668859Y139113I0J2305D01*
G01Y135963D02*
G02X1670957Y136638I2098J-2923D01*
G01X1678050D01*
G02X1678800Y136328I1J-1060D01*
G01Y136329D01*
X1679250Y135879D01*
X1689012Y126116D01*
G03X1698542I4765J4765D01*
G01X1701468Y129042D01*
G03X1697228Y133282I-2120J2120D01*
G01X1694622Y130676D01*
G02X1692930I-846J846D01*
G01X1689181Y134425D01*
G02X1689991Y136381I810J810D01*
G01X1693377D01*
G02X1695236Y135788I0J-3210D01*
G01X1668859Y132814D02*
G03X1669282Y132639I423J423D01*
G01X1677026D01*
G03X1677386Y132788I0J509D01*
G01Y129638D02*
X1677493Y129718D01*
G03X1677121Y130839I-372J499D01*
G01X1669717D01*
G03X1668859Y129664I0J-901D01*
G01X1676886Y120038D02*
X1676884Y120040D01*
G03X1674828Y120890I-2056J-2062D01*
G01X1671052D01*
G03X1668859Y120215I0J-3900D01*
G01Y123365D02*
X1669264Y122960D01*
G03X1669915Y122690I651J650D01*
G01X1675690D01*
G03X1676884Y123186I0J1685D01*
G01X1676886Y123188D01*
G01X1721740Y128474D02*
X1723314Y130050D01*
G01X1724890Y128474D02*
X1723314Y126900D01*
G01X1797441Y248146D02*
Y244105D01*
G01X1816339Y248194D02*
Y244105D01*
G01X1813190Y248213D02*
X1813189Y248212D01*
Y244105D01*
G01X1896594Y-15042D02*
X1897472Y-15920D01*
X1899096D01*
X1900256Y-14760D01*
G01Y-18911D02*
X1899065Y-17720D01*
X1897196D01*
X1896581Y-18335D01*
G01X1889594Y-15042D02*
X1890378Y-14258D01*
Y-11721D01*
X1889878Y-11221D01*
X1887169D01*
X1886668Y-10720D01*
Y-7308D01*
X1887958Y-6018D01*
Y-4638D01*
X1886668Y-3348D01*
Y-1948D01*
X1887958Y-658D01*
Y722D01*
X1886668Y2012D01*
Y3412D01*
X1887958Y4702D01*
Y6082D01*
X1886668Y7372D01*
Y8987D01*
X1888035Y10354D01*
X1889858D01*
X1890834Y11330D01*
Y13153D01*
X1893594Y15913D01*
X1897345D01*
X1897875Y15383D01*
Y14162D01*
X1897375Y13662D01*
X1895945D01*
G01X1889581Y-18335D02*
X1884923Y-13677D01*
Y9710D01*
X1892871Y17658D01*
X1900945D01*
G01X1893094Y-15042D02*
Y-12642D01*
G01X1893081Y-18335D02*
Y-20735D01*
G01X1891736Y155900D02*
Y155856D01*
X1891732Y155852D01*
Y154482D01*
X1890239Y152989D01*
Y147437D01*
X1889844Y147042D01*
X1888639D01*
G01X1893705Y155900D02*
Y153955D01*
X1892039Y152289D01*
Y147536D01*
X1892533Y147042D01*
X1893640D01*
G01X1897642Y155900D02*
Y153507D01*
X1897726Y153423D01*
Y148378D01*
X1896614Y147266D01*
Y143065D01*
X1895671Y142122D01*
X1894855D01*
G01X1899610Y155900D02*
Y153507D01*
X1899526Y153423D01*
Y147632D01*
X1898414Y146520D01*
Y142518D01*
X1898810Y142122D01*
X1899855D01*
G54D356*
G01X30600Y-12000D02*
X31500Y-12900D01*
X33400D01*
X33988Y-12312D01*
Y-10625D01*
G01X30600Y-12000D02*
X27600Y-9000D01*
Y-4137D01*
X28400Y-3337D01*
X29850D01*
G01X31899Y-14906D02*
X31599D01*
X30600Y-13907D01*
Y-12000D01*
G01X53340Y-16796D02*
X51378D01*
X50539Y-15957D01*
Y-14835D01*
X48579Y-12875D01*
X45834D01*
X45012Y-12053D01*
Y-10625D01*
G01X43437D02*
Y-12187D01*
X45373Y-14123D01*
X47256D01*
X48613Y-15480D01*
Y-16137D01*
G01X40287Y-10625D02*
Y-13102D01*
G01X35563Y-12657D02*
Y-10625D01*
G01X38713D02*
Y-12513D01*
X37700Y-13526D01*
Y-16010D01*
X37410Y-16300D01*
G01X8466Y69728D02*
X7028D01*
X6650Y69350D01*
X5950D01*
X5834Y69234D01*
G01X21000Y495800D02*
Y496500D01*
X19212Y498288D01*
X17750D01*
G01X10462Y494150D02*
Y490668D01*
X10443Y490649D01*
G01X10932Y523601D02*
X8887Y521556D01*
Y513450D01*
G01X14700Y517000D02*
X11800D01*
X10462Y515662D01*
Y513450D01*
G01X22788Y510338D02*
X21762Y509312D01*
X17750D01*
G01X21500Y507737D02*
X17750D01*
G01X19533Y513433D02*
X17750Y511650D01*
Y510887D01*
G01X25388Y504477D02*
X28028D01*
X28870Y503635D01*
G01X17750Y506162D02*
X22358D01*
X24043Y504477D01*
X25388D01*
G01X17750Y499863D02*
X19636D01*
X23000Y496499D01*
Y494500D01*
X25000Y492500D01*
G01X23000Y487500D02*
Y490500D01*
X25000Y492500D01*
G01X22491Y500618D02*
X20096Y503013D01*
X17750D01*
G01X25000Y496500D02*
Y497201D01*
X22491Y499710D01*
Y500618D01*
G01X49150Y-1762D02*
X52793D01*
G01X52744Y-4368D02*
X52333D01*
X51302Y-3337D01*
X49150D01*
G01X46587Y-10625D02*
X46892Y-10930D01*
X50096D01*
G01X87500Y322000D02*
X86387Y323113D01*
Y327900D01*
G01X72000Y385500D02*
Y381410D01*
X71300Y380710D01*
G01D02*
Y379200D01*
X72563Y377937D01*
Y375400D01*
G01X88300Y383110D02*
X86484D01*
X84164Y380790D01*
G01D02*
X82012Y378638D01*
Y375400D01*
G01X60934Y362307D02*
Y362306D01*
X61841Y363213D01*
X65100D01*
G01Y364787D02*
X60412D01*
X59599Y365600D01*
G01X65100Y366362D02*
X61538D01*
X56200Y371700D01*
X55500D01*
G01X65100Y367937D02*
X62800D01*
X62000Y368737D01*
Y368731D01*
X61914D01*
G01X65100Y369512D02*
X63672D01*
X57800Y375384D01*
Y376100D01*
G01X69413Y377587D02*
Y375400D01*
G01X74138D02*
Y379038D01*
X74800Y379700D01*
G01X78862Y375400D02*
Y377062D01*
X80200Y378400D01*
Y379700D01*
G01X65100Y372661D02*
X63401D01*
X62600Y373462D01*
Y375100D01*
G01X87900Y371087D02*
X90507D01*
G01X89570Y373280D02*
X88951Y372661D01*
X87900D01*
G01X77300Y383114D02*
Y381462D01*
X76900Y381062D01*
Y378500D01*
X75713Y377313D01*
Y375400D01*
G01X77287D02*
Y377187D01*
X78300Y378200D01*
Y380614D01*
X80800Y383114D01*
G01X334328Y203260D02*
Y199108D01*
G01X320808Y207159D02*
X320784Y207135D01*
Y203219D01*
G01X317428Y197409D02*
Y193507D01*
G01X324188Y205210D02*
X324200Y205198D01*
Y201308D01*
G01X330948Y205210D02*
Y201258D01*
G01X324458Y399911D02*
X324188Y399641D01*
Y396309D01*
G01X357987Y197409D02*
Y193507D01*
G01X378267Y197409D02*
Y193507D01*
G01X395166Y355360D02*
X392916D01*
G01X398546Y357309D02*
X396296D01*
G01X391787D02*
X389537D01*
G01X447800Y335900D02*
X447400Y335500D01*
X438000D01*
X433100Y330600D01*
Y330300D01*
G01X450700Y335550D02*
X449056Y333906D01*
X439406D01*
X436100Y330600D01*
Y330300D01*
G01X439100D02*
Y331300D01*
X439950Y332150D01*
X449838D01*
X453200Y335512D01*
Y335550D01*
G01X456900Y333000D02*
X453700Y329800D01*
X443500D01*
X443000Y330300D01*
X442100D01*
G01X662163Y253350D02*
Y251537D01*
X662800Y250900D01*
Y248600D01*
G01X697492Y38721D02*
X696547Y39666D01*
Y41350D01*
G01X668462Y253350D02*
Y251062D01*
X667600Y250200D01*
G01X666887Y253350D02*
Y250913D01*
X667600Y250200D01*
G01X714100Y274213D02*
X711515D01*
X709949Y272647D01*
G01X714100Y275787D02*
X709987D01*
X709700Y275500D01*
G01X714100Y277362D02*
X710338D01*
X709600Y278100D01*
G01X714100Y278937D02*
X711391D01*
X710405Y279923D01*
X708871D01*
X707048Y278100D01*
X706800D01*
G01X684050Y278000D02*
Y274500D01*
G01X680880Y271000D02*
X684750D01*
G01X680880D02*
X678392Y268512D01*
X675750D01*
G01X684050Y274500D02*
Y273200D01*
X684750Y272500D01*
Y271000D01*
G01X675750Y263787D02*
X679173D01*
X680385Y263285D01*
X681500Y262170D01*
Y260248D01*
G01D02*
Y258850D01*
X682780Y257570D01*
X684020D01*
G01X666887Y272650D02*
Y274787D01*
X667700Y275600D01*
G01X675750Y271357D02*
Y270087D01*
G01Y265362D02*
X680621D01*
X680932Y265673D01*
G01X684750Y264000D02*
Y267500D01*
G01X680932Y265673D02*
X682759Y267500D01*
X684750D01*
G01X684050Y260597D02*
Y263300D01*
X684750Y264000D01*
G01X684000Y251307D02*
X682073D01*
X679930Y253450D01*
Y256380D01*
X677247Y259063D01*
X675750D01*
G01X693529Y250188D02*
X692289Y248948D01*
X685546D01*
X684000Y250494D01*
Y251307D01*
G01X675750Y262213D02*
X678787D01*
X679300Y261700D01*
G01D02*
Y258900D01*
X681740Y256460D01*
Y255090D01*
X682360Y254470D01*
X684000D01*
G01X714100Y280512D02*
X711629D01*
X710272Y281869D01*
Y281911D01*
G01X724000Y291700D02*
Y290728D01*
X723362Y290090D01*
Y288623D01*
X723138Y288399D01*
Y286400D01*
G01X714100Y283661D02*
X712572D01*
X711359Y284874D01*
X709332D01*
X706800Y282342D01*
Y281900D01*
G01X725400Y293900D02*
Y293174D01*
X725800Y292774D01*
Y290600D01*
X724713Y289513D01*
Y286400D01*
G01X727862D02*
Y288812D01*
X729562Y290512D01*
Y290725D01*
X729405D01*
G01X728800Y294300D02*
Y293500D01*
X727600Y292300D01*
Y290500D01*
X726287Y289187D01*
Y286400D01*
G01X970416Y207159D02*
X970392Y207135D01*
Y203219D01*
G01X967036Y197409D02*
Y193507D01*
G01X1007482Y84806D02*
X1007480Y84808D01*
Y87500D01*
G01X973796Y205210D02*
X973808Y205198D01*
Y201308D01*
G01X980556Y205210D02*
Y201258D01*
G01X983936Y203260D02*
Y199108D01*
G01X1027875Y197409D02*
Y193507D01*
G01X1007595Y197409D02*
Y193507D01*
G01X973796Y396309D02*
Y399641D01*
X974066Y399911D01*
G01X1084580Y330260D02*
Y330651D01*
X1089580Y335651D01*
X1098041D01*
X1099391Y337001D01*
G01X1087680Y330260D02*
X1091471Y334051D01*
X1099951D01*
X1102300Y336400D01*
Y336700D01*
G01X1091180Y330160D02*
X1093071Y332051D01*
X1100751D01*
X1105530Y336830D01*
X1105800D01*
G01X1105900Y334000D02*
X1102000Y330100D01*
X1095000D01*
G01X1044774Y355360D02*
X1042524D01*
G01X1048154Y357309D02*
X1045904D01*
G01X1041395D02*
X1039145D01*
G01X1189369Y403396D02*
X1189442Y403469D01*
Y406942D01*
X1192050Y409550D01*
X1192200D01*
G01X1343260Y53770D02*
X1339370D01*
X1337500Y51900D01*
X1334000D01*
G01D02*
Y55000D01*
G01X1369408Y50479D02*
Y54104D01*
X1368524Y54988D01*
X1366650D01*
G01X1365855Y46972D02*
X1364447Y48380D01*
X1359877D01*
X1359362Y48895D01*
Y50850D01*
G01X1378000Y50500D02*
X1380500D01*
G01X1380900Y59820D02*
X1379580Y58500D01*
X1378000D01*
G01X1369400Y65100D02*
X1368737Y64437D01*
X1366650D01*
G01X1347350Y54988D02*
X1344478D01*
X1343260Y53770D01*
G01X1357787Y70150D02*
Y73787D01*
X1358500Y74500D01*
G01X1359362Y70150D02*
Y72362D01*
X1360141Y73141D01*
G01X1370975Y67225D02*
X1369405D01*
G01D02*
X1368192Y66012D01*
X1366650D01*
G01Y61287D02*
X1368713D01*
X1370651Y59349D01*
X1370849D01*
G01X1369716Y55784D02*
X1368937Y56563D01*
X1366650D01*
G01Y67587D02*
Y69151D01*
G01Y62862D02*
X1369037D01*
G01X1366650Y59713D02*
X1368078D01*
X1368900Y58891D01*
Y58732D01*
X1373132Y54500D01*
X1374500D01*
G01X1377666Y384822D02*
X1379436D01*
X1380108Y385494D01*
X1382692D01*
G01X1404910Y540018D02*
X1402623D01*
G01X1404910Y536868D02*
Y534137D01*
X1401960Y531187D01*
Y528455D01*
G01X1401499Y541593D02*
X1404910D01*
G01Y543168D02*
X1401992D01*
X1398471Y546689D01*
X1398455D01*
X1397674Y547470D01*
X1387940D01*
X1387720Y547690D01*
G01D02*
X1386680Y548730D01*
X1383920D01*
G01X1404910Y547892D02*
X1402744D01*
X1400222Y550414D01*
Y550685D01*
G01X1397235Y551044D02*
Y550455D01*
X1402948Y544742D01*
X1404910D01*
G01X1412198Y553605D02*
Y557201D01*
G01D02*
X1412019Y557380D01*
G01X1413773Y534305D02*
Y531473D01*
X1413600Y531300D01*
G01X1412198Y534305D02*
Y532597D01*
X1410486Y530885D01*
Y529792D01*
G01X1507076Y138862D02*
X1499933D01*
X1498395Y140400D01*
X1493750D01*
G01X1513023Y140630D02*
X1507785D01*
X1507076Y139921D01*
Y138862D01*
G01Y132956D02*
X1511017D01*
X1511664Y133603D01*
G01X1571732Y379350D02*
X1571066Y380016D01*
X1568353D01*
X1567475Y380894D01*
G01X1562137Y615150D02*
Y617337D01*
X1563827Y619027D01*
Y621376D01*
G01X1555838Y615150D02*
Y618062D01*
X1554800Y619100D01*
Y620910D01*
G01X1545407Y598393D02*
X1547002Y599988D01*
X1548550D01*
G01X1554263Y595850D02*
Y593669D01*
X1553000Y592406D01*
Y591100D01*
G01X1567850Y611012D02*
X1570782D01*
X1571670Y611900D01*
Y611943D01*
X1572167Y612440D01*
X1572210D01*
X1573270Y613500D01*
X1573500D01*
G01X1648393Y153280D02*
X1650653D01*
X1651556Y152377D01*
Y150157D01*
X1649961Y148562D01*
G01X1646812Y154861D02*
X1648393Y153280D01*
G01X1842250Y94600D02*
Y97131D01*
X1843107Y97988D01*
G01X1842250Y86900D02*
Y84000D01*
G01X1843825Y86900D02*
Y84800D01*
X1843025Y84000D01*
X1842250D01*
G01X1844957Y97221D02*
X1843874Y96138D01*
X1843864D01*
X1843825Y96099D01*
Y94600D01*
G01X1849426Y90700D02*
X1849376Y90750D01*
X1846100D01*
G01Y89175D02*
X1847924D01*
X1848546Y88553D01*
X1849551D01*
G01X1848972Y93219D02*
X1848266D01*
X1847372Y92325D01*
X1846100D01*
G01X1874600Y109250D02*
Y106756D01*
X1874151Y106307D01*
Y104671D01*
X1874251Y104571D01*
Y103203D01*
X1874258Y103196D01*
G54D347*
G01X1553918Y268469D02*
X1550750D01*
G01X1553868Y266500D02*
X1550750D01*
G54D38*
X29850Y-8062D03*
Y-6487D03*
Y-4912D03*
Y-3337D03*
Y-1762D03*
Y-188D03*
Y1387D03*
Y2962D03*
Y4537D03*
Y6112D03*
G54D257*
X1632000Y47500D03*
Y64500D03*
G54D293*
X1808600Y48200D03*
Y73000D03*
X1786800Y48200D03*
Y73000D03*
G54D65*
X17750Y510887D03*
Y509312D03*
Y507737D03*
Y506162D03*
Y504587D03*
Y503013D03*
Y501438D03*
Y499863D03*
Y498288D03*
Y496713D03*
X675750Y270087D03*
Y268512D03*
Y266937D03*
Y265362D03*
Y263787D03*
Y262213D03*
Y260638D03*
Y259063D03*
Y257488D03*
Y255913D03*
X1366650Y67587D03*
Y66012D03*
Y64437D03*
Y62862D03*
Y61287D03*
Y59713D03*
Y58138D03*
Y56563D03*
Y54988D03*
Y53413D03*
G54D92*
X71500Y298000D03*
G54D176*
X1253964Y297498D03*
X1254493Y290195D03*
X1237316Y312648D03*
G54D275*
X1711578Y512900D03*
G54D248*
X1542009Y17268D03*
Y30668D03*
X1545159Y17268D03*
Y30668D03*
X1548309Y17268D03*
Y30668D03*
X1551459Y17268D03*
Y30668D03*
X1554609Y17268D03*
Y30668D03*
X1557759Y17268D03*
Y30668D03*
X1560909Y17268D03*
Y30668D03*
X1564059Y17268D03*
Y30668D03*
X1567209Y17268D03*
Y30668D03*
X1570359Y17268D03*
Y30668D03*
X1573509Y17268D03*
Y30668D03*
X1576659Y17268D03*
Y30668D03*
X1579809Y17268D03*
Y30668D03*
X1582959Y17268D03*
Y30668D03*
X1586109Y17268D03*
Y30668D03*
X1589259Y17268D03*
Y30668D03*
X1592409Y17268D03*
Y30668D03*
X1595559Y17268D03*
Y30668D03*
X1598709Y17268D03*
Y30668D03*
X1601859Y17268D03*
Y30668D03*
X1605009Y17268D03*
Y30668D03*
X1608159Y17268D03*
Y30668D03*
X1611309Y17268D03*
Y30668D03*
X1614459Y17268D03*
Y30668D03*
X1617609Y17268D03*
Y30668D03*
X1620759Y17268D03*
Y30668D03*
X1623909Y17268D03*
Y30668D03*
X1627059Y17268D03*
Y30668D03*
X1630209Y17268D03*
Y30668D03*
X1633359Y17268D03*
Y30668D03*
X1636509Y17268D03*
Y30668D03*
X1639659Y17268D03*
Y30668D03*
X1642809Y17268D03*
Y30668D03*
X1645959Y17268D03*
Y30668D03*
X1649109Y17268D03*
Y30668D03*
X1652259Y17268D03*
Y30668D03*
X1655409Y17268D03*
Y30668D03*
X1658559Y17268D03*
Y30668D03*
X1661709Y17268D03*
Y30668D03*
X1664859Y17268D03*
Y30668D03*
X1668009Y17268D03*
Y30668D03*
X1671159Y17268D03*
Y30668D03*
X1674309Y17268D03*
Y30668D03*
X1677459Y17268D03*
Y30668D03*
X1680609Y17268D03*
Y30668D03*
X1683759Y17268D03*
Y30668D03*
X1686909Y17268D03*
Y30668D03*
X1690059Y17268D03*
Y30668D03*
X1693209Y17268D03*
Y30668D03*
X1696359Y17268D03*
Y30668D03*
X1699509D03*
X1702659Y17268D03*
Y30668D03*
X1705809Y17268D03*
Y30668D03*
X1708959Y17268D03*
Y30668D03*
X1712109Y17268D03*
Y30668D03*
X1699509Y17268D03*
X1715259D03*
Y30668D03*
X1718409Y17268D03*
Y30668D03*
X1721559Y17268D03*
Y30668D03*
X1724709Y17268D03*
Y30668D03*
X1727859Y17268D03*
Y30668D03*
X1731009Y17268D03*
Y30668D03*
X1734159Y17268D03*
Y30668D03*
X1737309Y17268D03*
Y30668D03*
X1740459Y17268D03*
Y30668D03*
X1743609Y17268D03*
Y30668D03*
X1746759Y17268D03*
Y30668D03*
X1749909Y17268D03*
Y30668D03*
X1753059Y17268D03*
Y30668D03*
X1768807Y17268D03*
Y30668D03*
X1771957Y17268D03*
Y30668D03*
X1775107Y17268D03*
Y30668D03*
X1778257Y17268D03*
Y30668D03*
X1781407Y17268D03*
Y30668D03*
X1784557Y17268D03*
Y30668D03*
X1787707Y17268D03*
Y30668D03*
X1790857Y17268D03*
Y30668D03*
X1794007Y17268D03*
Y30668D03*
X1797157Y17268D03*
Y30668D03*
X1800307Y17268D03*
Y30668D03*
X1803457Y17268D03*
Y30668D03*
X1806607Y17268D03*
Y30668D03*
X1809757Y17268D03*
Y30668D03*
X1812907Y17268D03*
Y30668D03*
X1816057Y17268D03*
Y30668D03*
X1819207Y17268D03*
Y30668D03*
X1822357Y17268D03*
Y30668D03*
X1825507Y17268D03*
Y30668D03*
X1828657Y17268D03*
Y30668D03*
X1831807Y17268D03*
Y30668D03*
X1834957Y17268D03*
Y30668D03*
X1853857D03*
X1857007Y17268D03*
Y30668D03*
X1860157Y17268D03*
Y30668D03*
X1863307Y17268D03*
Y30668D03*
X1838107Y17268D03*
X1866457D03*
X1838107Y30668D03*
X1841257Y17268D03*
Y30668D03*
X1844407Y17268D03*
Y30668D03*
X1847557Y17268D03*
Y30668D03*
X1850707Y17268D03*
Y30668D03*
X1853857Y17268D03*
X1866457Y30668D03*
G54D47*
X42600Y35244D03*
X42500Y62500D03*
X33500Y580000D03*
X33100Y544100D03*
X71100Y35244D03*
X71000Y62500D03*
X62000Y580000D03*
X61600Y544100D03*
X157624Y224533D03*
Y256533D03*
Y288533D03*
Y320533D03*
Y384533D03*
Y352033D03*
X186124Y224533D03*
Y256533D03*
Y288533D03*
Y320533D03*
Y384533D03*
Y352033D03*
X645684Y212995D03*
X674184D03*
X835732Y256533D03*
X807232D03*
X835732Y224533D03*
X807232D03*
X835732Y288533D03*
X807232D03*
X835732Y320533D03*
X807232D03*
X835732Y351533D03*
X807232D03*
X835687Y383681D03*
X807187D03*
X1313516Y22624D03*
X1342016D03*
X1314216Y-7476D03*
X1342716D03*
X1315000Y387500D03*
X1343500D03*
X1315400Y580556D03*
X1343900D03*
X1315300Y609456D03*
X1343800D03*
X1513700Y577066D03*
X1542200D03*
G54D167*
X1241963Y132677D03*
X1233463Y128927D03*
Y136427D03*
X1574447Y291724D03*
X1565947Y287974D03*
Y295474D03*
X1650250Y217650D03*
Y225150D03*
X1658750Y221400D03*
G54D185*
X1270621Y355590D03*
G54D239*
X1475723Y602756D03*
X1511261Y604024D03*
G54D329*
X1949650Y220787D03*
Y228661D03*
G54D83*
X67500Y255200D03*
X68053Y232300D03*
G54D29*
X43586Y-19703D03*
G54D56*
X12290Y264640D03*
X18450Y267010D03*
X22970Y244400D03*
X28720Y244450D03*
X17120Y244220D03*
X24200Y267060D03*
G54D149*
X699500Y56450D03*
Y542700D03*
X1359700Y116400D03*
X1354500Y527000D03*
G54D338*
X1952756Y589960D03*
X1944882Y582086D03*
X1952756D03*
X1944882Y574212D03*
X1952756D03*
X1944882Y566338D03*
X1952756D03*
X1944882Y558464D03*
Y589960D03*
Y605708D03*
X1952756D03*
X1944882Y597834D03*
X1952756D03*
G54D194*
X1225284Y468813D03*
X1234100Y475081D03*
G54D284*
X1770080Y504930D03*
X1788580D03*
G54D74*
X63261Y8225D03*
X117589Y227500D03*
X110032Y373284D03*
X680330Y9287D03*
X767277Y323658D03*
X1307363Y480350D03*
X1310700Y492569D03*
X1345561Y84900D03*
X1384906Y394845D03*
X1371874Y494665D03*
X1349779Y479400D03*
X1400050Y501950D03*
X1442800Y439175D03*
X1443000Y450275D03*
X1447800Y440125D03*
X1448000Y451225D03*
X1444550Y412364D03*
X1449350Y411414D03*
X1421608Y485300D03*
X1426993Y486250D03*
X1588510Y130663D03*
X1587477Y144569D03*
X1593420Y131800D03*
X1592816Y140550D03*
X1593401Y145489D03*
X1634358Y180527D03*
X1780543Y609000D03*
X1850407Y93219D03*
X1868541Y138200D03*
X1836531Y97664D03*
X1929336Y167130D03*
G54D266*
X1599194Y429620D03*
G54D158*
X694053Y213901D03*
X1359142Y-6923D03*
X1359453Y25101D03*
X1361760Y383969D03*
X1363453Y571957D03*
Y603157D03*
G54D357*
G01X334328Y207159D02*
Y203260D01*
G01X462023Y202547D02*
Y198327D01*
G01X455263Y198050D02*
Y198100D01*
X455290Y198127D01*
Y202520D01*
X455263Y202547D01*
G01X458643Y204496D02*
Y200599D01*
X458640Y200596D01*
G01X458643Y208397D02*
Y204496D01*
G01X983936Y207159D02*
Y203260D01*
G01X1111631Y202547D02*
Y198327D01*
G01X1108251Y208397D02*
Y204496D01*
G01X1104871Y202547D02*
X1104898Y202520D01*
Y198127D01*
X1104871Y198100D01*
Y198050D01*
G01X1108251Y204496D02*
Y200599D01*
X1108248Y200596D01*
G01X1493375Y446020D02*
X1493312Y445737D01*
X1492068Y444944D01*
X1490787D01*
X1489711Y446020D01*
X1489475D01*
G54D348*
G01X1849551Y88553D02*
X1850498Y87606D01*
G01D02*
X1853671Y84433D01*
X1856354D01*
G01Y96430D02*
X1854950D01*
X1851739Y93219D01*
X1850407D01*
G01D02*
X1848972D01*
G01X1943369Y80902D02*
X1947932D01*
X1948472Y80362D01*
G54D39*
X32413Y8675D03*
X33988D03*
X35563D03*
X37138D03*
X38713D03*
X40287D03*
X41862D03*
X43437D03*
X45012D03*
X46587D03*
G54D66*
X15187Y494150D03*
X13612D03*
X12037D03*
X10462D03*
X8887D03*
X7313D03*
X5738D03*
X4163D03*
X2588D03*
X1013D03*
X662163Y253350D03*
X660588D03*
X659013D03*
X673187D03*
X671612D03*
X670037D03*
X668462D03*
X666887D03*
X665313D03*
X663738D03*
X1364087Y50850D03*
X1362512D03*
X1360937D03*
X1359362D03*
X1357787D03*
X1356213D03*
X1354638D03*
X1353063D03*
X1351488D03*
X1349913D03*
G54D177*
X1236150Y300592D03*
G54D168*
X1279928Y207308D03*
X1288111Y199713D03*
G54D267*
X1647186Y474076D03*
Y527817D03*
G54D186*
X1279501Y350527D03*
G54D249*
X1569492Y125722D03*
X1692272Y119372D03*
X1682615Y113935D03*
G54D258*
X1623812Y235469D03*
G54D195*
X1316231Y205501D03*
X1303646Y199358D03*
X1293820Y221977D03*
G54D57*
X3000Y280500D03*
X5560D03*
X8120D03*
X10680D03*
X3000Y290500D03*
X8120D03*
X5560D03*
X10680D03*
G54D84*
X104000Y243000D03*
Y254000D03*
X128450Y118700D03*
Y129700D03*
X727500Y93000D03*
Y104000D03*
X758603Y506177D03*
Y495177D03*
X1512959Y277400D03*
Y266400D03*
X1889400Y77300D03*
Y88300D03*
G54D276*
X1710594Y516950D03*
Y508850D03*
X1708626Y516950D03*
Y508850D03*
X1714530Y516950D03*
Y508850D03*
X1712562Y516950D03*
Y508850D03*
G54D294*
X1835832Y56368D03*
X1859768D03*
G54D48*
X21100Y16000D03*
X22292Y503187D03*
X398408Y106083D03*
X410543Y112617D03*
X396832Y114253D03*
X389148Y112345D03*
X404022Y112970D03*
X417190Y112652D03*
X383938Y103754D03*
X424817Y111219D03*
X422606Y116393D03*
X433172Y108790D03*
X439767Y105158D03*
X454520Y104627D03*
X481792Y112900D03*
X488242Y116350D03*
X697307Y275728D03*
X1033546Y103754D03*
X1048016Y106083D03*
X1060718Y112050D03*
X1074425Y111219D03*
X1045884Y114809D03*
X1081142Y110428D03*
X1090500Y104033D03*
X1038756Y112345D03*
X1053630Y112970D03*
X1066798Y112652D03*
X1104128Y104627D03*
X1101598Y110917D03*
X1131400Y112900D03*
X1109228Y123800D03*
X1118586Y143516D03*
X1138850Y115350D03*
X1134363Y143064D03*
X1141231Y139841D03*
G54D285*
X1719500Y494500D03*
G54D159*
X684400Y228100D03*
X1343072Y40715D03*
X1356960Y9620D03*
X1360800Y368200D03*
X1357200Y556000D03*
X1362482Y618600D03*
G54D339*
X1952756Y558464D03*
G54D75*
X107249Y105000D03*
X102328D03*
X97406D03*
X92485D03*
X87564D03*
X82643D03*
X77721D03*
G54D93*
X78395Y288750D03*
X76425D03*
X74455D03*
X72485D03*
X70515D03*
X68545D03*
X66575D03*
X64605D03*
G54D358*
G01X54700Y91500D02*
X53496Y92704D01*
X51760D01*
X51381Y92325D01*
Y90750D01*
G01X54700Y95000D02*
X53496Y93796D01*
X51760D01*
X51381Y94175D01*
Y95750D01*
G01X58200Y91500D02*
Y92640D01*
X58885Y93325D01*
X65094D01*
X66000Y92419D01*
Y91350D01*
X65550Y90900D01*
X63725D01*
G01X58200Y95000D02*
X58925Y94275D01*
X65488D01*
X66950Y92813D01*
Y91350D01*
X67400Y90900D01*
X68725D01*
G01X54700Y102000D02*
X53425Y100725D01*
X47350D01*
X46900Y101175D01*
Y102750D01*
G01X54700Y105500D02*
X53496Y106704D01*
X51760D01*
X51381Y106325D01*
Y104750D01*
G01X54700Y112500D02*
X53425Y113775D01*
X47350D01*
X46900Y113325D01*
Y111750D01*
G01X54700Y123000D02*
X53425Y121725D01*
X52019D01*
X51569Y122175D01*
Y123750D01*
G01X54700Y126500D02*
X53425Y127775D01*
X47350D01*
X46900Y127325D01*
Y125750D01*
G01X54700Y137000D02*
X53425Y135725D01*
X52019D01*
X51569Y136175D01*
Y137750D01*
G01X54700Y140500D02*
X53425Y141775D01*
X47350D01*
X46900Y141325D01*
Y139750D01*
G01X54700Y98500D02*
X53425Y99775D01*
X47350D01*
X46900Y99325D01*
Y97750D01*
G01X54700Y109000D02*
X53496Y107796D01*
X51760D01*
X51381Y108175D01*
Y109750D01*
G01X54700Y116000D02*
X53425Y114725D01*
X47350D01*
X46900Y115175D01*
Y116750D01*
G01X54700Y119500D02*
X53425Y120775D01*
X52019D01*
X51569Y120325D01*
Y118750D01*
G01X54700Y130000D02*
X53425Y128725D01*
X47350D01*
X46900Y129175D01*
Y130750D01*
G01X54700Y133500D02*
X53425Y134775D01*
X52019D01*
X51569Y134325D01*
Y132750D01*
G01X54700Y144000D02*
X53425Y142725D01*
X47350D01*
X46900Y143175D01*
Y144750D01*
G01X58200Y102000D02*
X59404Y100796D01*
X60452D01*
X60831Y101175D01*
X60801Y102750D01*
G01X58200Y105500D02*
X59475Y106775D01*
X64934D01*
X65384Y106325D01*
Y104750D01*
G01X58200Y112500D02*
X59462Y113762D01*
X60263D01*
X60700Y113325D01*
Y111750D01*
G01X58200Y123000D02*
X59480Y121720D01*
X64970D01*
X65405Y122155D01*
Y123730D01*
G01X58200Y126500D02*
X59404Y127704D01*
X60452D01*
X60831Y127325D01*
Y125750D01*
G01X58200Y137000D02*
X59475Y135725D01*
X65237D01*
X65687Y136175D01*
Y137750D01*
G01X58200Y140500D02*
X59475Y141775D01*
X60381D01*
X60831Y141325D01*
Y139750D01*
G01X58200Y98500D02*
X59404Y99704D01*
X60452D01*
X60831Y99325D01*
X60801Y97750D01*
G01X65384Y109750D02*
Y108783D01*
X64326Y107725D01*
X59475D01*
X58200Y109000D01*
G01Y116000D02*
X59488Y114712D01*
X60237D01*
X60700Y115175D01*
Y116750D01*
G01X58200Y119500D02*
X59470Y120770D01*
X64940D01*
X65405Y120305D01*
Y118730D01*
G01X58200Y130000D02*
X59404Y128796D01*
X60452D01*
X60831Y129175D01*
Y130750D01*
G01X58200Y133500D02*
X59475Y134775D01*
X65237D01*
X65687Y134325D01*
Y132750D01*
G01X58200Y144000D02*
X59475Y142725D01*
X60381D01*
X60831Y143175D01*
Y144750D01*
G01X206696Y651626D02*
X205190Y650086D01*
X203176D01*
X198827Y650423D01*
X193498Y649531D01*
X191355Y646895D01*
X191018Y644986D01*
X190498Y644623D01*
X189079Y644873D01*
X188714Y645393D01*
X190240Y654048D01*
X189423Y655214D01*
X187229Y655599D01*
X186061Y654782D01*
X184352Y645081D01*
X183832Y644717D01*
X182414Y644967D01*
X182050Y645488D01*
X183560Y654059D01*
X182745Y655228D01*
X180551Y655613D01*
X179383Y654796D01*
X177671Y645079D01*
X177151Y644715D01*
X175732Y644965D01*
X175367Y645484D01*
X176864Y653978D01*
X176049Y655145D01*
X173853Y655529D01*
X172685Y654714D01*
X170987Y645067D01*
X170467Y644702D01*
X169049Y644952D01*
X168685Y645473D01*
X170179Y653956D01*
X169364Y655125D01*
X167170Y655510D01*
X166002Y654693D01*
X164308Y645073D01*
X163788Y644709D01*
X162368Y644957D01*
X162004Y645477D01*
X163501Y653972D01*
X162684Y655138D01*
X160492Y655523D01*
X159323Y654708D01*
X157614Y645006D01*
X157095Y644643D01*
X155675Y644891D01*
X155311Y645411D01*
X156816Y653952D01*
X155999Y655118D01*
X153806Y655503D01*
X152638Y654686D01*
X150934Y645014D01*
X150401Y644641D01*
X149005Y644887D01*
X148629Y645422D01*
X150136Y653974D01*
X149320Y655141D01*
X147128Y655526D01*
X145959Y654709D01*
X144251Y645000D01*
X143731Y644636D01*
X142310Y644886D01*
X141947Y645406D01*
X143455Y653973D01*
X142638Y655139D01*
X140447Y655523D01*
X139278Y654706D01*
X137574Y645033D01*
X137054Y644669D01*
X135634Y644918D01*
X135269Y645440D01*
X136771Y653957D01*
X135956Y655126D01*
X133763Y655511D01*
X132595Y654694D01*
X131815Y650276D01*
X130906Y645126D01*
X130383Y644760D01*
X128967Y645009D01*
X128602Y645532D01*
X130104Y654050D01*
X129287Y655217D01*
X127092Y655602D01*
X125927Y654787D01*
X124223Y645114D01*
X123699Y644748D01*
X122283Y644996D01*
X121918Y645517D01*
X123426Y654083D01*
X122613Y655249D01*
X120415Y655635D01*
X119250Y654820D01*
X117542Y645111D01*
X117019Y644745D01*
X115602Y644994D01*
X115237Y645515D01*
X116745Y654069D01*
X115916Y655248D01*
X113745Y655631D01*
X112567Y654806D01*
X110863Y645134D01*
X110340Y644768D01*
X108922Y645017D01*
X108557Y645538D01*
X110062Y654079D01*
X109246Y655244D01*
X107052Y655629D01*
X105887Y654814D01*
X104178Y645113D01*
X103655Y644748D01*
X102237Y644997D01*
X101872Y645518D01*
X103369Y654013D01*
X102553Y655178D01*
X100359Y655563D01*
X99193Y654747D01*
X97499Y645127D01*
X96976Y644761D01*
X95559Y645010D01*
X95194Y645533D01*
X96689Y654017D01*
X95873Y655183D01*
X93679Y655569D01*
X92514Y654753D01*
X90816Y645107D01*
X90293Y644742D01*
X88873Y644990D01*
X88509Y645511D01*
X90006Y654006D01*
X89190Y655170D01*
X86996Y655557D01*
X85830Y654741D01*
X84118Y645024D01*
X83595Y644658D01*
X82178Y644907D01*
X81813Y645430D01*
X83324Y654002D01*
X82508Y655168D01*
X80314Y655555D01*
X79149Y654739D01*
X77440Y645038D01*
X76917Y644672D01*
X75498Y644921D01*
X75133Y645442D01*
X76659Y654097D01*
X75843Y655262D01*
X73649Y655648D01*
X72483Y654835D01*
X72121Y652780D01*
X70360Y650614D01*
X65500Y649801D01*
X61230Y650131D01*
X59179D01*
X57684Y651654D01*
G01X206696Y647686D02*
X205190Y649136D01*
X203139D01*
X198869Y649466D01*
X194009Y648653D01*
X192248Y646487D01*
X191886Y644432D01*
X190720Y643619D01*
X188526Y644005D01*
X187710Y645170D01*
X189236Y653825D01*
X188871Y654346D01*
X187452Y654595D01*
X186929Y654229D01*
X185220Y644528D01*
X184055Y643712D01*
X181861Y644099D01*
X181045Y645265D01*
X182556Y653837D01*
X182191Y654360D01*
X180774Y654609D01*
X180251Y654243D01*
X178539Y644526D01*
X177373Y643710D01*
X175179Y644097D01*
X174363Y645261D01*
X175860Y653756D01*
X175496Y654277D01*
X174076Y654525D01*
X173553Y654160D01*
X171855Y644514D01*
X170690Y643698D01*
X168496Y644084D01*
X167680Y645250D01*
X169175Y653734D01*
X168810Y654257D01*
X167393Y654506D01*
X166870Y654140D01*
X165176Y644520D01*
X164010Y643704D01*
X161816Y644089D01*
X161000Y645254D01*
X162497Y653749D01*
X162132Y654270D01*
X160714Y654519D01*
X160191Y654154D01*
X158482Y644453D01*
X157317Y643638D01*
X155123Y644023D01*
X154307Y645188D01*
X155812Y653729D01*
X155447Y654250D01*
X154029Y654499D01*
X153506Y654133D01*
X151802Y644461D01*
X150624Y643636D01*
X148453Y644019D01*
X147624Y645198D01*
X149132Y653752D01*
X148767Y654273D01*
X147350Y654522D01*
X146827Y654156D01*
X145119Y644447D01*
X143954Y643632D01*
X141756Y644018D01*
X140943Y645184D01*
X142451Y653750D01*
X142086Y654271D01*
X140670Y654519D01*
X140146Y654153D01*
X138442Y644480D01*
X137277Y643665D01*
X135082Y644050D01*
X134265Y645217D01*
X135767Y653735D01*
X135402Y654258D01*
X133986Y654507D01*
X133463Y654141D01*
X132759Y650154D01*
X131774Y644573D01*
X130606Y643756D01*
X128413Y644141D01*
X127598Y645310D01*
X129100Y653827D01*
X128735Y654349D01*
X127315Y654598D01*
X126795Y654234D01*
X125091Y644561D01*
X123922Y643744D01*
X121731Y644128D01*
X120914Y645294D01*
X122422Y653861D01*
X122059Y654381D01*
X120638Y654631D01*
X120118Y654267D01*
X118410Y644558D01*
X117241Y643741D01*
X115049Y644126D01*
X114233Y645293D01*
X115740Y653845D01*
X115364Y654380D01*
X113968Y654626D01*
X113435Y654253D01*
X111731Y644581D01*
X110563Y643764D01*
X108370Y644149D01*
X107553Y645315D01*
X109058Y653856D01*
X108694Y654376D01*
X107274Y654624D01*
X106755Y654261D01*
X105046Y644559D01*
X103877Y643744D01*
X101685Y644129D01*
X100868Y645295D01*
X102365Y653790D01*
X102001Y654310D01*
X100581Y654558D01*
X100061Y654194D01*
X98367Y644574D01*
X97199Y643757D01*
X95005Y644142D01*
X94190Y645311D01*
X95684Y653794D01*
X95320Y654315D01*
X93902Y654565D01*
X93382Y654200D01*
X91684Y644553D01*
X90516Y643738D01*
X88320Y644122D01*
X87505Y645289D01*
X89002Y653783D01*
X88637Y654302D01*
X87218Y654552D01*
X86698Y654188D01*
X84986Y644471D01*
X83818Y643654D01*
X81624Y644039D01*
X80809Y645208D01*
X82319Y653779D01*
X81955Y654300D01*
X80537Y654550D01*
X80017Y654186D01*
X78308Y644485D01*
X77140Y643668D01*
X74946Y644053D01*
X74129Y645219D01*
X75655Y653874D01*
X75290Y654394D01*
X73871Y654644D01*
X73351Y654281D01*
X73014Y652372D01*
X70871Y649736D01*
X65542Y648844D01*
X61193Y649181D01*
X59179D01*
X57684Y647714D01*
G01X246406Y647814D02*
X247801Y649209D01*
X248788D01*
X251213Y646784D01*
G01X246406Y651754D02*
X247801Y650359D01*
X248788D01*
X251213Y652784D01*
G01X394280Y647566D02*
X392913Y648933D01*
X391898D01*
X389473Y646508D01*
G01X394280Y651506D02*
X392857Y650083D01*
X391898D01*
X389473Y652508D01*
G01X477792Y346847D02*
X475542D01*
G01X474413Y344896D02*
X472163D01*
G01X477792Y350747D02*
X475542D01*
G01X433874Y647544D02*
X435269Y648939D01*
X446168D01*
X448593Y646514D01*
G01X433874Y651484D02*
X435269Y650089D01*
X446168D01*
X448593Y652514D01*
G01X522861Y210346D02*
X525111D01*
G01X519481Y212296D02*
X521731D01*
G01X512722Y208397D02*
X514972D01*
G01X512722Y212296D02*
X514972D01*
G01X505962Y216196D02*
X508212D01*
G01X502582Y214247D02*
X504832D01*
G01X495822D02*
X498072D01*
G01X539761Y216196D02*
X542011D01*
G01X533001Y212296D02*
X535251D01*
G01X529621Y210346D02*
X531871D01*
G01X529621Y214247D02*
X531871D01*
G01X522861D02*
X525111D01*
G01X516102D02*
X518352D01*
G01X516102Y210346D02*
X518351D01*
X518352Y210345D01*
G01X512722Y216196D02*
X514972D01*
G01X509342Y214247D02*
X511592D01*
G01X499202Y216196D02*
X501452D01*
G01X492442Y212296D02*
X494692D01*
G01X492442Y216196D02*
X494692D01*
G01X539761Y212296D02*
X542011D01*
G01X533001Y208397D02*
X535251D01*
G01X526241Y212296D02*
X528491D01*
G01X533001Y216196D02*
X535251D01*
G01X484552Y272747D02*
X482302D01*
G01X484552Y276646D02*
X482302D01*
G01X533001Y243496D02*
X535251D01*
G01X539761Y266896D02*
X542011D01*
G01X536381Y272747D02*
X538631D01*
G01X529621D02*
X531871D01*
G01X536381Y276646D02*
X538631D01*
G01X533001Y278596D02*
X535251D01*
G01X536381Y241547D02*
X538631D01*
G01X539761Y243496D02*
X542011D01*
G01X539761Y251296D02*
X542011D01*
G01X539761Y255196D02*
X542011D01*
G01X539761Y262996D02*
X542011D01*
G01X536381Y261047D02*
X538631D01*
G01X529621Y245447D02*
X531871D01*
G01X536381Y264947D02*
X538631D01*
G01X536381Y268847D02*
X538631D01*
G01X533001Y270796D02*
X535251D01*
G01X539761Y278596D02*
X542011D01*
G01X533001Y274696D02*
X535251D01*
G01X536381Y245447D02*
X538631D01*
G01X536381Y253247D02*
X538631D01*
G01X539761Y259096D02*
X542011D01*
G01X533001Y262996D02*
X535251D01*
G01X509342Y229847D02*
X511592D01*
G01X509342Y225947D02*
X511592D01*
G01X509342Y237647D02*
X511592D01*
G01X505962Y235696D02*
X508212D01*
G01X495822Y229847D02*
X498072D01*
G01X502582Y233746D02*
X504832D01*
G01X492442Y227896D02*
X494692D01*
G01X499202Y235696D02*
X501452D01*
G01X495822Y237647D02*
X498072D01*
G01X495822Y241547D02*
X498072D01*
G01X539761Y227896D02*
X542011D01*
G01X539761Y235696D02*
X542011D01*
G01X533001Y231797D02*
X535251D01*
G01X533001Y227896D02*
X535251D01*
G01X529621Y229847D02*
X531871D01*
G01X522861Y233746D02*
X525111D01*
G01X522861Y222047D02*
X525111D01*
G01X519481Y223996D02*
X521731D01*
G01X522861Y229847D02*
X525111D01*
G01X512722Y231797D02*
X514972D01*
G01X505962Y227896D02*
X508212D01*
G01X509342Y233746D02*
X511592D01*
G01X502582Y237647D02*
X504832D01*
G01X499202Y227896D02*
X501452D01*
G01X499202Y231797D02*
X501452D01*
G01X492442D02*
X494692D01*
G01X499202Y239596D02*
X501452D01*
G01X492442D02*
X494692D01*
G01X499202Y243496D02*
X501452D01*
G01X539761Y231797D02*
X542011D01*
G01X536381Y233746D02*
X538631D01*
G01X536381Y229847D02*
X538631D01*
G01X529621Y225947D02*
X531871D01*
G01X529621Y233746D02*
X531871D01*
G01X526241Y231797D02*
X528491D01*
G01X522861Y225947D02*
X525111D01*
G01X516102D02*
X518352D01*
G01X519481Y227896D02*
X521731D01*
G01X499202Y220096D02*
X501452D01*
G01X495822Y218147D02*
X498072D01*
G01X492442Y220096D02*
X494692D01*
G01X536381Y218147D02*
X538631D01*
G01X502582Y222047D02*
X504832D01*
G01X502582Y218147D02*
X504832D01*
G01X539761Y220096D02*
X542011D01*
G01X533001D02*
X535251D01*
G01X536381Y280547D02*
X538631D01*
G01X539761Y282496D02*
X542011D01*
G01X539761Y286396D02*
X542011D01*
G01X531871Y284447D02*
X529621D01*
G01X531871Y280547D02*
X529621D01*
G01X539761Y290296D02*
X542011D01*
G01X535251Y282496D02*
X533001D01*
G01X535251Y286396D02*
X533001D01*
G01X528491Y282496D02*
X526241D01*
G01X481172D02*
X478922D01*
G01X481172Y286396D02*
X478922D01*
G01X481172Y348796D02*
X478922D01*
G01X502582Y397546D02*
X504832D01*
G01X502582Y393647D02*
X504832D01*
G01X509342D02*
X511592D01*
G01X499202Y387796D02*
X501452D01*
G01X509342Y385847D02*
X511592D01*
G01X516102D02*
X518352D01*
G01X516102Y381947D02*
X518352D01*
G01X516102Y378047D02*
X518352D01*
G01X505962Y395597D02*
X508212D01*
G01X502582Y389747D02*
X504832D01*
G01X505962Y391696D02*
X508212D01*
G01X502582Y385847D02*
X504832D01*
G01X509342Y381947D02*
X511592D01*
G01X512722Y383896D02*
X514972D01*
G01X519481Y379996D02*
X521731D01*
G01X516102Y374146D02*
X518352D01*
G01X522861Y401447D02*
X525111D01*
G01X526241Y395597D02*
X528491D01*
G01X533001Y399496D02*
X535251D01*
G01X529621Y393647D02*
X531871D01*
G01X536381Y389747D02*
X538631D01*
G01X536381Y385847D02*
X538631D01*
G01X516102Y401447D02*
X518352D01*
G01X526241Y399496D02*
X528491D01*
G01X529621Y397546D02*
X531871D01*
G01X533001Y395597D02*
X535251D01*
G01X533001Y391696D02*
X535251D01*
G01X533001Y387796D02*
X535251D01*
G01X542011Y383896D02*
X539761D01*
G01X522861Y370247D02*
X525111D01*
G01X529621D02*
X531871D01*
G01X522861Y362447D02*
X525111D01*
G01X526241Y360496D02*
X528491D01*
G01X526241Y356596D02*
X528491D01*
G01X533001Y352696D02*
X535251D01*
G01X522861Y378047D02*
X525111D01*
G01X522861Y374146D02*
X525111D01*
G01X522861Y366347D02*
X525111D01*
G01X526241Y368296D02*
X528491D01*
G01X519481Y364396D02*
X521731D01*
G01X522861Y358547D02*
X525111D01*
G01X529621Y354647D02*
X531871D01*
G01X529621Y350747D02*
X531871D01*
G01X519481Y376096D02*
X521731D01*
G01X526241Y372197D02*
X528491D01*
G01X542011Y379996D02*
X539761D01*
G01X516102Y405347D02*
X518352D01*
G01X522861D02*
X525111D01*
G01X519481Y403396D02*
X521731D01*
G01X543141Y214247D02*
X545391D01*
G01X546521Y216196D02*
X548771D01*
G01X543141Y245447D02*
X545391D01*
G01X543141Y253247D02*
X545391D01*
G01X546521Y259096D02*
X548771D01*
G01X543141Y241547D02*
X545391D01*
G01X546521Y247396D02*
X548771D01*
G01X543141Y249347D02*
X545391D01*
G01X543141Y257147D02*
X545391D01*
G01X543141Y261047D02*
X545391D01*
G01X543141Y229847D02*
X545391D01*
G01X546521Y231797D02*
X548771D01*
G01X560041Y223996D02*
X562616D01*
G01X553281Y259096D02*
X555531D01*
G01X553281Y266896D02*
X555531D01*
G01X556661Y268847D02*
X558911D01*
G01X549901D02*
X552151D01*
G01X549901Y276646D02*
X552151D01*
G01X553281Y278596D02*
X555531D01*
G01X560041Y231797D02*
X562578D01*
X562640Y231735D01*
G01X564774Y233220D02*
X565453D01*
X568779Y229894D01*
X569525D01*
X570404Y229015D01*
G01X565176Y238158D02*
X571166D01*
X576405Y232919D01*
X577022D01*
X577832Y233729D01*
G01X553281Y243496D02*
X555531D01*
G01X549901Y253247D02*
X552151D01*
G01X556661Y249347D02*
X558911D01*
G01X556661Y257147D02*
X558911D01*
G01X556661Y225947D02*
X558911D01*
G01X553281Y262996D02*
X555531D01*
G01X549901Y264947D02*
X552151D01*
G01X553281Y270796D02*
X555531D01*
G01X549901Y272747D02*
X552151D01*
G01X546521Y274696D02*
X548771D01*
G01X560041Y227896D02*
X562630D01*
G01X564693Y234170D02*
X565847D01*
X569173Y230844D01*
X569829D01*
X570528Y231543D01*
G01X565176Y237208D02*
X570772D01*
X576011Y231969D01*
X576999D01*
X577849Y231119D01*
G01X556661Y241547D02*
X558911D01*
G01X553281Y251296D02*
X555531D01*
G01X556661Y253247D02*
X558911D01*
G01X553281Y255196D02*
X555531D01*
G01X553281Y227896D02*
X555531D01*
G01X553281Y220096D02*
X555531D01*
G01X546521D02*
X548771D01*
G01X543141Y218147D02*
X545391D01*
G01X553281Y223996D02*
X555531D01*
G01X549901Y222047D02*
X552151D01*
G01X546521Y223996D02*
X548771D01*
G01X543141Y284447D02*
X545391D01*
G01X553281Y282496D02*
X555531D01*
G01X553281Y290296D02*
Y289640D01*
X554100Y288821D01*
X556558D01*
X557099Y289362D01*
X559950D01*
X560884Y290296D01*
G01X553281Y294196D02*
X555831D01*
G01X549901Y280547D02*
X552151D01*
G01X556661Y284447D02*
X559211D01*
G01X553281Y286396D02*
X554756Y287871D01*
X556952D01*
X557493Y288412D01*
X558868D01*
X560884Y286396D01*
G01X549901Y292247D02*
X552151Y292245D01*
G01X543141Y378047D02*
X545391D01*
G01X549901Y374146D02*
X552151D01*
G01X543141D02*
X545391D01*
G01X546521Y364396D02*
X548771D01*
G01X546521Y360496D02*
X548771D01*
G01X546521Y356596D02*
X548771D01*
G01X546521Y383896D02*
X548771D01*
G01X546521Y376096D02*
X548771D01*
G01X546521Y372197D02*
X546522Y372196D01*
X548771D01*
G01X543141Y370247D02*
X545391D01*
G01X543141Y362447D02*
X545391D01*
G01X549901Y358547D02*
X552151D01*
G01X546521Y352696D02*
X548771D01*
G01X543141Y381947D02*
X545391D01*
G01X546521Y379996D02*
X548771D01*
G01X581748Y651236D02*
X580325Y649813D01*
X569454D01*
X567029Y652238D01*
G01X581748Y647296D02*
X580381Y648663D01*
X569454D01*
X567029Y646238D01*
G01X640500Y332000D02*
Y333686D01*
X640050Y334136D01*
X638187D01*
X637681Y333630D01*
Y332390D01*
G01X640500Y337000D02*
Y335650D01*
X640050Y335200D01*
X638199D01*
X637681Y335718D01*
Y337390D01*
G01X662097Y335948D02*
Y337483D01*
X662430Y337816D01*
Y338625D01*
X661149Y339906D01*
Y341350D01*
X660499Y342000D01*
X659000D01*
G01X664066Y335948D02*
Y337514D01*
X663380Y338200D01*
Y339019D01*
X662099Y340300D01*
Y341530D01*
X662569Y342000D01*
X664000D01*
G01X654221Y335948D02*
Y337221D01*
X654558Y337558D01*
Y338362D01*
X653970Y338950D01*
X652150D01*
X650996Y340104D01*
Y341404D01*
X650400Y342000D01*
X649000D01*
G01X656190Y335948D02*
Y337210D01*
X655508Y337892D01*
Y338756D01*
X654364Y339900D01*
X652544D01*
X651946Y340498D01*
Y341390D01*
X652556Y342000D01*
X654000D01*
G01X649819Y329578D02*
X649241Y330156D01*
X647428D01*
X646034Y331550D01*
Y333547D01*
X645473Y334108D01*
X644521D01*
X644000Y333587D01*
Y332000D01*
G01X649819Y331547D02*
X649378Y331106D01*
X647822D01*
X646984Y331944D01*
Y333941D01*
X645867Y335058D01*
X644557D01*
X644000Y335615D01*
Y337000D01*
G01X649819Y303981D02*
X647725D01*
X647412Y304294D01*
X644928D01*
X644000Y303366D01*
Y302000D01*
G01X649819Y305950D02*
X647724D01*
X647018Y305244D01*
X644450D01*
X644000Y305694D01*
Y307000D01*
G01X637600Y302000D02*
Y303624D01*
X638026Y304050D01*
X638450D01*
X640500Y302000D01*
G01X637600Y307000D02*
Y305499D01*
X638099Y305000D01*
X638500D01*
X640500Y307000D01*
G01X659694Y351206D02*
X660274D01*
X661170Y350310D01*
Y346700D01*
X659970Y345500D01*
X659000D01*
G01X664194Y351206D02*
X663176D01*
X662120Y350150D01*
Y346700D01*
X663320Y345500D01*
X664000D01*
G01X649194Y351206D02*
X650382D01*
X651124Y350464D01*
Y346261D01*
X650363Y345500D01*
X649000D01*
G01X654194Y351206D02*
X652816D01*
X652074Y350464D01*
Y346158D01*
X652732Y345500D01*
X654000D01*
G01X897391Y651215D02*
X895896Y649748D01*
X893882D01*
X889533Y650085D01*
X884204Y649193D01*
X882061Y646557D01*
X881724Y644648D01*
X881204Y644285D01*
X879785Y644535D01*
X879420Y645055D01*
X880946Y653710D01*
X880129Y654876D01*
X877935Y655261D01*
X876767Y654444D01*
X875058Y644743D01*
X874538Y644379D01*
X873120Y644629D01*
X872756Y645150D01*
X874266Y653721D01*
X873451Y654890D01*
X871257Y655275D01*
X870089Y654458D01*
X868377Y644741D01*
X867857Y644377D01*
X866438Y644627D01*
X866073Y645146D01*
X867570Y653640D01*
X866755Y654807D01*
X864559Y655191D01*
X863391Y654376D01*
X861693Y644729D01*
X861173Y644364D01*
X859755Y644614D01*
X859391Y645135D01*
X860885Y653618D01*
X860070Y654787D01*
X857876Y655172D01*
X856708Y654355D01*
X855014Y644735D01*
X854494Y644371D01*
X853074Y644619D01*
X852710Y645139D01*
X854207Y653634D01*
X853390Y654800D01*
X851198Y655185D01*
X850029Y654370D01*
X848320Y644668D01*
X847801Y644305D01*
X846381Y644553D01*
X846017Y645073D01*
X847522Y653614D01*
X846705Y654780D01*
X844512Y655165D01*
X843344Y654348D01*
X841640Y644676D01*
X841107Y644303D01*
X839711Y644549D01*
X839335Y645084D01*
X840842Y653636D01*
X840026Y654803D01*
X837834Y655188D01*
X836665Y654371D01*
X834957Y644662D01*
X834437Y644298D01*
X833016Y644548D01*
X832653Y645068D01*
X834161Y653635D01*
X833344Y654801D01*
X831153Y655185D01*
X829984Y654368D01*
X828280Y644695D01*
X827760Y644331D01*
X826340Y644580D01*
X825975Y645102D01*
X827477Y653619D01*
X826662Y654788D01*
X824469Y655173D01*
X823301Y654356D01*
X822311Y648746D01*
X821590Y644662D01*
X821070Y644298D01*
X819650Y644546D01*
X819286Y645066D01*
X820800Y653658D01*
X819983Y654824D01*
X817791Y655209D01*
X816622Y654394D01*
X814896Y644595D01*
X814377Y644232D01*
X812957Y644480D01*
X812593Y645000D01*
X814115Y653638D01*
X813298Y654804D01*
X811105Y655189D01*
X809937Y654372D01*
X808216Y644603D01*
X807683Y644230D01*
X806287Y644476D01*
X805911Y645011D01*
X807435Y653660D01*
X806619Y654827D01*
X804427Y655212D01*
X803258Y654395D01*
X801550Y644686D01*
X801030Y644322D01*
X799609Y644572D01*
X799246Y645092D01*
X800754Y653659D01*
X799937Y654825D01*
X797746Y655209D01*
X796577Y654392D01*
X794855Y644603D01*
X794332Y644237D01*
X792915Y644486D01*
X792550Y645007D01*
X794072Y653641D01*
X793243Y654820D01*
X791072Y655203D01*
X789894Y654378D01*
X788173Y644609D01*
X787650Y644243D01*
X786232Y644492D01*
X785867Y645013D01*
X787389Y653651D01*
X786573Y654816D01*
X784379Y655201D01*
X783214Y654386D01*
X781488Y644588D01*
X780965Y644223D01*
X779547Y644472D01*
X779182Y644993D01*
X780696Y653585D01*
X779880Y654750D01*
X777686Y655135D01*
X776520Y654319D01*
X774812Y644619D01*
X774289Y644253D01*
X772872Y644502D01*
X772507Y645025D01*
X774016Y653589D01*
X773200Y654755D01*
X771006Y655141D01*
X769841Y654325D01*
X768143Y644679D01*
X767620Y644314D01*
X766200Y644562D01*
X765836Y645083D01*
X767333Y653578D01*
X766517Y654742D01*
X764323Y655129D01*
X763157Y654313D01*
X761445Y644596D01*
X760922Y644230D01*
X759505Y644479D01*
X759140Y645002D01*
X760651Y653574D01*
X759835Y654740D01*
X757641Y655127D01*
X756476Y654311D01*
X754767Y644610D01*
X754247Y644247D01*
X752828Y644497D01*
X752463Y645017D01*
X753989Y653672D01*
X753172Y654838D01*
X750978Y655223D01*
X749810Y654406D01*
X748101Y644705D01*
X747581Y644341D01*
X746163Y644591D01*
X745799Y645112D01*
X747309Y653683D01*
X746494Y654852D01*
X744300Y655237D01*
X743132Y654420D01*
X741420Y644703D01*
X740900Y644339D01*
X739481Y644589D01*
X739116Y645108D01*
X740613Y653602D01*
X739798Y654769D01*
X737602Y655153D01*
X736434Y654338D01*
X734736Y644691D01*
X734216Y644326D01*
X732798Y644576D01*
X732434Y645097D01*
X733928Y653580D01*
X733113Y654749D01*
X730919Y655134D01*
X729751Y654317D01*
X728057Y644697D01*
X727537Y644333D01*
X726117Y644581D01*
X725753Y645101D01*
X727250Y653596D01*
X726433Y654762D01*
X724241Y655147D01*
X723072Y654332D01*
X721363Y644630D01*
X720844Y644267D01*
X719424Y644515D01*
X719060Y645035D01*
X720565Y653576D01*
X719748Y654742D01*
X717555Y655127D01*
X716387Y654310D01*
X714683Y644638D01*
X714150Y644265D01*
X712754Y644511D01*
X712378Y645046D01*
X713885Y653598D01*
X713069Y654765D01*
X710877Y655150D01*
X709708Y654333D01*
X708000Y644624D01*
X707480Y644260D01*
X706059Y644510D01*
X705696Y645030D01*
X707204Y653597D01*
X706387Y654763D01*
X704196Y655147D01*
X703027Y654330D01*
X701323Y644657D01*
X700803Y644293D01*
X699383Y644542D01*
X699018Y645064D01*
X700520Y653581D01*
X699705Y654750D01*
X697512Y655135D01*
X696344Y654318D01*
X695564Y649900D01*
X694644Y644687D01*
X694121Y644321D01*
X692705Y644570D01*
X692340Y645093D01*
X693842Y653611D01*
X693025Y654778D01*
X690830Y655163D01*
X689665Y654348D01*
X687961Y644675D01*
X687437Y644309D01*
X686021Y644557D01*
X685656Y645078D01*
X687164Y653644D01*
X686351Y654810D01*
X684153Y655196D01*
X682988Y654381D01*
X681280Y644672D01*
X680757Y644306D01*
X679340Y644555D01*
X678975Y645076D01*
X680483Y653630D01*
X679654Y654809D01*
X677483Y655192D01*
X676305Y654367D01*
X674601Y644695D01*
X674078Y644329D01*
X672660Y644578D01*
X672295Y645099D01*
X673800Y653640D01*
X672984Y654805D01*
X670790Y655190D01*
X669625Y654375D01*
X667916Y644674D01*
X667393Y644309D01*
X665975Y644558D01*
X665610Y645079D01*
X667107Y653574D01*
X666291Y654739D01*
X664097Y655124D01*
X662931Y654308D01*
X661237Y644688D01*
X660714Y644322D01*
X659297Y644571D01*
X658932Y645094D01*
X660427Y653578D01*
X659611Y654744D01*
X657417Y655130D01*
X656252Y654314D01*
X654554Y644668D01*
X654031Y644303D01*
X652611Y644551D01*
X652247Y645072D01*
X653744Y653567D01*
X652928Y654731D01*
X650734Y655118D01*
X649568Y654302D01*
X647856Y644585D01*
X647333Y644219D01*
X645916Y644468D01*
X645551Y644991D01*
X647062Y653563D01*
X646246Y654729D01*
X644052Y655116D01*
X642887Y654300D01*
X641178Y644599D01*
X640655Y644233D01*
X639236Y644482D01*
X638871Y645003D01*
X640397Y653658D01*
X639581Y654823D01*
X637387Y655209D01*
X636221Y654396D01*
X635859Y652341D01*
X634098Y650175D01*
X629238Y649362D01*
X624968Y649692D01*
X622917D01*
X621422Y651215D01*
G01X897391Y647275D02*
X895896Y648798D01*
X893845D01*
X889575Y649128D01*
X884715Y648315D01*
X882954Y646149D01*
X882592Y644094D01*
X881426Y643281D01*
X879232Y643667D01*
X878416Y644832D01*
X879942Y653487D01*
X879577Y654008D01*
X878158Y654257D01*
X877635Y653891D01*
X875926Y644190D01*
X874761Y643374D01*
X872567Y643761D01*
X871751Y644927D01*
X873262Y653499D01*
X872897Y654022D01*
X871480Y654271D01*
X870957Y653905D01*
X869245Y644188D01*
X868079Y643372D01*
X865885Y643759D01*
X865069Y644923D01*
X866566Y653418D01*
X866202Y653939D01*
X864782Y654187D01*
X864259Y653822D01*
X862561Y644176D01*
X861396Y643360D01*
X859202Y643746D01*
X858386Y644912D01*
X859881Y653396D01*
X859516Y653919D01*
X858099Y654168D01*
X857576Y653802D01*
X855882Y644182D01*
X854716Y643366D01*
X852522Y643751D01*
X851706Y644916D01*
X853203Y653411D01*
X852838Y653932D01*
X851420Y654181D01*
X850897Y653816D01*
X849188Y644115D01*
X848023Y643300D01*
X845829Y643685D01*
X845013Y644850D01*
X846518Y653391D01*
X846153Y653912D01*
X844735Y654161D01*
X844212Y653795D01*
X842508Y644123D01*
X841330Y643298D01*
X839159Y643681D01*
X838330Y644860D01*
X839838Y653414D01*
X839473Y653935D01*
X838056Y654184D01*
X837533Y653818D01*
X835825Y644109D01*
X834660Y643294D01*
X832462Y643680D01*
X831649Y644846D01*
X833157Y653412D01*
X832792Y653933D01*
X831376Y654181D01*
X830852Y653815D01*
X829148Y644142D01*
X827983Y643327D01*
X825788Y643712D01*
X824971Y644879D01*
X826473Y653397D01*
X826108Y653920D01*
X824692Y654169D01*
X824169Y653803D01*
X823465Y649816D01*
X822458Y644109D01*
X821292Y643293D01*
X819098Y643678D01*
X818282Y644843D01*
X819796Y653435D01*
X819431Y653956D01*
X818013Y654205D01*
X817490Y653840D01*
X815764Y644042D01*
X814599Y643227D01*
X812405Y643612D01*
X811589Y644777D01*
X813111Y653415D01*
X812746Y653936D01*
X811328Y654185D01*
X810805Y653819D01*
X809084Y644050D01*
X807906Y643225D01*
X805735Y643608D01*
X804906Y644787D01*
X806431Y653438D01*
X806066Y653959D01*
X804649Y654208D01*
X804126Y653842D01*
X802418Y644133D01*
X801253Y643318D01*
X799055Y643704D01*
X798242Y644870D01*
X799750Y653436D01*
X799385Y653957D01*
X797969Y654205D01*
X797445Y653839D01*
X795723Y644050D01*
X794554Y643233D01*
X792362Y643618D01*
X791546Y644785D01*
X793067Y653417D01*
X792691Y653952D01*
X791295Y654198D01*
X790762Y653825D01*
X789041Y644056D01*
X787873Y643239D01*
X785680Y643624D01*
X784863Y644790D01*
X786385Y653428D01*
X786021Y653948D01*
X784601Y654196D01*
X784082Y653833D01*
X782356Y644034D01*
X781187Y643219D01*
X778995Y643604D01*
X778178Y644770D01*
X779692Y653362D01*
X779328Y653882D01*
X777908Y654130D01*
X777388Y653766D01*
X775680Y644066D01*
X774512Y643249D01*
X772318Y643634D01*
X771503Y644803D01*
X773011Y653366D01*
X772647Y653887D01*
X771229Y654137D01*
X770709Y653772D01*
X769011Y644125D01*
X767843Y643310D01*
X765647Y643694D01*
X764832Y644861D01*
X766329Y653355D01*
X765964Y653874D01*
X764545Y654124D01*
X764025Y653760D01*
X762313Y644043D01*
X761145Y643226D01*
X758951Y643611D01*
X758136Y644780D01*
X759646Y653351D01*
X759282Y653872D01*
X757864Y654122D01*
X757344Y653758D01*
X755635Y644057D01*
X754469Y643243D01*
X752275Y643629D01*
X751459Y644794D01*
X752985Y653449D01*
X752620Y653970D01*
X751201Y654219D01*
X750678Y653853D01*
X748969Y644152D01*
X747804Y643336D01*
X745610Y643723D01*
X744794Y644889D01*
X746305Y653461D01*
X745940Y653984D01*
X744523Y654233D01*
X744000Y653867D01*
X742288Y644150D01*
X741122Y643334D01*
X738928Y643721D01*
X738112Y644885D01*
X739609Y653380D01*
X739245Y653901D01*
X737825Y654149D01*
X737302Y653784D01*
X735604Y644138D01*
X734439Y643322D01*
X732245Y643708D01*
X731429Y644874D01*
X732924Y653358D01*
X732559Y653881D01*
X731142Y654130D01*
X730619Y653764D01*
X728925Y644144D01*
X727759Y643328D01*
X725565Y643713D01*
X724749Y644878D01*
X726246Y653373D01*
X725881Y653894D01*
X724463Y654143D01*
X723940Y653778D01*
X722231Y644077D01*
X721066Y643262D01*
X718872Y643647D01*
X718056Y644812D01*
X719561Y653353D01*
X719196Y653874D01*
X717778Y654123D01*
X717255Y653757D01*
X715551Y644085D01*
X714373Y643260D01*
X712202Y643643D01*
X711373Y644822D01*
X712881Y653376D01*
X712516Y653897D01*
X711099Y654146D01*
X710576Y653780D01*
X708868Y644071D01*
X707703Y643256D01*
X705505Y643642D01*
X704692Y644808D01*
X706200Y653374D01*
X705835Y653895D01*
X704419Y654143D01*
X703895Y653777D01*
X702191Y644104D01*
X701026Y643289D01*
X698831Y643674D01*
X698014Y644841D01*
X699516Y653359D01*
X699151Y653882D01*
X697735Y654131D01*
X697212Y653765D01*
X695512Y644134D01*
X694344Y643317D01*
X692151Y643702D01*
X691336Y644871D01*
X692838Y653388D01*
X692473Y653910D01*
X691053Y654159D01*
X690533Y653795D01*
X688829Y644122D01*
X687660Y643305D01*
X685469Y643689D01*
X684652Y644855D01*
X686160Y653422D01*
X685797Y653942D01*
X684376Y654192D01*
X683856Y653828D01*
X682148Y644119D01*
X680979Y643302D01*
X678787Y643687D01*
X677971Y644854D01*
X679478Y653406D01*
X679102Y653941D01*
X677706Y654187D01*
X677173Y653814D01*
X675469Y644142D01*
X674301Y643325D01*
X672108Y643710D01*
X671291Y644876D01*
X672796Y653417D01*
X672432Y653937D01*
X671012Y654185D01*
X670493Y653822D01*
X668784Y644120D01*
X667615Y643305D01*
X665423Y643690D01*
X664606Y644856D01*
X666103Y653351D01*
X665739Y653871D01*
X664319Y654119D01*
X663799Y653755D01*
X662105Y644135D01*
X660937Y643318D01*
X658743Y643703D01*
X657928Y644872D01*
X659422Y653355D01*
X659058Y653876D01*
X657640Y654126D01*
X657120Y653761D01*
X655422Y644114D01*
X654254Y643299D01*
X652058Y643683D01*
X651243Y644850D01*
X652740Y653344D01*
X652375Y653863D01*
X650956Y654113D01*
X650436Y653749D01*
X648724Y644032D01*
X647556Y643215D01*
X645362Y643600D01*
X644547Y644769D01*
X646057Y653340D01*
X645693Y653861D01*
X644275Y654111D01*
X643755Y653747D01*
X642046Y644046D01*
X640878Y643229D01*
X638684Y643614D01*
X637867Y644780D01*
X639393Y653435D01*
X639028Y653955D01*
X637609Y654205D01*
X637089Y653842D01*
X636752Y651933D01*
X634609Y649297D01*
X629280Y648405D01*
X624931Y648742D01*
X622917D01*
X621422Y647275D01*
G01X697120Y305349D02*
Y304721D01*
X695799Y303400D01*
X694488D01*
X694000Y303888D01*
Y305500D01*
G01X697120Y300349D02*
Y301229D01*
X695899Y302450D01*
X694519D01*
X694000Y301931D01*
Y300500D01*
G01X701000Y315500D02*
X702850Y313650D01*
X703838D01*
X704404Y314216D01*
Y315875D01*
G01X701000Y319000D02*
Y315500D01*
G01Y307000D02*
Y310500D01*
G01X704404Y310875D02*
Y312234D01*
X703938Y312700D01*
X703050D01*
X701000Y310650D01*
Y310500D01*
G01X694000Y325500D02*
Y323888D01*
X694413Y323475D01*
X697131D01*
X697521Y323865D01*
Y325500D01*
G01X694000Y320500D02*
Y322042D01*
X694483Y322525D01*
X697131D01*
X697521Y322135D01*
Y320500D01*
G01X684219Y305950D02*
X685469D01*
X685981Y305438D01*
X686981D01*
X688950Y303469D01*
X689977D01*
X690500Y303992D01*
Y305500D01*
G01X684219Y303981D02*
X685504D01*
X686011Y304488D01*
X686587D01*
X688556Y302519D01*
X689973D01*
X690500Y301992D01*
Y300500D01*
G01X684219Y313826D02*
X686313D01*
X686823Y313316D01*
X693962D01*
G01D02*
X695316D01*
X697500Y315500D01*
G01X684219Y311857D02*
X686314D01*
X686823Y312366D01*
X689000D01*
G01D02*
X695634D01*
X697500Y310500D01*
G01X684219Y323671D02*
X686417D01*
X686670Y323418D01*
X689790D01*
X690500Y324128D01*
Y325500D01*
G01X684219Y321702D02*
X685904D01*
X686670Y322468D01*
X689372D01*
X690500Y321340D01*
Y320500D01*
G01X669973Y335948D02*
Y337908D01*
X670514Y338449D01*
Y339393D01*
X671034Y339913D01*
Y340937D01*
X669971Y342000D01*
X669000D01*
G01X671942Y335948D02*
Y337930D01*
X671464Y338408D01*
Y338999D01*
X671984Y339519D01*
Y340937D01*
X673047Y342000D01*
X674000D01*
G01X669194Y351206D02*
X670042D01*
X671159Y350089D01*
Y346296D01*
X670363Y345500D01*
X669000D01*
G01X674194Y351206D02*
X673124D01*
X672109Y350191D01*
Y346141D01*
X672750Y345500D01*
X674000D01*
G01X679194Y351206D02*
X680340D01*
X681159Y350387D01*
Y346396D01*
X680263Y345500D01*
X679000D01*
G01X684000D02*
X682850D01*
X682009Y346341D01*
Y350407D01*
X682808Y351206D01*
X684194D01*
G01X1107118Y-42431D02*
X914200D01*
G03Y-46181I0J-1875D01*
G01X1108550D01*
G02Y-51831I0J-2825D01*
G01X910187D01*
X905888Y-47532D01*
X803509D01*
X798984Y-52057D01*
G01X1107118Y-41481D02*
X914200D01*
G03Y-47131I0J-2825D01*
G01X1108549D01*
G02Y-50881I0J-1875D01*
G01X910581D01*
X906282Y-46582D01*
X803509D01*
X798984Y-42057D01*
G01X937076Y651204D02*
X938471Y649809D01*
X949370D01*
X951795Y652234D01*
G01X937076Y647264D02*
X938471Y648659D01*
X949370D01*
X951795Y646234D01*
G01X1142050Y216196D02*
X1144300D01*
G01X1142050Y212296D02*
X1144300D01*
G01X1152190Y214247D02*
X1154440D01*
G01X1155570Y216196D02*
X1157820D01*
G01X1145430Y214247D02*
X1147680D01*
G01X1148810Y216196D02*
X1151060D01*
G01X1134160Y272747D02*
X1131910D01*
G01X1134160Y276646D02*
X1131910D01*
G01X1145430Y218147D02*
X1147680D01*
G01X1148810Y220096D02*
X1151060D01*
G01X1142050D02*
X1144300D01*
G01X1152190Y218147D02*
X1154440D01*
G01X1152190Y222047D02*
X1154440D01*
G01X1148810Y243496D02*
X1151060D01*
G01X1142050Y239596D02*
X1144300D01*
G01X1148810Y235696D02*
X1151060D01*
G01X1142050Y227896D02*
X1144300D01*
G01X1152190Y233746D02*
X1154440D01*
G01X1145430Y229847D02*
X1147680D01*
G01X1152190Y237647D02*
X1154440D01*
G01X1155570Y227896D02*
X1157820D01*
G01X1145430Y241547D02*
X1147680D01*
G01X1145430Y237647D02*
X1147680D01*
G01X1148810Y239596D02*
X1151060D01*
G01X1142050Y231797D02*
X1144300D01*
G01X1148810D02*
X1151060D01*
G01X1148810Y227896D02*
X1151060D01*
G01X1155570Y235696D02*
X1157820D01*
G01X1130780Y282496D02*
X1128530D01*
G01X1130780Y286396D02*
X1128530D01*
G01X1127400Y346847D02*
X1125150D01*
G01X1124021Y344896D02*
X1121771D01*
G01X1130780Y348796D02*
X1128530D01*
G01X1127400Y350747D02*
X1125150D01*
G01X1152190Y397546D02*
X1154440D01*
G01X1152190Y393647D02*
X1154440D01*
G01X1148810Y387796D02*
X1151060D01*
G01X1155570Y395597D02*
X1157820D01*
G01X1152190Y389747D02*
X1154440D01*
G01X1155570Y391696D02*
X1157820D01*
G01X1152190Y385847D02*
X1154440D01*
G01X1179229Y214247D02*
X1181479D01*
G01X1175849Y212296D02*
X1178099D01*
G01X1182609Y208397D02*
X1184859D01*
G01X1189369Y216196D02*
X1191619D01*
G01X1194999Y214247D02*
X1192749D01*
G01X1162330Y212296D02*
X1164580D01*
G01X1162330Y208397D02*
X1164580D01*
G01X1167960Y214247D02*
X1165710D01*
G01X1172469Y210346D02*
X1174719D01*
G01X1182609Y216196D02*
X1184859D01*
G01X1179229Y210346D02*
X1181479D01*
G01X1182609Y212296D02*
X1184859D01*
G01X1189369D02*
X1191619D01*
G01X1196129Y216196D02*
X1198379D01*
G01X1158950Y214247D02*
X1161200D01*
G01X1162330Y216196D02*
X1164580D01*
G01X1167960Y210346D02*
X1165710D01*
G01X1169089Y212296D02*
X1171339D01*
G01X1172469Y214247D02*
X1174719D01*
G01X1288111Y199713D02*
X1272527Y211880D01*
X1264417Y223671D01*
X1245777Y250774D01*
X1231749Y260500D01*
X1211373Y289058D01*
G01X1202889Y255196D02*
X1205139D01*
G01X1206269Y249347D02*
X1208519D01*
G01X1199509Y253247D02*
X1201759D01*
G01X1202889Y243496D02*
X1205139D01*
G01X1209649Y239596D02*
X1212199D01*
G01X1202889Y235696D02*
X1205139D01*
G01X1209649Y227896D02*
X1212199D01*
G01X1206269Y225947D02*
X1208519D01*
G01X1196129Y274696D02*
X1198379D01*
G01X1199509Y272747D02*
X1201759D01*
G01X1202889Y270796D02*
X1205139D01*
G01X1199509Y264947D02*
X1201759D01*
G01X1202889Y262996D02*
X1205139D01*
G01X1206269Y257147D02*
X1208519D01*
G01X1206269Y253247D02*
X1208519D01*
G01X1202889Y251296D02*
X1205139D01*
G01X1206269Y241547D02*
X1208519D01*
G01X1206269Y237647D02*
X1208519D01*
G01X1202889Y239596D02*
X1205139D01*
G01X1209649Y231797D02*
X1212199D01*
G01X1209649Y223996D02*
X1212199D01*
G01X1202889Y278596D02*
X1205139D01*
G01X1199509Y276646D02*
X1201759D01*
G01X1199509Y268847D02*
X1201759D01*
G01X1206269D02*
X1208519D01*
G01X1202889Y266896D02*
X1205139D01*
G01X1202889Y259096D02*
X1205139D01*
G01X1182609Y220096D02*
X1184859D01*
G01X1194999Y218147D02*
X1192749D01*
G01X1196129Y220096D02*
X1198379D01*
G01X1199509Y222047D02*
X1201759D01*
G01X1202889Y223996D02*
X1205139D01*
G01X1185989Y218147D02*
X1188239D01*
G01X1189369Y220096D02*
X1191619D01*
G01X1196129Y223996D02*
X1198379D01*
G01X1202889Y220096D02*
X1205139D01*
G01X1202889Y227896D02*
X1205139D01*
G01X1182609Y262996D02*
X1184859D01*
G01X1189369Y259096D02*
X1191619D01*
G01X1194999Y261047D02*
X1192749D01*
G01X1194999Y257147D02*
X1192749D01*
G01X1185989Y253247D02*
X1188239D01*
G01X1194999Y249347D02*
X1192749D01*
G01X1196129Y247396D02*
X1198379D01*
G01X1189369Y243496D02*
X1191619D01*
G01X1185989Y241547D02*
X1188239D01*
G01X1179229Y245447D02*
X1181479D01*
G01X1182609Y278596D02*
X1184859D01*
G01X1185989Y276646D02*
X1188239D01*
G01X1179229Y272747D02*
X1181479D01*
G01X1185989Y268847D02*
X1188239D01*
G01X1189369Y266896D02*
X1191619D01*
G01X1185989Y261047D02*
X1188239D01*
G01X1189369Y262996D02*
X1191619D01*
G01X1196129Y259096D02*
X1198379D01*
G01X1189369Y255196D02*
X1191619D01*
G01X1189369Y251296D02*
X1191619D01*
G01X1194999Y253247D02*
X1192749D01*
G01X1194999Y245447D02*
X1192749D01*
G01X1194999Y241547D02*
X1192749D01*
G01X1185989Y245447D02*
X1188239D01*
G01X1182609Y243496D02*
X1184859D01*
G01X1182609Y274696D02*
X1184859D01*
G01X1189369Y278596D02*
X1191619D01*
G01X1182609Y270796D02*
X1184859D01*
G01X1185989Y272747D02*
X1188239D01*
G01X1185989Y264947D02*
X1188239D01*
G01X1172469Y229847D02*
X1174719D01*
G01X1167960Y225947D02*
X1165710D01*
G01X1172469Y222047D02*
X1174719D01*
G01X1172469Y233746D02*
X1174719D01*
G01X1179229Y229847D02*
X1181479D01*
G01X1182609Y227896D02*
X1184859D01*
G01X1182609Y231797D02*
X1184859D01*
G01X1189369Y235696D02*
X1191619D01*
G01X1189369Y227896D02*
X1191619D01*
G01X1196129Y231797D02*
X1198379D01*
G01X1158950Y233746D02*
X1161200D01*
G01X1158950Y229847D02*
X1161200D01*
G01X1169089Y227896D02*
X1171339D01*
G01X1169089Y223996D02*
X1171339D01*
G01X1172469Y225947D02*
X1174719D01*
G01X1175849Y231797D02*
X1178099D01*
G01X1179229Y233746D02*
X1181479D01*
G01X1179229Y225947D02*
X1181479D01*
G01X1185989Y229847D02*
X1188239D01*
G01X1185989Y233746D02*
X1188239D01*
G01X1189369Y231797D02*
X1191619D01*
G01X1194999Y229847D02*
X1192749D01*
G01X1158950Y237647D02*
X1161200D01*
G01X1158950Y225947D02*
X1161200D01*
G01X1162330Y231797D02*
X1164580D01*
G01X1182609Y337096D02*
X1184859D01*
G01X1175849Y340996D02*
X1178099D01*
G01X1179229Y339047D02*
X1181479D01*
G01X1199509Y331247D02*
X1201759D01*
G01Y335147D02*
X1199509D01*
G01X1198379Y333196D02*
X1196129D01*
G01X1199509Y339047D02*
X1201759D01*
G01X1202889Y340996D02*
X1205139D01*
G01X1214187Y315321D02*
X1215879D01*
X1228180Y303020D01*
X1250153Y272934D01*
X1267572Y260446D01*
X1292458Y224263D01*
X1316231Y205501D01*
G01X1216558Y308192D02*
X1242549Y271749D01*
X1264479Y256545D01*
X1284290Y227739D01*
G01X1215414Y304832D02*
X1240529Y269623D01*
X1245946Y265866D01*
G01X1303646Y199358D02*
Y199360D01*
X1280372Y217533D01*
X1254369Y255341D01*
X1237776Y266846D01*
X1214071Y300076D01*
G01X1210425Y296996D02*
X1234456Y263307D01*
X1234457D01*
X1248582Y253512D01*
X1274395Y215981D01*
X1274396D01*
X1296586Y198653D01*
G01X1279928Y207308D02*
X1273225Y212542D01*
X1265200Y224210D01*
X1246461Y251456D01*
X1232428Y261186D01*
X1212147Y289609D01*
G01X1261972Y300150D02*
Y300151D01*
X1244103Y325826D01*
X1217524Y339521D01*
X1211124D01*
X1209649Y340996D01*
G01X1265720Y287844D02*
X1241026Y323115D01*
X1216749Y335621D01*
X1214220D01*
G01X1253964Y297498D02*
X1237432Y320685D01*
X1219835Y329750D01*
X1207766D01*
X1206269Y331247D01*
G01X1254493Y290195D02*
X1234863Y317726D01*
X1219055Y325871D01*
X1213164D01*
G01X1216206Y321971D02*
X1218263D01*
X1230643Y315597D01*
Y315596D01*
X1257566Y277839D01*
X1277195Y264229D01*
X1309200Y221511D01*
X1318085Y214375D01*
X1323431Y212626D01*
X1327598Y213460D01*
X1331799Y212620D01*
X1339799Y214220D01*
X1346850Y212810D01*
X1357254Y214891D01*
X1360253Y214274D01*
G01X1217322Y317800D02*
X1218199D01*
X1229784Y309521D01*
X1236150Y300592D01*
G01X1214187Y314371D02*
X1215485D01*
X1227456Y302400D01*
X1246891Y275788D01*
X1246793Y275159D01*
X1247589Y274069D01*
X1248218Y273971D01*
X1249475Y272250D01*
X1266883Y259771D01*
X1291756Y223606D01*
X1293820Y221977D01*
G01X1217332Y308743D02*
X1243227Y272436D01*
X1265163Y257227D01*
X1267805Y253386D01*
G01X1214640Y304281D02*
X1239851Y268936D01*
X1254526Y258759D01*
G01X1213297Y299525D02*
X1237098Y266159D01*
X1253685Y254659D01*
X1279672Y216874D01*
X1281987Y215066D01*
G01X1286850Y207463D02*
X1275094Y216642D01*
X1273158Y219456D01*
X1249266Y254194D01*
X1235135Y263994D01*
X1211199Y297547D01*
G01X1245219Y322557D02*
X1243457Y325089D01*
X1217293Y338571D01*
X1211124D01*
X1209649Y337096D01*
G01X1214220Y334671D02*
X1216518D01*
X1240382Y322378D01*
X1260848Y293146D01*
G01X1248995Y302830D02*
X1236792Y319946D01*
X1219604Y328800D01*
X1207722D01*
X1206269Y327347D01*
G01X1213251Y324921D02*
X1218824D01*
X1234223Y316987D01*
X1237316Y312648D01*
G01X1216119Y321021D02*
X1218032D01*
X1230003Y314857D01*
X1256888Y277152D01*
X1276527Y263536D01*
X1308511Y220845D01*
X1317625Y213525D01*
X1323373Y211645D01*
X1327598Y212491D01*
X1331799Y211651D01*
X1339799Y213251D01*
X1346850Y211841D01*
X1357251Y213921D01*
X1371373Y211018D01*
G01X1252354Y276226D02*
X1229102Y308840D01*
X1217894Y316850D01*
X1217322D01*
G01X1199509Y292247D02*
X1201759D01*
G01X1202889Y290296D02*
X1205439D01*
G01X1202889Y282496D02*
X1205139D01*
G01X1199509Y280547D02*
X1201759D01*
G01X1202889Y294196D02*
X1205439D01*
G01X1202889Y286396D02*
X1205239D01*
X1205439Y286596D01*
G01X1206269Y284447D02*
X1208819D01*
G01X1175849Y282496D02*
X1178099D01*
G01X1182609Y286396D02*
X1184859D01*
G01X1189369D02*
X1191619D01*
G01X1194999Y284447D02*
X1192749D01*
G01X1185989Y280547D02*
X1188239D01*
G01X1179229D02*
X1181479D01*
G01X1179229Y284447D02*
X1181479D01*
G01X1182609Y282496D02*
X1184859D01*
G01X1189369Y290296D02*
X1191619D01*
G01X1189369Y282496D02*
X1191619D01*
G01X1189369Y313696D02*
X1191619D01*
G01X1189369Y309797D02*
X1191619D01*
G01X1185989Y307847D02*
X1188239D01*
G01X1185989Y303947D02*
X1188239D01*
G01X1185989Y300047D02*
X1188239D01*
G01X1182609Y298096D02*
X1184859D01*
G01X1189369Y340996D02*
X1191619D01*
G01X1189369Y337096D02*
X1191619D01*
G01X1185989Y331247D02*
X1188239D01*
G01X1194999Y327347D02*
X1192749D01*
G01X1185989D02*
X1188239D01*
G01X1182609Y317596D02*
X1184859D01*
G01X1189369D02*
X1191619D01*
G01X1194999Y311747D02*
X1192749D01*
G01X1189369Y305896D02*
X1191619D01*
G01X1182609D02*
X1184859D01*
G01X1189369Y301996D02*
X1191619D01*
G01X1185989Y296147D02*
X1188239D01*
G01X1181479D02*
X1179229D01*
G01X1182609Y340996D02*
X1184859D01*
G01X1194999Y339047D02*
X1192749D01*
G01X1189369Y333196D02*
X1191619D01*
G01X1189369Y329296D02*
X1191619D01*
G01X1189369Y325396D02*
X1191619D01*
G01X1185989Y323446D02*
X1188239D01*
G01X1182609Y313696D02*
X1184859D01*
G01X1185989Y315647D02*
X1188239D01*
G01X1172469Y346847D02*
X1174719D01*
G01X1175849Y348796D02*
X1178099D01*
G01X1179229Y342947D02*
X1181479D01*
G01X1175849Y344896D02*
X1178099D01*
G01X1175849Y352696D02*
X1178099D01*
G01X1199509Y342947D02*
X1201759D01*
G01X1196129Y344896D02*
X1198379D01*
G01X1199509Y346847D02*
X1201759D01*
G01X1265488Y322910D02*
X1254610Y338813D01*
X1221815Y355121D01*
X1219459D01*
G01X1264182Y315862D02*
X1250681Y335293D01*
Y335294D01*
X1221366Y349871D01*
G01X1256754Y321327D02*
X1249466Y331804D01*
X1219247Y347338D01*
X1217325D01*
G01X1261585Y307408D02*
X1246617Y328927D01*
X1218242Y343421D01*
X1215187D01*
G01X1260234Y328907D02*
X1253965Y338072D01*
X1221591Y354171D01*
X1219459D01*
G01X1221789Y350722D02*
X1251323Y336036D01*
X1269395Y310026D01*
G01X1251491Y327228D02*
X1248821Y331067D01*
X1219017Y346388D01*
X1217325D01*
G01X1255730Y314160D02*
X1245973Y328189D01*
X1218013Y342471D01*
X1215100D01*
G01X1182609Y348796D02*
X1184859D01*
G01X1182609Y344896D02*
X1184859D01*
G01X1189369D02*
X1191619D01*
G01X1185989Y346847D02*
X1188239D01*
G01X1185989Y342947D02*
X1188239D01*
G01X1175849Y387796D02*
X1178099D01*
G01X1169089D02*
X1171339D01*
G01X1169089Y391696D02*
X1171339D01*
G01X1165710Y393647D02*
X1167960D01*
G01X1162330Y395597D02*
X1164580D01*
G01X1158950Y389747D02*
X1161200D01*
G01X1175849Y379996D02*
X1178099D01*
G01X1175849Y383896D02*
X1178099D01*
G01X1174719Y385847D02*
X1172469D01*
G01X1169089Y383896D02*
X1171339D01*
G01X1172469Y389747D02*
X1174719D01*
G01X1169089Y395597D02*
X1171338D01*
X1171339Y395596D01*
G01X1162330Y391696D02*
X1164580D01*
G01X1162330Y387796D02*
X1164580D01*
G01X1175849Y376096D02*
X1178099D01*
G01X1179229Y381947D02*
X1181479D01*
G01X1211413Y402105D02*
X1219829Y410523D01*
X1229257Y430349D01*
X1260765Y451319D01*
G01X1255969Y462926D02*
X1250528Y457484D01*
X1248482Y456121D01*
X1234444Y446760D01*
X1218264Y415282D01*
X1218458Y414676D01*
X1217841Y413475D01*
X1217235Y413281D01*
X1216618Y412080D01*
X1214737Y410199D01*
G01X1205731Y410530D02*
X1215399Y420200D01*
X1233317Y457297D01*
X1239184Y461227D01*
G01X1201900Y414100D02*
X1213958Y426158D01*
X1230611Y461180D01*
X1230733Y461383D01*
X1248059Y474440D01*
Y474441D01*
G01X1239722Y474778D02*
X1228851Y466582D01*
X1211918Y431262D01*
X1211917D01*
X1204272Y423616D01*
G01X1195153Y420147D02*
X1206187Y431181D01*
X1217335Y454636D01*
X1223252Y467080D01*
X1225284Y468813D01*
G01X1261381Y427008D02*
X1239141Y418117D01*
X1228657Y410780D01*
X1220243Y392342D01*
X1218013Y390850D01*
X1216901D01*
G01X1215447Y394750D02*
X1216221D01*
X1216649Y395036D01*
X1225670Y413549D01*
X1226779Y414319D01*
X1226892Y414945D01*
X1228001Y415715D01*
X1228627Y415602D01*
X1229736Y416372D01*
X1229849Y416998D01*
X1230958Y417768D01*
X1231584Y417655D01*
X1232693Y418425D01*
X1232806Y419051D01*
X1233915Y419821D01*
X1234541Y419708D01*
X1261528Y438443D01*
G01X1212085Y401433D02*
X1220616Y409965D01*
X1230003Y429703D01*
X1242207Y437825D01*
X1242831Y437700D01*
X1243955Y438448D01*
X1244081Y439072D01*
X1245204Y439820D01*
X1245828Y439695D01*
X1246952Y440443D01*
X1247078Y441067D01*
X1253522Y445355D01*
G01X1214065Y410871D02*
X1215841Y412647D01*
X1215840D01*
X1233714Y447419D01*
X1242016Y452953D01*
X1249922Y458223D01*
X1251312Y459613D01*
G01X1254389Y470270D02*
X1234060Y456651D01*
X1216185Y419641D01*
X1212179Y415635D01*
Y414998D01*
X1211225Y414044D01*
X1210588D01*
X1209634Y413089D01*
Y412453D01*
X1208679Y411498D01*
X1208043D01*
X1206403Y409858D01*
G01X1244243Y470374D02*
X1244242D01*
Y470373D01*
X1231453Y460735D01*
X1231451Y460733D01*
X1231450Y460730D01*
X1214746Y425602D01*
X1211943Y422799D01*
Y422162D01*
X1210988Y421208D01*
X1210352D01*
X1202572Y413428D01*
G01X1232141Y467872D02*
X1229608Y465962D01*
X1212705Y430705D01*
X1210036Y428036D01*
Y427400D01*
X1209082Y426445D01*
X1208445D01*
X1207491Y425491D01*
Y424854D01*
X1206536Y423900D01*
X1205900D01*
X1204945Y422945D01*
G01X1195825Y419475D02*
X1206977Y430627D01*
X1207578Y431891D01*
X1208231Y432124D01*
X1208832Y433388D01*
X1208600Y434041D01*
X1224024Y466488D01*
X1234100Y475081D01*
G01X1253042Y422650D02*
X1239596Y417275D01*
X1229414Y410150D01*
X1220996Y391702D01*
X1218302Y389900D01*
X1216901D01*
G01X1215447Y393800D02*
X1216510D01*
X1217391Y394389D01*
X1226416Y412909D01*
X1253007Y431370D01*
G01X1185989Y354647D02*
X1188239D01*
G01X1185989Y358547D02*
X1188239D01*
G01X1185989Y362447D02*
X1188239D01*
G01X1179229D02*
X1181479D01*
G01X1179229Y366347D02*
X1181479D01*
G01X1182609Y372197D02*
X1184859D01*
G01X1182609Y376096D02*
X1184859D01*
G01X1182609Y379996D02*
X1184859D01*
G01X1185989Y350747D02*
X1188239D01*
G01X1189369Y356596D02*
X1191619D01*
G01X1182609Y360496D02*
X1184859D01*
G01X1179229Y358547D02*
X1181479D01*
G01X1182609Y364396D02*
X1184859D01*
G01X1182609Y368296D02*
X1184859D01*
G01X1185989Y374146D02*
X1188239D01*
G01X1179229Y378047D02*
X1181479D01*
G01X1285536Y330531D02*
X1266411Y338395D01*
X1226616Y359491D01*
X1217364D01*
G01X1220316Y363323D02*
X1228690D01*
X1247619Y353586D01*
G01X1217113Y367260D02*
X1230616D01*
X1254441Y355073D01*
G01X1262771Y355220D02*
X1262770D01*
Y355221D01*
X1245174Y364221D01*
X1231644Y371142D01*
X1215721D01*
G01X1221789Y375011D02*
X1232647D01*
X1270621Y355590D01*
G01X1217755Y378772D02*
X1221020D01*
X1228884Y382225D01*
X1239110Y403212D01*
X1243913Y406662D01*
X1248188Y407793D01*
X1260373Y405090D01*
X1281185Y390082D01*
X1282412Y386838D01*
G01X1287176Y385127D02*
X1285817Y388717D01*
X1284347Y392603D01*
X1269301Y403478D01*
X1260688Y409703D01*
X1249610Y412157D01*
X1242228Y410203D01*
X1236029Y405747D01*
X1226023Y385220D01*
X1220007Y382579D01*
X1215795D01*
G01X1291431Y382075D02*
X1286652Y394706D01*
X1262197Y412369D01*
X1249444Y415204D01*
X1241263Y413065D01*
X1233502Y407489D01*
X1223817Y387617D01*
X1218965Y385487D01*
X1216124D01*
G01X1274699Y333959D02*
X1266005Y337534D01*
X1226379Y358541D01*
X1217364D01*
G01X1220316Y362373D02*
X1228459D01*
X1268614Y341717D01*
G01X1265918Y348135D02*
X1230387Y366310D01*
X1217113D01*
G01X1246918Y362262D02*
X1244742Y363375D01*
X1231415Y370192D01*
X1215721D01*
G01X1279501Y350527D02*
X1276464Y351536D01*
X1276463Y351535D01*
X1270188Y354743D01*
X1232416Y374061D01*
X1221789D01*
G01X1217755Y377822D02*
X1221220D01*
X1229586Y381495D01*
X1239859Y402580D01*
X1244325Y405788D01*
X1248208Y406815D01*
X1259976Y404204D01*
X1280397Y389478D01*
X1284195Y379437D01*
G01X1290105Y374700D02*
Y374701D01*
X1284927Y388380D01*
X1283557Y392001D01*
X1275096Y398116D01*
X1260290Y408817D01*
X1249630Y411179D01*
X1242640Y409329D01*
X1236778Y405115D01*
X1226725Y384490D01*
X1220207Y381629D01*
X1215795D01*
G01X1288657Y392100D02*
X1287443Y395309D01*
X1262595Y413255D01*
X1249426Y416182D01*
X1240852Y413940D01*
X1232753Y408121D01*
X1223115Y388347D01*
X1218765Y386437D01*
X1216124D01*
G01X1172469Y370247D02*
X1174719D01*
G01X1179229D02*
X1181479D01*
G01X1169089Y364396D02*
X1171339D01*
G01X1175849Y360496D02*
X1178099D01*
G01X1175849Y356596D02*
X1178099D01*
G01X1182609Y352696D02*
X1184859D01*
G01X1158950Y393647D02*
X1161200D01*
G01X1158950Y385847D02*
X1161200D01*
G01X1165710D02*
X1167960D01*
G01X1165710Y381947D02*
X1167960D01*
G01Y378047D02*
X1165710D01*
G01X1172469D02*
X1174719D01*
G01X1172469Y374146D02*
X1174719D01*
G01X1172469Y366347D02*
X1174719D01*
G01X1175849Y368296D02*
X1178099D01*
G01X1172469Y362447D02*
X1174719D01*
G01X1172469Y358547D02*
X1174719D01*
G01X1179229Y354647D02*
X1181479D01*
G01X1179229Y350747D02*
X1181479D01*
G01X1158950Y381947D02*
X1161200D01*
G01X1162330Y383896D02*
X1164580D01*
G01X1169089Y379996D02*
X1171339D01*
G01X1165710Y374146D02*
X1167960D01*
G01X1169089Y376096D02*
X1171339D01*
G01X1175849Y372197D02*
X1178099D01*
G01X1194999Y378047D02*
X1192749D01*
G01X1199509Y374146D02*
X1201759D01*
G01X1194999D02*
X1192749D01*
G01X1196129Y364396D02*
X1198379D01*
G01X1196129Y360496D02*
X1198379D01*
G01X1196129Y356596D02*
X1198379D01*
G01X1172469Y401447D02*
X1174719D01*
G01X1178099Y395596D02*
X1175850D01*
X1175849Y395597D01*
G01X1182609Y399496D02*
X1184859D01*
G01X1179229Y393647D02*
X1181479D01*
G01X1185989Y389747D02*
X1188239D01*
G01X1185989Y385847D02*
X1188239D01*
G01X1189369Y379996D02*
X1191619D01*
G01X1196129Y383896D02*
X1198379D01*
G01X1165710Y401447D02*
X1167960D01*
G01X1196129Y376096D02*
X1198379D01*
G01X1196129Y372197D02*
X1198379D01*
G01X1194999Y370247D02*
X1192749D01*
G01X1194999Y362447D02*
X1192749D01*
G01X1199509Y358547D02*
X1201759D01*
G01X1196129Y352696D02*
X1198379D01*
G01X1175849Y399496D02*
X1178099D01*
G01X1179229Y397546D02*
X1181479D01*
G01X1184859Y395596D02*
X1182610D01*
X1182609Y395597D01*
G01Y391696D02*
X1184859D01*
G01X1182609Y387796D02*
X1184859D01*
G01X1189369Y383896D02*
X1191619D01*
G01X1194999Y381947D02*
X1192749D01*
G01X1196129Y379996D02*
X1198379D01*
G01X1165710Y405347D02*
X1167960D01*
G01X1172469D02*
X1174719D01*
G01X1169089Y403396D02*
X1171339D01*
G01X1210917Y651204D02*
X1209494Y649781D01*
X1198623D01*
X1196198Y652206D01*
G01X1210917Y647264D02*
X1209550Y648631D01*
X1198623D01*
X1196198Y646206D01*
G01X1429786Y42977D02*
X1428511Y44252D01*
Y49856D01*
X1421462Y65633D01*
Y65634D01*
X1418840Y77990D01*
X1420060Y83733D01*
X1418911Y89144D01*
X1419563Y92206D01*
X1420242Y95397D01*
X1417614Y104265D01*
X1417613D01*
X1404648Y148000D01*
X1407383Y159328D01*
X1405690Y167289D01*
X1389382Y178333D01*
X1376874Y180835D01*
X1368900Y179240D01*
X1352850Y182450D01*
X1343700Y180620D01*
X1334999Y182360D01*
X1327516Y180863D01*
X1303911Y188584D01*
X1279928Y207308D01*
G01X1245946Y265866D02*
X1257042Y258171D01*
X1282919Y220552D01*
X1311398Y198318D01*
X1328387Y192758D01*
X1335400Y194160D01*
X1343550Y192530D01*
X1352450Y194310D01*
X1368500Y191100D01*
X1377848Y192970D01*
X1393215Y189898D01*
X1416318Y174281D01*
X1419382Y159280D01*
X1416817Y148643D01*
X1432458Y95880D01*
X1431026Y89142D01*
X1432175Y83733D01*
X1430954Y77989D01*
X1432858Y69018D01*
X1436486Y61968D01*
X1454440Y50083D01*
X1456861Y45678D01*
Y44252D01*
X1458136Y42977D01*
G01X1570548Y42984D02*
X1569273Y44259D01*
Y45542D01*
X1566134Y49338D01*
X1562434Y52103D01*
X1481624Y66865D01*
X1479377Y68353D01*
X1476724Y74697D01*
X1477955Y80888D01*
X1476619Y87496D01*
X1478049Y94652D01*
X1476385Y102984D01*
X1477960Y110864D01*
X1475425Y123510D01*
X1476889Y129204D01*
Y131018D01*
X1475746Y133696D01*
X1473723Y135282D01*
X1469390Y136080D01*
X1468124Y137981D01*
X1466394Y146630D01*
X1467224Y150778D01*
X1465472Y159541D01*
X1466819Y167083D01*
X1461153Y183973D01*
X1461152D01*
X1453125Y189409D01*
X1443761Y191280D01*
X1439747Y193957D01*
X1434123Y202392D01*
X1414624Y215595D01*
Y215596D01*
X1410263Y232323D01*
X1406441Y237669D01*
X1400358Y241697D01*
X1390704Y243590D01*
X1383138Y241620D01*
X1376379Y243056D01*
X1371762Y242075D01*
X1366824Y243126D01*
X1362195Y242142D01*
X1357354Y243171D01*
X1354233Y242509D01*
X1310702Y251277D01*
X1294776Y260752D01*
X1288425Y270858D01*
X1267402Y285442D01*
X1265720Y287844D01*
G01X1560898Y43184D02*
X1559623Y44459D01*
Y45742D01*
X1557265Y48595D01*
X1480251Y63146D01*
X1476133Y65873D01*
X1472615Y74286D01*
X1473887Y80682D01*
X1472622Y87013D01*
X1474049Y94150D01*
X1468891Y119946D01*
X1464740Y133133D01*
X1461967Y146993D01*
X1462789Y151101D01*
X1461286Y158614D01*
X1462707Y166557D01*
X1457598Y181784D01*
X1451625Y185828D01*
X1442197Y187713D01*
X1436976Y191194D01*
X1431333Y199658D01*
X1400559Y220497D01*
X1373213Y226313D01*
X1348013Y221279D01*
X1332197Y225798D01*
X1327455Y224793D01*
X1313360Y229405D01*
X1291620Y258407D01*
X1284731Y268782D01*
X1264376Y282894D01*
X1253964Y297498D01*
G01X1551748Y42984D02*
X1550473Y44259D01*
Y44879D01*
X1549414Y46155D01*
X1478533Y59450D01*
X1473005Y63112D01*
X1468505Y73874D01*
X1469785Y80303D01*
X1468458Y86813D01*
X1470038Y94710D01*
X1465260Y118621D01*
X1460379Y134144D01*
X1457924Y146414D01*
X1457925D01*
X1458776Y150672D01*
X1457085Y159122D01*
X1458466Y166846D01*
X1454234Y179467D01*
X1450140Y182239D01*
X1434031Y185458D01*
X1429581Y188473D01*
X1420441Y202183D01*
X1410218Y209098D01*
X1387781Y216824D01*
X1385180Y218544D01*
X1369828Y221732D01*
X1347627Y217301D01*
X1331967Y221775D01*
X1327315Y220789D01*
X1310564Y226270D01*
X1279582Y267622D01*
X1261791Y279959D01*
X1254493Y290195D01*
G01X1236150Y300592D02*
X1254763Y274485D01*
X1275530Y260086D01*
X1307675Y217136D01*
X1319596Y207829D01*
X1329369Y204634D01*
X1335650Y205890D01*
X1343650Y204290D01*
X1352750Y206110D01*
X1368435Y202973D01*
X1377466Y204779D01*
X1397844Y200705D01*
X1427253Y180847D01*
X1431542Y159756D01*
X1429027Y149343D01*
X1434668Y130249D01*
X1457950Y113656D01*
X1461861Y94104D01*
X1460499Y87298D01*
X1461825Y80783D01*
X1459989Y71560D01*
X1465544Y58279D01*
X1484918Y45462D01*
X1485211Y44496D01*
Y44252D01*
X1486486Y42977D01*
G01X1467586D02*
X1466311Y44252D01*
Y45839D01*
X1463522Y49373D01*
X1438864Y65692D01*
X1436716Y69862D01*
X1434992Y77989D01*
X1436216Y83751D01*
X1435067Y89157D01*
X1436529Y96042D01*
X1420868Y148880D01*
X1423386Y159318D01*
X1419873Y176496D01*
X1394669Y193535D01*
X1377821Y196904D01*
X1368450Y195030D01*
X1352500Y198220D01*
X1343500Y196420D01*
X1335302Y198059D01*
X1328715Y196743D01*
X1315359Y201114D01*
X1311820Y203878D01*
X1290284Y220702D01*
X1267805Y253386D01*
G01X1254526Y258759D02*
X1256357Y257489D01*
X1282219Y219893D01*
X1310944Y197466D01*
X1328329Y191777D01*
X1335400Y193191D01*
X1335402Y193190D01*
X1343550Y191561D01*
X1352450Y193341D01*
X1368500Y190131D01*
X1377848Y192001D01*
X1392841Y189003D01*
X1415464Y173711D01*
X1418408Y159297D01*
X1415833Y148618D01*
X1431478Y95842D01*
X1430054Y89142D01*
X1431203Y83733D01*
X1429982Y77989D01*
X1431955Y68696D01*
X1435754Y61312D01*
X1446270Y54351D01*
X1446397Y53728D01*
X1447523Y52982D01*
X1448146Y53109D01*
X1449272Y52364D01*
X1449399Y51741D01*
X1450525Y50995D01*
X1451148Y51122D01*
X1453720Y49420D01*
X1455911Y45434D01*
Y44252D01*
X1454636Y42977D01*
G01X1260848Y293146D02*
X1266721Y284758D01*
X1287724Y270188D01*
X1294093Y260052D01*
X1310355Y250377D01*
X1354238Y241538D01*
X1357354Y242199D01*
X1362195Y241170D01*
X1366824Y242154D01*
X1371762Y241103D01*
X1376379Y242084D01*
X1383161Y240643D01*
X1390734Y242616D01*
X1399990Y240801D01*
X1405770Y236973D01*
X1409388Y231913D01*
X1410162Y228945D01*
X1409840Y228396D01*
X1410180Y227089D01*
X1410729Y226767D01*
X1411070Y225461D01*
X1410748Y224912D01*
X1411089Y223605D01*
X1411637Y223283D01*
X1411978Y221977D01*
X1411656Y221428D01*
X1411997Y220121D01*
X1412546Y219799D01*
X1412886Y218493D01*
X1412564Y217944D01*
X1412905Y216637D01*
X1413454Y216315D01*
X1413794Y215009D01*
X1433435Y201709D01*
X1439061Y193271D01*
X1443390Y190385D01*
X1452750Y188514D01*
X1460354Y183366D01*
X1465841Y167011D01*
X1464505Y159531D01*
X1466255Y150778D01*
X1465425Y146630D01*
X1467229Y137611D01*
X1468822Y135218D01*
X1473321Y134390D01*
X1474967Y133098D01*
X1475939Y130823D01*
Y129325D01*
X1474450Y123536D01*
X1476991Y110864D01*
X1475416Y102984D01*
X1477080Y94652D01*
X1475649Y87495D01*
X1476986Y80886D01*
X1475735Y74598D01*
X1478611Y67720D01*
X1481262Y65965D01*
X1562044Y51208D01*
X1565192Y48856D01*
X1565474Y48645D01*
X1568323Y45200D01*
Y44259D01*
X1567048Y42984D01*
G01X1557398Y43184D02*
X1558673Y44459D01*
Y45400D01*
X1556751Y47725D01*
X1555424Y47976D01*
X1554899Y47617D01*
X1553572Y47868D01*
X1553214Y48393D01*
X1479886Y62248D01*
X1475367Y65240D01*
X1471626Y74187D01*
X1472918Y80682D01*
X1471653Y87013D01*
X1473080Y94150D01*
X1467969Y119710D01*
X1463818Y132896D01*
X1460998Y146993D01*
X1461820Y151101D01*
X1460319Y158604D01*
X1461729Y166485D01*
X1456799Y181177D01*
X1451251Y184933D01*
X1441826Y186818D01*
X1436290Y190508D01*
X1435386Y191865D01*
X1434762Y191989D01*
X1434013Y193113D01*
X1434138Y193737D01*
X1433389Y194860D01*
X1432765Y194985D01*
X1432016Y196108D01*
X1432140Y196732D01*
X1430645Y198975D01*
X1429527Y199732D01*
X1428902Y199612D01*
X1427784Y200369D01*
X1427664Y200994D01*
X1400180Y219606D01*
X1373207Y225343D01*
X1347973Y220302D01*
X1332163Y224819D01*
X1327402Y223810D01*
X1312779Y228595D01*
X1290843Y257858D01*
X1284040Y268105D01*
X1263698Y282207D01*
X1248995Y302830D01*
G01X1237316Y312648D02*
X1261113Y279272D01*
X1278914Y266929D01*
X1309983Y225460D01*
X1327262Y219806D01*
X1331933Y220796D01*
X1347587Y216324D01*
X1369822Y220762D01*
Y220761D01*
X1369824Y220762D01*
X1384808Y217650D01*
X1384809Y217649D01*
X1387357Y215964D01*
X1409789Y208240D01*
X1419753Y201500D01*
X1428893Y187790D01*
X1431272Y186179D01*
X1433656Y184563D01*
X1449766Y181344D01*
X1453435Y178860D01*
X1457488Y166774D01*
X1456118Y159112D01*
X1457807Y150672D01*
X1456955Y146414D01*
X1459457Y133908D01*
X1464338Y118385D01*
X1469069Y94710D01*
X1467488Y86811D01*
X1468815Y80301D01*
X1467516Y73775D01*
X1472239Y62479D01*
X1478168Y58551D01*
X1479495Y58302D01*
X1479854Y57777D01*
X1481181Y57528D01*
X1481706Y57887D01*
X1483033Y57638D01*
X1483392Y57113D01*
X1484719Y56864D01*
X1485244Y57223D01*
X1486571Y56974D01*
X1486930Y56449D01*
X1488257Y56200D01*
X1488782Y56559D01*
X1490109Y56310D01*
X1490468Y55785D01*
X1491795Y55536D01*
X1492320Y55895D01*
X1548902Y45284D01*
X1549523Y44536D01*
Y44259D01*
X1548248Y42984D01*
G01X1482986Y42977D02*
X1484261Y44252D01*
Y44355D01*
X1484107Y44858D01*
X1473786Y51687D01*
X1473162Y51560D01*
X1472037Y52305D01*
X1471910Y52928D01*
X1470784Y53673D01*
X1470160Y53546D01*
X1469034Y54291D01*
X1468907Y54915D01*
X1467781Y55660D01*
X1467158Y55533D01*
X1466032Y56277D01*
X1465905Y56901D01*
X1464779Y57646D01*
X1461778Y64819D01*
X1461190Y65060D01*
X1460669Y66306D01*
X1460910Y66895D01*
X1460389Y68140D01*
X1459800Y68381D01*
X1459279Y69627D01*
X1459521Y70216D01*
X1459000Y71461D01*
X1460855Y80781D01*
X1459529Y87296D01*
X1460892Y94104D01*
X1457091Y113099D01*
X1433849Y129665D01*
X1428043Y149318D01*
X1430568Y159774D01*
X1426399Y180277D01*
X1397470Y199810D01*
X1377466Y203810D01*
X1368435Y202004D01*
X1352750Y205141D01*
X1343650Y203321D01*
X1335650Y204921D01*
X1329311Y203653D01*
X1319142Y206977D01*
X1306990Y216465D01*
X1274862Y259393D01*
X1254085Y273798D01*
X1252354Y276226D01*
G01X1265488Y322910D02*
X1281351Y299719D01*
X1316372Y276045D01*
X1338446Y265590D01*
X1353959Y262297D01*
X1357335Y262944D01*
Y262948D01*
X1362227Y261909D01*
X1366857Y262892D01*
X1371747Y261853D01*
X1376544Y262872D01*
X1381441Y261834D01*
X1399682Y266810D01*
X1414377Y263921D01*
X1424130Y256568D01*
X1427842Y242337D01*
X1436707Y229726D01*
X1476760Y202178D01*
X1485357Y200140D01*
X1496065Y203194D01*
X1502406Y201319D01*
X1508896Y191232D01*
X1512085Y189976D01*
X1517914Y182374D01*
X1528534Y175346D01*
X1533867Y174261D01*
X1545936Y166273D01*
X1548238Y162792D01*
X1549915Y154547D01*
X1547907Y144673D01*
X1551571Y126675D01*
X1550943Y123670D01*
X1553916Y109042D01*
X1551563Y100447D01*
X1555505Y87593D01*
X1559478Y81307D01*
X1567641Y76600D01*
X1568856Y72082D01*
X1586568Y60356D01*
X1595565Y58558D01*
X1610442Y48667D01*
X1615112D01*
X1616199Y47580D01*
Y46221D01*
X1617393Y45027D01*
G01X1264182Y315862D02*
X1277751Y296334D01*
X1313300Y272183D01*
X1337487Y260730D01*
X1354175Y257369D01*
X1357333Y258040D01*
X1362225Y257001D01*
X1366857Y257984D01*
X1371796Y256935D01*
X1376583Y257952D01*
X1381783Y256847D01*
X1399863Y261780D01*
X1412326Y259330D01*
X1419976Y253563D01*
X1423483Y240113D01*
X1433867Y225337D01*
X1474472Y197844D01*
X1485065Y195057D01*
X1490549Y196443D01*
X1500723Y194076D01*
X1509476Y182321D01*
X1522879Y171433D01*
X1531694Y169661D01*
X1538557Y165031D01*
X1543608Y157398D01*
X1544552Y152756D01*
X1542982Y145033D01*
X1546647Y126747D01*
X1544926Y118288D01*
X1546803Y109064D01*
X1546804D01*
X1545417Y103942D01*
X1545418D01*
X1550983Y85478D01*
X1550982D01*
X1559701Y72294D01*
X1585108Y55480D01*
X1594121Y53679D01*
X1599247Y50261D01*
X1599372Y49637D01*
X1600495Y48888D01*
X1601119Y49012D01*
X1602242Y48263D01*
X1602367Y47639D01*
X1603490Y46890D01*
X1604114Y47015D01*
X1604573Y46709D01*
X1606111Y44849D01*
X1606081Y44212D01*
X1604848Y42979D01*
G01X1598898Y42984D02*
X1597623Y44259D01*
Y45542D01*
X1593311Y50758D01*
X1584347Y52551D01*
X1560067Y68622D01*
X1554757Y69699D01*
X1548082Y79222D01*
X1543048Y82557D01*
X1541263Y82919D01*
X1536272Y81902D01*
X1532277Y83807D01*
X1530678Y86367D01*
X1529920Y89650D01*
X1531250Y95419D01*
X1530018Y100754D01*
X1531172Y105751D01*
X1530069Y110533D01*
X1531439Y116464D01*
X1529082Y126666D01*
Y126844D01*
X1528681Y127245D01*
X1523492Y130680D01*
X1523071Y131317D01*
X1522458Y134324D01*
X1523116Y137558D01*
X1521222Y146869D01*
X1523375Y157451D01*
X1522766Y160722D01*
X1520891Y168843D01*
X1510063Y175609D01*
X1498242Y191114D01*
X1490310Y193415D01*
X1485014Y192058D01*
X1473323Y195101D01*
X1430886Y223841D01*
X1421089Y237769D01*
X1417455Y251707D01*
X1411071Y256519D01*
X1399974Y258701D01*
X1382083Y253819D01*
X1376534Y254998D01*
X1371826Y253997D01*
X1366936Y255036D01*
X1362227Y254036D01*
X1357335Y255076D01*
X1354191Y254408D01*
X1336649Y257941D01*
X1311900Y269660D01*
X1275595Y294239D01*
X1256754Y321327D01*
G01X1261585Y307408D02*
X1272534Y291667D01*
X1308910Y266862D01*
X1335605Y254224D01*
X1354211Y250477D01*
X1357335Y251140D01*
X1362227Y250101D01*
X1366857Y251084D01*
X1371784Y250037D01*
X1376572Y251054D01*
X1382877Y249715D01*
X1390500Y251700D01*
X1400200Y249800D01*
X1405253Y251484D01*
X1409576Y250489D01*
X1414694Y247160D01*
X1417610Y235973D01*
X1429661Y218832D01*
X1439995Y211858D01*
X1447202Y201046D01*
X1448705Y200045D01*
X1452220Y199341D01*
X1456787Y200255D01*
X1459821Y199649D01*
X1471731Y191584D01*
X1471795Y191567D01*
X1472305Y191222D01*
X1485513Y187998D01*
X1490601Y189091D01*
X1493744Y187792D01*
X1502241Y176485D01*
X1517719Y164198D01*
X1518455Y161026D01*
X1517321Y156112D01*
X1518326Y151756D01*
X1517051Y145483D01*
X1518492Y138398D01*
X1517317Y132617D01*
X1516016Y130652D01*
X1516322Y129148D01*
X1518431Y125962D01*
X1521662Y110070D01*
X1521005Y106791D01*
X1522320Y101929D01*
X1520158Y97448D01*
X1524672Y75203D01*
X1526693Y72151D01*
X1541430Y68511D01*
X1558527Y65034D01*
X1583125Y48750D01*
X1586132Y48243D01*
X1588173Y45517D01*
Y44259D01*
X1589448Y42984D01*
G01X1579998D02*
X1578723Y44259D01*
Y45542D01*
X1576196Y48600D01*
X1558730Y60161D01*
X1526422Y66095D01*
X1500562Y74214D01*
X1497523Y78444D01*
X1495731Y85083D01*
X1497902Y92623D01*
X1494953Y102220D01*
X1495036Y102472D01*
X1495037D01*
X1496234Y106106D01*
X1495692Y108672D01*
X1491851Y110758D01*
X1487141Y109738D01*
X1484832Y110333D01*
X1480925Y115479D01*
X1479495Y122611D01*
X1480692Y128141D01*
Y132377D01*
X1478983Y136457D01*
X1472393Y141213D01*
X1471731Y143210D01*
X1472605Y147433D01*
X1470897Y155985D01*
X1472317Y163082D01*
X1464267Y187075D01*
X1461471Y193834D01*
X1459065Y195260D01*
X1455457Y196004D01*
X1448790Y194286D01*
X1445136Y195016D01*
X1442600Y196708D01*
X1436977Y205139D01*
X1418109Y217885D01*
X1414012Y233596D01*
X1408589Y241788D01*
X1403570Y245111D01*
X1390681Y247666D01*
X1382772Y245606D01*
X1376074Y247029D01*
X1371763Y246113D01*
X1366876Y247153D01*
X1362246Y246169D01*
X1357355Y247209D01*
X1354185Y246536D01*
X1334535Y250493D01*
X1316810Y258885D01*
X1298163Y265332D01*
X1293498Y272508D01*
X1270214Y288307D01*
X1261972Y300150D01*
G01X1260234Y328907D02*
X1280669Y299033D01*
X1315900Y275217D01*
X1338140Y264683D01*
X1353949Y261327D01*
X1357336Y261976D01*
X1362227Y260937D01*
X1366857Y261920D01*
X1371747Y260881D01*
X1376544Y261900D01*
X1381464Y260855D01*
X1399717Y265834D01*
X1413979Y263031D01*
X1423294Y256008D01*
X1426966Y241931D01*
X1436024Y229042D01*
X1476368Y201294D01*
X1485379Y199158D01*
X1496060Y202204D01*
X1501798Y200508D01*
X1508263Y190460D01*
X1511491Y189188D01*
X1517256Y181669D01*
X1528163Y174451D01*
X1533496Y173366D01*
X1545250Y165587D01*
X1547343Y162421D01*
X1548945Y154547D01*
X1546937Y144673D01*
X1550600Y126678D01*
X1549972Y123673D01*
X1550241Y122350D01*
X1549890Y121819D01*
X1550158Y120496D01*
X1550689Y120145D01*
X1551891Y114230D01*
X1551540Y113699D01*
X1551809Y112377D01*
X1552339Y112025D01*
X1552939Y109075D01*
X1552583Y107773D01*
X1552030Y107458D01*
X1551673Y106156D01*
X1551988Y105603D01*
X1550573Y100432D01*
X1554633Y87192D01*
X1558800Y80601D01*
X1566825Y75973D01*
X1568031Y71488D01*
X1586199Y59460D01*
X1595194Y57662D01*
X1610155Y47717D01*
X1614718D01*
X1615249Y47186D01*
Y46383D01*
X1613893Y45027D01*
G01X1269395Y310026D02*
X1278431Y297021D01*
X1313774Y273011D01*
X1337789Y261639D01*
X1354170Y258340D01*
X1357333Y259012D01*
X1362225Y257973D01*
X1366857Y258956D01*
X1371747Y257917D01*
Y257918D01*
X1371758Y257916D01*
X1371796Y257907D01*
X1376583Y258924D01*
X1381755Y257825D01*
X1399828Y262756D01*
X1412724Y260220D01*
X1420812Y254123D01*
X1424359Y240519D01*
X1434544Y226027D01*
X1474870Y198722D01*
X1485070Y196039D01*
X1490540Y197421D01*
X1501278Y194923D01*
X1510167Y182985D01*
X1523297Y172319D01*
X1532068Y170555D01*
X1539245Y165713D01*
X1544503Y157769D01*
X1545522Y152756D01*
X1543952Y145033D01*
X1543953D01*
X1543952Y145032D01*
X1547617Y126746D01*
X1545896Y118288D01*
X1547780Y109033D01*
X1546406Y103958D01*
X1551854Y85883D01*
X1560387Y72980D01*
X1585477Y56376D01*
X1594492Y54574D01*
X1600102Y50834D01*
Y50833D01*
X1605217Y47423D01*
X1607078Y45172D01*
X1607037Y44290D01*
X1608348Y42979D01*
G01X1595398Y42984D02*
X1596673Y44259D01*
Y45200D01*
X1592792Y49893D01*
Y49892D01*
X1591467Y50157D01*
X1591468Y50158D01*
X1590939Y49805D01*
X1589615Y50069D01*
X1589262Y50599D01*
X1583978Y51655D01*
X1559697Y67727D01*
X1554196Y68842D01*
X1551817Y72236D01*
X1551191Y72346D01*
X1550416Y73452D01*
X1550526Y74078D01*
X1549751Y75184D01*
X1549124Y75294D01*
X1548350Y76400D01*
X1548460Y77026D01*
X1547407Y78529D01*
X1542677Y81662D01*
X1541263Y81949D01*
X1536150Y80907D01*
X1531617Y83068D01*
X1529788Y85998D01*
X1528945Y89650D01*
X1530274Y95419D01*
X1529042Y100754D01*
X1530196Y105751D01*
X1529093Y110533D01*
X1530463Y116464D01*
X1528164Y126417D01*
X1528076Y126505D01*
X1522805Y129994D01*
X1522487Y130475D01*
X1522488D01*
X1522176Y130947D01*
X1522139Y131127D01*
X1522140D01*
X1521488Y134324D01*
X1522146Y137558D01*
X1520252Y146869D01*
X1522407Y157459D01*
X1521835Y160528D01*
X1520053Y168245D01*
X1509412Y174894D01*
X1497676Y190289D01*
X1490295Y192430D01*
X1485012Y191076D01*
X1472925Y194222D01*
X1430205Y223153D01*
X1420213Y237363D01*
X1416619Y251147D01*
X1410673Y255628D01*
X1400009Y257725D01*
X1382111Y252841D01*
X1376534Y254026D01*
X1371826Y253025D01*
X1366936Y254064D01*
X1362227Y253064D01*
X1357335Y254104D01*
X1354196Y253437D01*
X1336347Y257032D01*
X1311427Y268832D01*
X1274916Y293551D01*
X1268941Y302140D01*
X1251491Y327228D01*
G01X1255730Y314160D02*
X1271853Y290980D01*
X1308436Y266035D01*
X1335303Y253315D01*
X1354216Y249506D01*
X1357335Y250168D01*
X1362227Y249129D01*
X1366857Y250112D01*
X1371784Y249065D01*
X1376572Y250082D01*
X1382899Y248739D01*
X1390530Y250726D01*
X1400263Y248819D01*
X1405300Y250498D01*
X1409200Y249600D01*
X1413867Y246564D01*
X1416733Y235568D01*
X1416734Y235567D01*
X1416832Y235426D01*
X1428984Y218142D01*
X1439308Y211175D01*
X1446516Y200360D01*
X1448335Y199150D01*
X1452220Y198372D01*
X1456787Y199286D01*
X1459447Y198754D01*
X1471331Y190706D01*
X1471395Y190689D01*
X1471914Y190339D01*
X1485499Y187023D01*
X1490511Y188099D01*
X1493141Y187013D01*
X1501554Y175816D01*
X1516868Y163660D01*
X1517479Y161025D01*
X1516346Y156112D01*
X1517353Y151743D01*
X1516081Y145483D01*
X1517522Y138398D01*
X1516422Y132988D01*
X1515006Y130848D01*
X1515427Y128777D01*
X1517536Y125591D01*
X1520692Y110069D01*
X1520029Y106759D01*
X1521057Y102957D01*
X1521310Y102023D01*
X1519163Y97573D01*
X1523777Y74832D01*
X1526105Y71317D01*
X1527241Y71036D01*
X1527570Y70491D01*
X1528881Y70168D01*
X1529425Y70497D01*
X1530736Y70173D01*
X1531065Y69628D01*
X1532376Y69305D01*
X1532920Y69634D01*
X1534231Y69310D01*
X1534560Y68765D01*
X1535871Y68442D01*
X1536415Y68771D01*
X1537726Y68447D01*
X1538055Y67902D01*
X1539366Y67579D01*
X1539910Y67908D01*
X1541221Y67584D01*
X1558156Y64139D01*
X1582768Y47846D01*
X1585599Y47369D01*
X1587223Y45200D01*
Y44259D01*
X1585948Y42984D01*
G01X1576498D02*
X1577773Y44259D01*
Y45200D01*
X1575551Y47887D01*
X1558370Y59260D01*
X1557042Y59504D01*
X1556518Y59143D01*
X1555191Y59387D01*
X1554829Y59910D01*
X1553501Y60154D01*
X1552978Y59793D01*
X1551650Y60037D01*
X1551289Y60561D01*
X1549961Y60805D01*
X1549437Y60444D01*
X1548109Y60688D01*
X1547748Y61211D01*
X1546420Y61455D01*
X1545896Y61094D01*
X1544568Y61338D01*
X1544207Y61862D01*
X1526193Y65171D01*
X1499975Y73402D01*
X1496650Y78029D01*
X1494744Y85091D01*
X1496910Y92614D01*
X1493956Y102230D01*
X1495251Y106160D01*
X1494853Y108046D01*
X1491707Y109754D01*
X1487122Y108761D01*
X1485750Y109114D01*
Y109115D01*
X1484274Y109495D01*
X1480036Y115078D01*
X1478524Y122618D01*
X1479742Y128243D01*
Y132186D01*
X1478210Y135843D01*
X1471587Y140622D01*
X1470749Y143153D01*
X1471635Y147436D01*
X1469928Y155985D01*
X1471335Y163020D01*
X1463376Y186742D01*
X1461044Y192379D01*
X1461043D01*
X1460714Y193178D01*
X1458717Y194361D01*
X1455481Y195029D01*
X1448817Y193311D01*
X1444765Y194121D01*
X1441914Y196022D01*
X1436290Y204456D01*
X1417280Y217298D01*
X1413132Y233200D01*
X1413134D01*
X1407903Y241102D01*
X1403201Y244215D01*
X1390710Y246691D01*
X1382795Y244629D01*
X1376074Y246057D01*
X1371763Y245141D01*
X1366876Y246181D01*
X1362246Y245197D01*
X1357355Y246237D01*
X1354190Y245565D01*
X1334233Y249584D01*
X1316450Y258004D01*
X1297544Y264540D01*
X1292804Y271830D01*
X1269534Y287619D01*
X1245219Y322557D01*
G01X1353142Y306760D02*
X1351572D01*
X1350978Y307354D01*
Y311094D01*
X1349149Y312923D01*
X1348076D01*
X1347316Y313686D01*
X1346205Y318567D01*
X1343548Y322309D01*
X1338045Y323835D01*
X1329371Y322110D01*
X1271318Y341395D01*
X1271317Y341396D01*
X1247619Y353586D01*
G01X1274699Y333959D02*
X1316076Y316948D01*
X1316321Y316361D01*
X1317569Y315847D01*
X1318157Y316092D01*
X1319405Y315579D01*
X1319650Y314992D01*
X1320899Y314478D01*
X1321486Y314724D01*
X1322735Y314210D01*
X1322980Y313623D01*
X1324229Y313110D01*
X1324816Y313355D01*
X1326064Y312841D01*
X1326310Y312254D01*
X1327558Y311741D01*
X1328145Y311986D01*
X1330295Y311102D01*
X1335906Y312226D01*
X1336988Y311772D01*
X1338454Y310306D01*
Y307149D01*
X1338065Y306760D01*
X1336240D01*
G01X1347642D02*
X1349268D01*
X1350028Y307520D01*
Y310700D01*
X1348755Y311973D01*
X1347681D01*
X1346450Y313209D01*
X1345320Y318171D01*
X1342969Y321483D01*
X1342968D01*
X1338009Y322859D01*
X1332838Y321830D01*
X1332484Y321301D01*
X1331160Y321038D01*
X1330631Y321391D01*
X1329307Y321128D01*
X1319083Y324525D01*
X1318514Y324240D01*
X1317233Y324665D01*
X1316947Y325234D01*
X1315666Y325660D01*
X1315097Y325375D01*
X1313816Y325800D01*
X1313531Y326369D01*
X1312250Y326795D01*
X1311681Y326510D01*
X1310400Y326935D01*
X1310115Y327504D01*
X1308833Y327930D01*
X1308265Y327645D01*
X1306983Y328070D01*
X1306698Y328639D01*
X1270947Y340517D01*
X1268614Y341717D01*
G01X1254441Y355073D02*
X1273624Y345262D01*
Y345261D01*
X1330708Y326296D01*
Y326295D01*
X1339170Y327979D01*
X1350708Y324778D01*
X1353719Y317390D01*
X1358507Y312602D01*
X1360254D01*
X1361769Y311087D01*
Y307140D01*
X1362219Y306690D01*
X1364044D01*
G01X1374840Y307130D02*
X1373015D01*
X1372565Y307580D01*
Y310600D01*
X1376025Y317192D01*
X1374495Y323479D01*
X1369901Y326542D01*
X1341026Y332326D01*
X1330876Y330308D01*
X1275513Y348701D01*
X1262771Y355219D01*
Y355220D01*
G01X1270621Y355590D02*
X1276826Y352417D01*
X1314454Y339916D01*
X1320563Y341026D01*
X1326612Y339279D01*
X1331747Y340374D01*
X1338258Y338833D01*
X1349334Y343333D01*
X1360250Y341150D01*
X1367286Y342557D01*
X1369972Y342020D01*
X1376077Y337948D01*
X1378629Y337438D01*
X1382099Y335126D01*
X1388375Y325710D01*
X1388566Y324756D01*
X1386490Y314379D01*
X1383773Y310304D01*
Y307760D01*
X1384223Y307310D01*
X1386048D01*
G01X1358544Y306690D02*
X1360369D01*
X1360819Y307140D01*
Y310693D01*
X1359860Y311652D01*
X1358113D01*
X1355539Y314226D01*
X1354902D01*
X1353947Y315180D01*
Y315817D01*
X1352911Y316853D01*
X1352402Y318103D01*
X1351815Y318350D01*
X1351306Y319600D01*
X1351553Y320187D01*
X1350004Y323987D01*
X1346072Y325078D01*
X1345518Y324765D01*
X1344217Y325126D01*
X1343904Y325680D01*
X1342603Y326041D01*
X1342049Y325727D01*
X1340748Y326088D01*
X1340435Y326642D01*
X1339134Y327003D01*
X1330647Y325314D01*
X1273259Y344380D01*
X1273256Y344382D01*
X1265918Y348135D01*
G01X1246918Y362262D02*
X1248828Y361285D01*
X1267242Y351865D01*
X1267241D01*
X1275145Y347822D01*
X1330815Y329327D01*
X1341025Y331357D01*
X1350576Y329444D01*
X1350929Y328914D01*
X1352253Y328649D01*
X1352783Y329002D01*
X1354106Y328736D01*
X1354459Y328207D01*
X1355783Y327942D01*
X1356312Y328295D01*
X1357636Y328030D01*
X1357989Y327500D01*
X1359312Y327235D01*
X1359842Y327588D01*
X1361166Y327323D01*
X1361518Y326793D01*
X1362842Y326528D01*
X1363372Y326881D01*
X1369530Y325647D01*
X1373659Y322894D01*
X1375017Y317316D01*
X1371615Y310835D01*
Y307580D01*
X1371165Y307130D01*
X1369340D01*
G01X1380548Y307310D02*
X1382373D01*
X1382823Y307760D01*
Y310592D01*
X1385595Y314750D01*
X1387597Y324756D01*
X1387480Y325338D01*
X1386731Y326462D01*
X1386107Y326587D01*
X1385358Y327710D01*
X1385483Y328334D01*
X1384734Y329458D01*
X1384110Y329583D01*
X1383361Y330706D01*
X1383486Y331330D01*
X1381413Y334440D01*
X1378258Y336542D01*
X1375706Y337053D01*
X1369601Y341125D01*
X1367286Y341588D01*
X1360250Y340181D01*
X1356487Y340933D01*
X1355958Y340580D01*
X1354634Y340845D01*
X1354281Y341374D01*
X1352957Y341639D01*
X1352428Y341286D01*
X1351104Y341551D01*
X1350751Y342080D01*
X1349427Y342345D01*
X1338335Y337838D01*
X1331736Y339400D01*
X1326577Y338300D01*
X1320514Y340051D01*
X1314384Y338937D01*
X1279500Y350527D01*
X1279501D01*
G01X1260765Y451319D02*
X1266017Y454814D01*
X1272858D01*
X1282420Y464376D01*
X1288329D01*
X1297633Y473680D01*
X1304319D01*
X1306210Y475571D01*
X1327724D01*
X1328363Y476210D01*
Y477492D01*
G01X1255969Y462926D02*
X1258343Y465300D01*
X1260356D01*
X1262202Y463454D01*
X1271150D01*
X1271750Y462854D01*
Y461504D01*
G01X1264430Y474540D02*
Y473278D01*
X1263778Y472626D01*
X1256199D01*
X1239184Y461228D01*
Y461227D01*
G01X1310630Y466600D02*
Y465200D01*
X1310180Y464750D01*
X1300999D01*
X1292085Y455836D01*
Y445077D01*
X1287564Y438910D01*
X1287562D01*
X1286074Y436879D01*
X1261381Y427008D01*
G01X1261528Y438443D02*
X1264976Y440837D01*
X1284499Y460360D01*
X1290532D01*
X1300017Y469845D01*
X1319463D01*
X1321873Y467435D01*
X1334929D01*
X1335522Y468028D01*
Y469337D01*
G01X1253522Y445355D02*
X1266305Y453863D01*
Y453864D01*
X1273252D01*
X1282814Y463426D01*
X1288723D01*
X1298027Y472730D01*
X1304713D01*
X1306604Y474621D01*
X1327724D01*
X1328463Y473882D01*
Y472592D01*
G01X1271750Y466204D02*
Y464888D01*
X1271266Y464404D01*
X1262596D01*
X1260750Y466250D01*
X1257949D01*
X1251312Y459613D01*
G01X1310586Y462030D02*
Y463314D01*
X1310100Y463800D01*
X1301393D01*
X1293035Y455442D01*
Y444766D01*
X1286680Y436097D01*
X1253042Y422650D01*
G01X1253007Y431370D02*
X1265588Y440105D01*
X1284893Y459410D01*
X1290926D01*
X1293966Y462450D01*
X1294602D01*
X1295557Y463404D01*
Y464041D01*
X1300411Y468895D01*
X1315469D01*
X1315919Y468445D01*
X1317269D01*
X1317719Y468895D01*
X1319069D01*
X1321479Y466485D01*
X1334929D01*
X1335522Y465892D01*
Y464337D01*
G01X1307363Y480350D02*
X1304806D01*
X1303556Y479100D01*
X1297606D01*
X1286727Y468221D01*
X1280721D01*
X1276898Y464398D01*
X1275802D01*
X1275250Y464950D01*
Y466204D01*
G01Y461504D02*
Y462850D01*
X1275848Y463448D01*
X1277292D01*
X1281115Y467271D01*
X1287121D01*
X1298000Y478150D01*
X1303950D01*
X1305200Y479400D01*
X1349779D01*
G01X1268250Y461504D02*
X1263000D01*
X1262700Y461804D01*
G01X1277750Y479000D02*
Y477700D01*
X1277050Y477000D01*
X1270850D01*
X1268840Y479010D01*
X1258840D01*
X1257732Y477902D01*
X1252653D01*
X1248060Y474441D01*
X1248059D01*
G01X1277750Y487500D02*
Y485950D01*
X1277300Y485500D01*
X1270496D01*
X1268716Y483720D01*
X1258133D01*
X1256145Y481732D01*
X1248947D01*
X1239722Y474778D01*
G01X1225284Y468813D02*
X1243800Y484600D01*
X1249557Y486447D01*
X1252532Y488690D01*
X1261800D01*
X1262250Y489140D01*
Y490500D01*
G01X1264430Y469540D02*
Y471070D01*
X1263824Y471676D01*
X1256488D01*
X1254389Y470270D01*
G01X1277750Y474000D02*
Y475744D01*
X1277444Y476050D01*
X1270456D01*
X1268446Y478060D01*
X1259234D01*
X1258126Y476952D01*
X1252971D01*
X1244243Y470374D01*
G01X1232141Y467872D02*
X1249265Y480782D01*
X1256539D01*
X1258527Y482770D01*
X1269110D01*
X1270890Y484550D01*
X1277444D01*
X1277750Y484244D01*
Y482500D01*
G01X1262250Y485500D02*
Y487100D01*
X1261610Y487740D01*
X1252850D01*
X1250001Y485591D01*
X1244272Y483753D01*
X1234100Y475081D01*
G01X1267930Y469540D02*
Y470810D01*
X1268521Y471401D01*
X1269159D01*
X1271730Y468830D01*
X1274167D01*
X1276490Y471153D01*
X1285462D01*
X1296459Y482150D01*
X1302120D01*
X1303320Y483350D01*
X1353264D01*
X1358464Y478150D01*
X1371796D01*
X1374097Y475849D01*
X1390809D01*
X1409666Y485650D01*
X1416882D01*
X1418632Y485300D01*
X1421608D01*
G01X1265750Y485500D02*
Y487244D01*
X1266056Y487550D01*
X1266893D01*
X1271347Y489996D01*
X1273146Y492626D01*
X1277055Y494363D01*
X1281014Y493481D01*
X1294347Y500392D01*
X1299466Y499371D01*
X1305704Y495500D01*
X1359943D01*
X1360778Y494665D01*
X1371874D01*
G01X1267930Y474540D02*
Y472814D01*
X1268393Y472351D01*
X1269553D01*
X1272124Y469780D01*
X1273773D01*
X1276096Y472103D01*
X1285068D01*
X1296065Y483100D01*
X1301726D01*
X1302926Y484300D01*
X1353658D01*
X1358858Y479100D01*
X1372190D01*
X1374491Y476799D01*
X1390576D01*
X1409433Y486600D01*
X1416977D01*
X1418727Y486250D01*
X1426993D01*
G01X1400050Y501950D02*
X1379596D01*
X1373261Y495615D01*
X1361172D01*
X1360337Y496450D01*
X1305976D01*
X1305975Y496451D01*
X1299821Y500269D01*
X1294206Y501389D01*
X1280883Y494484D01*
X1276956Y495359D01*
X1272514Y493385D01*
X1270691Y490720D01*
X1266649Y488500D01*
X1266200D01*
X1265750Y488950D01*
Y490500D01*
G01X1260930Y474540D02*
X1258140D01*
G01X1274250Y479000D02*
X1271571D01*
G01X1274250Y487500D02*
X1271836D01*
X1271662Y487326D01*
G01X1258750Y490500D02*
X1256480D01*
X1256320Y490660D01*
G01X1262900Y466504D02*
X1263200Y466204D01*
X1268250D01*
G01X1258126Y469540D02*
X1260930D01*
G01X1274250Y474000D02*
X1272060D01*
X1271640Y474420D01*
G01X1271647Y482500D02*
X1274250D01*
G01X1256350Y486080D02*
X1256930Y485500D01*
X1258750D01*
G01X1250574Y651234D02*
X1251969Y649839D01*
X1262868D01*
X1265293Y652264D01*
G01X1250574Y647294D02*
X1251969Y648689D01*
X1262868D01*
X1265293Y646264D01*
G01X1477036Y42977D02*
X1475761Y44252D01*
Y45839D01*
X1474607Y46902D01*
X1441671Y68701D01*
X1440533Y70907D01*
X1439030Y77988D01*
X1440251Y83732D01*
X1439102Y89143D01*
X1440602Y96205D01*
X1424941Y149032D01*
X1427357Y159034D01*
X1423321Y178761D01*
X1396169Y197114D01*
X1377723Y200805D01*
X1368600Y198980D01*
X1352650Y202170D01*
X1343550Y200350D01*
X1335451Y201970D01*
X1329101Y200700D01*
X1317666Y204368D01*
X1316231Y205501D01*
G01X1284290Y227739D02*
X1289584Y220043D01*
X1314905Y200262D01*
X1328656Y195762D01*
X1335302Y197090D01*
X1343500Y195451D01*
X1352500Y197251D01*
X1368450Y194061D01*
X1377821Y195935D01*
X1394295Y192640D01*
X1419019Y175925D01*
X1422412Y159335D01*
X1419884Y148855D01*
X1435549Y96003D01*
X1434095Y89157D01*
X1435244Y83751D01*
X1434020Y77989D01*
X1435813Y69540D01*
X1438132Y65036D01*
X1458437Y51597D01*
X1458438D01*
X1458565Y50973D01*
X1459691Y50228D01*
X1460314Y50355D01*
X1462870Y48664D01*
X1465361Y45509D01*
Y44252D01*
X1464086Y42977D01*
G01X1448686D02*
X1447411Y44252D01*
Y47432D01*
X1446211Y50156D01*
X1436419Y56636D01*
Y56638D01*
X1434114Y58162D01*
X1429024Y68048D01*
X1426916Y77990D01*
X1428137Y83733D01*
X1426988Y89142D01*
X1428386Y95718D01*
X1412732Y148524D01*
X1415367Y159436D01*
X1412788Y172030D01*
X1391362Y186316D01*
X1377824Y189025D01*
X1368600Y187180D01*
X1352750Y190350D01*
X1343649Y188530D01*
X1335251Y190210D01*
X1328123Y188785D01*
X1309302Y194942D01*
X1303647Y199358D01*
X1303646D01*
G01X1296586Y198653D02*
X1306754Y190714D01*
X1327756Y183842D01*
X1335051Y185301D01*
Y185300D01*
X1343750Y183561D01*
X1353100Y185431D01*
X1368929Y182265D01*
X1377575Y183994D01*
X1389735Y181559D01*
X1408380Y168935D01*
X1410384Y159120D01*
X1407737Y148139D01*
X1423333Y95520D01*
X1423334Y95517D01*
Y95516D01*
X1421978Y89143D01*
X1423127Y83733D01*
X1421907Y77991D01*
X1424427Y66104D01*
X1429768Y55733D01*
X1431633Y53868D01*
Y53231D01*
X1432588Y52277D01*
X1433224Y52276D01*
X1436138Y49362D01*
X1436711Y47981D01*
Y44252D01*
X1435436Y42977D01*
G01X1293820Y221977D02*
X1317211Y203514D01*
X1329046Y199719D01*
X1335451Y201001D01*
X1343550Y199381D01*
X1352650Y201201D01*
X1368600Y198011D01*
X1377723Y199836D01*
X1395794Y196220D01*
X1422467Y178190D01*
X1426383Y159051D01*
X1423957Y149007D01*
X1439622Y96166D01*
X1438130Y89143D01*
X1439279Y83732D01*
X1438058Y77988D01*
X1439630Y70585D01*
X1440940Y68045D01*
X1467899Y50201D01*
X1468026Y49577D01*
X1469152Y48832D01*
X1469775Y48959D01*
X1470901Y48214D01*
X1471028Y47591D01*
X1472154Y46846D01*
X1472778Y46973D01*
X1474019Y46151D01*
X1474811Y45422D01*
Y44252D01*
X1473536Y42977D01*
G01X1445186D02*
X1446461Y44252D01*
Y47232D01*
X1445453Y49517D01*
X1441987Y51811D01*
X1441364Y51684D01*
X1440238Y52430D01*
X1440111Y53053D01*
X1438985Y53798D01*
X1438362Y53671D01*
X1437236Y54417D01*
X1437109Y55040D01*
X1435469Y56125D01*
Y56127D01*
X1433383Y57506D01*
X1428121Y67726D01*
X1425944Y77990D01*
X1427165Y83733D01*
X1426016Y89141D01*
X1427406Y95679D01*
X1411748Y148499D01*
X1414393Y159453D01*
X1411935Y171456D01*
X1390991Y185421D01*
X1377824Y188056D01*
X1368600Y186211D01*
X1352750Y189381D01*
X1343649Y187561D01*
X1335249Y189241D01*
Y189240D01*
X1328065Y187804D01*
X1308849Y194089D01*
X1308848Y194090D01*
X1281987Y215066D01*
G01X1438936Y42977D02*
X1437661Y44252D01*
Y48170D01*
X1436944Y49901D01*
X1430545Y56300D01*
X1425330Y66426D01*
X1422879Y77991D01*
X1424099Y83733D01*
X1422950Y89143D01*
X1424314Y95556D01*
X1408721Y148164D01*
X1411358Y159103D01*
X1409234Y169505D01*
X1390110Y182454D01*
X1377575Y184963D01*
X1368929Y183234D01*
X1353100Y186400D01*
X1343750Y184530D01*
X1335050Y186270D01*
X1327814Y184823D01*
X1307208Y191566D01*
X1286850Y207463D01*
G01X1426286Y42977D02*
X1427561Y44252D01*
Y49653D01*
X1427010Y50886D01*
X1426416Y51113D01*
X1425865Y52345D01*
X1426092Y52940D01*
X1425542Y54172D01*
X1424947Y54400D01*
X1424396Y55632D01*
X1424624Y56227D01*
X1420553Y65337D01*
X1417868Y77990D01*
Y77992D01*
X1417869Y77993D01*
X1419088Y83731D01*
X1417939Y89145D01*
X1419262Y95359D01*
X1411690Y120900D01*
X1403664Y147975D01*
X1406408Y159341D01*
X1404840Y166717D01*
X1389007Y177438D01*
X1376874Y179866D01*
X1368900Y178271D01*
X1352850Y181481D01*
X1343700Y179651D01*
X1334999Y181391D01*
X1334997Y181390D01*
X1327458Y179882D01*
X1303457Y187732D01*
X1288111Y199713D01*
G01X1341740Y306760D02*
X1339915D01*
X1339404Y307271D01*
Y310700D01*
X1337528Y312576D01*
X1336005Y313215D01*
X1330390Y312091D01*
X1285537Y330532D01*
X1285536Y330531D01*
G01X1397635Y307630D02*
X1395810D01*
X1395360Y308080D01*
Y312848D01*
X1396027Y314307D01*
X1395184Y317674D01*
X1399770Y328512D01*
X1398971Y331410D01*
X1397042Y334304D01*
X1389634Y339242D01*
X1377494Y341671D01*
X1375459Y343027D01*
X1373304Y346258D01*
X1362801Y348360D01*
X1357122Y347225D01*
X1349394Y348771D01*
X1341504Y354031D01*
X1334382Y355456D01*
X1328824Y354345D01*
X1321823Y355821D01*
X1315649Y354588D01*
X1308380Y356121D01*
X1289194Y368905D01*
X1282412Y386838D01*
G01X1287176Y385127D02*
X1288378Y381950D01*
X1292233Y371762D01*
X1310429Y359624D01*
X1315269Y358602D01*
X1321499Y359848D01*
X1328384Y358397D01*
X1333878Y359494D01*
X1344780Y357313D01*
X1349914Y353890D01*
X1356343Y352603D01*
X1372945Y355926D01*
X1386189Y353283D01*
X1394568Y354959D01*
X1399274Y351815D01*
X1401925Y338582D01*
X1403824Y336683D01*
Y325238D01*
X1406262Y322800D01*
Y308080D01*
X1406712Y307630D01*
X1408537D01*
G01X1413720Y307634D02*
X1415586Y307621D01*
X1416055Y308086D01*
X1416057Y308388D01*
X1416056D01*
Y308427D01*
X1416059Y308709D01*
Y320739D01*
X1413117Y323681D01*
Y338751D01*
X1403704Y348164D01*
Y351385D01*
X1402107Y353779D01*
X1395559Y358154D01*
X1386081Y356257D01*
X1371897Y359088D01*
X1356614Y356028D01*
X1353235Y356701D01*
X1345017Y362177D01*
X1338744Y363500D01*
X1328343Y361420D01*
X1311501Y365522D01*
X1310909Y365161D01*
X1309548Y365493D01*
X1309188Y366085D01*
X1307828Y366416D01*
X1306997Y366969D01*
X1306373Y366844D01*
X1305249Y367592D01*
X1305124Y368216D01*
X1304001Y368965D01*
X1303377Y368840D01*
X1302253Y369589D01*
X1302129Y370213D01*
X1301005Y370961D01*
X1300381Y370837D01*
X1299258Y371585D01*
X1299133Y372209D01*
X1298009Y372958D01*
X1297385Y372833D01*
X1296262Y373582D01*
X1296137Y374206D01*
X1293824Y375747D01*
X1291431Y382075D01*
G01X1392135Y307630D02*
X1393960D01*
X1394410Y308080D01*
Y313055D01*
X1395024Y314399D01*
X1394185Y317751D01*
X1395219Y320196D01*
X1394980Y320786D01*
X1395506Y322029D01*
X1396096Y322268D01*
X1396622Y323512D01*
X1396383Y324101D01*
X1396909Y325345D01*
X1397499Y325584D01*
X1398766Y328578D01*
X1398097Y331005D01*
X1396356Y333618D01*
X1389263Y338347D01*
X1387939Y338612D01*
X1387410Y338259D01*
X1386086Y338524D01*
X1385733Y339053D01*
X1384409Y339318D01*
X1383880Y338965D01*
X1382556Y339230D01*
X1382203Y339760D01*
X1377123Y340776D01*
X1374773Y342341D01*
X1372730Y345404D01*
X1362801Y347391D01*
X1357122Y346256D01*
X1349023Y347876D01*
X1341133Y353136D01*
X1334382Y354487D01*
X1328819Y353375D01*
X1321818Y354851D01*
X1315644Y353618D01*
X1308005Y355229D01*
X1288413Y368283D01*
X1284195Y379437D01*
G01X1403037Y307630D02*
X1404862D01*
X1405312Y308080D01*
Y312181D01*
X1404862Y312631D01*
Y313981D01*
X1405312Y314431D01*
Y315781D01*
X1404862Y316231D01*
Y317581D01*
X1405312Y318031D01*
Y322406D01*
X1402874Y324844D01*
Y336289D01*
X1401049Y338113D01*
X1400784Y339437D01*
X1400254Y339790D01*
X1399989Y341113D01*
X1400342Y341643D01*
X1400077Y342967D01*
X1399547Y343319D01*
X1399282Y344643D01*
X1399635Y345173D01*
X1398419Y351243D01*
X1394368Y353950D01*
X1386189Y352314D01*
X1372945Y354957D01*
X1356343Y351634D01*
X1349543Y352995D01*
X1344409Y356418D01*
X1333878Y358525D01*
X1328379Y357427D01*
X1321494Y358878D01*
X1315264Y357632D01*
X1310054Y358732D01*
X1291452Y371141D01*
X1290105Y374700D01*
G01X1288657Y392100D02*
X1289764Y389170D01*
X1294605Y376369D01*
X1308216Y367300D01*
X1328363Y362393D01*
X1338749Y364470D01*
X1345392Y363069D01*
X1353605Y357598D01*
X1356614Y356997D01*
X1371897Y360057D01*
X1386081Y357226D01*
X1395759Y359163D01*
X1402793Y354464D01*
X1404654Y351673D01*
Y348558D01*
X1414067Y339145D01*
Y324075D01*
X1417009Y321133D01*
Y308703D01*
X1417005Y308063D01*
X1417451Y307611D01*
X1419333Y307598D01*
G01X1430570Y457961D02*
X1424211Y456556D01*
X1413573Y459430D01*
X1413572Y459431D01*
X1402935Y462306D01*
X1395221Y460027D01*
X1360754D01*
X1360313Y460468D01*
X1320859D01*
X1317727Y463600D01*
X1314480D01*
X1314086Y463206D01*
Y462030D01*
G01X1339022Y464337D02*
Y465243D01*
X1339856Y466077D01*
X1365029D01*
X1367171Y463935D01*
X1394063D01*
X1403325Y466675D01*
X1421619Y461733D01*
G01X1437930Y459805D02*
X1434508D01*
X1424234Y457534D01*
X1402923Y463294D01*
X1395083Y460977D01*
X1361148D01*
X1360707Y461418D01*
X1321253D01*
X1318121Y464550D01*
X1314580D01*
X1314130Y465000D01*
Y466600D01*
G01X1304200Y462030D02*
X1307086D01*
G01X1329419Y464337D02*
X1332022D01*
G01X1417111Y466941D02*
X1417110Y466942D01*
X1403015Y470751D01*
X1393783Y468018D01*
X1370438D01*
X1368506Y469950D01*
X1346238D01*
X1341707Y474481D01*
X1332588D01*
X1331963Y473856D01*
Y472592D01*
G01X1307363Y480350D02*
X1352186D01*
X1357636Y474900D01*
X1370600D01*
X1372645Y472855D01*
X1391265D01*
X1399492Y475292D01*
X1399796Y475852D01*
X1401090Y476235D01*
X1401650Y475932D01*
X1402944Y476315D01*
X1423402Y470787D01*
X1425130Y471133D01*
G01X1391987Y482515D02*
X1387982Y479679D01*
X1375684D01*
X1371693Y483670D01*
X1358627D01*
X1354634Y487663D01*
X1291763D01*
X1286232Y482132D01*
Y478164D01*
X1284068Y476000D01*
X1281700D01*
X1281250Y475550D01*
Y474000D01*
G01X1351800Y491619D02*
X1304842D01*
X1297333Y495505D01*
X1294421Y496070D01*
X1288643Y492672D01*
X1285108Y486496D01*
X1282626Y484525D01*
X1281701D01*
X1281250Y484074D01*
Y482500D01*
G01X1331863Y477492D02*
Y475908D01*
X1332340Y475431D01*
X1342101D01*
X1346632Y470900D01*
X1368900D01*
X1370832Y468968D01*
X1393645D01*
X1403003Y471739D01*
X1414485Y468635D01*
X1422665Y466425D01*
X1423664Y466156D01*
X1430584Y467544D01*
G01X1404310Y492405D02*
X1387679Y480629D01*
X1376078D01*
X1372087Y484620D01*
X1359021D01*
X1355028Y488613D01*
X1291369D01*
X1285282Y482526D01*
Y478558D01*
X1283674Y476950D01*
X1281664D01*
X1281250Y477364D01*
Y479000D01*
G01X1435336Y501750D02*
X1429051D01*
X1418900Y503780D01*
X1409928Y501986D01*
X1406128Y499452D01*
X1401128Y496118D01*
X1398067Y494076D01*
X1393498Y491029D01*
X1376375D01*
X1375419Y490073D01*
X1360963D01*
X1358467Y492569D01*
X1310700D01*
G01X1281250Y487500D02*
Y485750D01*
X1281525Y485475D01*
X1282294D01*
X1284373Y487127D01*
X1287943Y493364D01*
X1294249Y497072D01*
X1297648Y496412D01*
X1305074Y492569D01*
X1310700D01*
G01X1339022Y469337D02*
Y467861D01*
X1339856Y467027D01*
X1365423D01*
X1367565Y464885D01*
X1393925D01*
X1403313Y467663D01*
X1409867Y465892D01*
X1412123Y465283D01*
G01X1322260Y477492D02*
X1324863D01*
G01X1307130Y466600D02*
X1304200D01*
G01X1329419Y469337D02*
X1332022D01*
G01X1322360Y472592D02*
X1324963D01*
G01X1495336Y43077D02*
X1494050Y44363D01*
Y45928D01*
X1490125Y48970D01*
X1485165Y50034D01*
X1469997Y60068D01*
X1464395Y73463D01*
X1465784Y80438D01*
X1464474Y86872D01*
X1465879Y93894D01*
X1460798Y119278D01*
X1437147Y136142D01*
X1433184Y149504D01*
X1435538Y159251D01*
X1430679Y183133D01*
X1395345Y207061D01*
X1360253Y214274D01*
G01X1371373Y211018D02*
X1394969Y206168D01*
X1394968D01*
X1429825Y182563D01*
X1434564Y159269D01*
X1432200Y149479D01*
X1436329Y135558D01*
X1459940Y118723D01*
X1464910Y93894D01*
X1463504Y86870D01*
X1464814Y80436D01*
X1463406Y73364D01*
X1463996Y71954D01*
X1463754Y71365D01*
X1464275Y70119D01*
X1464864Y69878D01*
X1465385Y68633D01*
X1465143Y68044D01*
X1465664Y66798D01*
X1466253Y66557D01*
X1466774Y65311D01*
X1466532Y64723D01*
X1467053Y63477D01*
X1467642Y63236D01*
X1469231Y59434D01*
X1484790Y49142D01*
X1489714Y48086D01*
X1493100Y45462D01*
Y44341D01*
X1491836Y43077D01*
G01X1432813Y496700D02*
X1427394D01*
X1417799Y498620D01*
X1413526Y497765D01*
X1391987Y482515D01*
G01X1435336Y500800D02*
X1428956D01*
X1418900Y502811D01*
X1410299Y501091D01*
X1401655Y495326D01*
X1398594Y493285D01*
X1393786Y490079D01*
X1376769D01*
X1375813Y489123D01*
X1360569D01*
X1358073Y491619D01*
X1351800D01*
G01X1371874Y494665D02*
X1373655D01*
X1379990Y501000D01*
X1402799D01*
X1408288Y504658D01*
X1408447Y504689D01*
X1408450Y504690D01*
X1418950Y506790D01*
X1427900Y505000D01*
X1444813D01*
G01X1349779Y479400D02*
X1351792D01*
X1357242Y473950D01*
X1370206D01*
X1372251Y471905D01*
X1391403D01*
X1402956Y475327D01*
X1423369Y469811D01*
X1425315Y470201D01*
G01X1444813Y505950D02*
X1440279D01*
X1439829Y506400D01*
X1438479D01*
X1438029Y505950D01*
X1427995D01*
X1418950Y507759D01*
X1408450Y505661D01*
X1408447Y505660D01*
X1407917Y505554D01*
X1402511Y501950D01*
X1400050D01*
G01X1464115Y17283D02*
Y14661D01*
X1463008Y13554D01*
Y12108D01*
X1463553Y11563D01*
X1465237D01*
G01X1454666Y17283D02*
Y14530D01*
X1453748Y13612D01*
Y10446D01*
X1452966Y9664D01*
Y6039D01*
X1453416Y5589D01*
X1454991D01*
G01X1442067Y17283D02*
Y14600D01*
X1443161Y13506D01*
Y12014D01*
X1442710Y11563D01*
X1441340D01*
G01X1435768Y17283D02*
Y14812D01*
X1434568Y13612D01*
Y11425D01*
X1433900Y10757D01*
Y8700D01*
X1434844Y7756D01*
X1436025D01*
G01X1426319Y17283D02*
Y14660D01*
X1425213Y13554D01*
Y12108D01*
X1425758Y11563D01*
X1427442D01*
G01X1460965Y17283D02*
Y14599D01*
X1462058Y13506D01*
Y12014D01*
X1461607Y11563D01*
X1460237D01*
G01X1451516Y17283D02*
Y14778D01*
X1452798Y13496D01*
Y10840D01*
X1452016Y10058D01*
Y6039D01*
X1451566Y5589D01*
X1449991D01*
G01X1445217Y17283D02*
Y14660D01*
X1444111Y13554D01*
Y12108D01*
X1444656Y11563D01*
X1446340D01*
G01X1432619Y17283D02*
Y14575D01*
X1433618Y13576D01*
Y11819D01*
X1432950Y11151D01*
Y8632D01*
X1432074Y7756D01*
X1431025D01*
G01X1423170Y17283D02*
Y14599D01*
X1424263Y13506D01*
Y12014D01*
X1423812Y11563D01*
X1422442D01*
G01X1464115Y30669D02*
Y33851D01*
X1465368Y35104D01*
Y38195D01*
X1464086Y39477D01*
G01X1457815Y30669D02*
Y33850D01*
X1456802Y34863D01*
Y38143D01*
X1458136Y39477D01*
G01X1448367Y30669D02*
Y33850D01*
X1447267Y34950D01*
Y38058D01*
X1448686Y39477D01*
G01X1435768Y30669D02*
Y33850D01*
X1436748Y34830D01*
Y38165D01*
X1435436Y39477D01*
G01X1429469Y30669D02*
Y33850D01*
X1428511Y34808D01*
Y38202D01*
X1429786Y39477D01*
G01X1454666Y30669D02*
Y33851D01*
X1455852Y35037D01*
Y38261D01*
X1454636Y39477D01*
G01X1445217Y30669D02*
Y33850D01*
X1446317Y34950D01*
Y38346D01*
X1445186Y39477D01*
G01X1438918Y30669D02*
Y33850D01*
X1437698Y35070D01*
Y38239D01*
X1438936Y39477D01*
G01X1426319Y30669D02*
Y33850D01*
X1427561Y35092D01*
Y38202D01*
X1426286Y39477D01*
G01X1410571Y30669D02*
Y33130D01*
X1409523Y34178D01*
Y42589D01*
X1410050Y43116D01*
X1411546D01*
G01X1407422Y30669D02*
Y33023D01*
X1408573Y34174D01*
Y42627D01*
X1408084Y43116D01*
X1406546D01*
G01X1420337Y39477D02*
X1419062Y38202D01*
Y34808D01*
X1420020Y33850D01*
Y30669D01*
G01X1416837Y39477D02*
X1418112Y38202D01*
Y35090D01*
X1416871Y33849D01*
G01X1439000Y437000D02*
X1441175Y439175D01*
X1442800D01*
G01D02*
X1449032D01*
G01X1449346Y450275D02*
X1443000D01*
G01D02*
X1441275D01*
X1439000Y448000D01*
G01Y442500D02*
X1441375Y440125D01*
X1447800D01*
G01X1449032D02*
X1447800D01*
G01X1449346Y451225D02*
X1448000D01*
G01D02*
X1441275D01*
X1439000Y453500D01*
G01X1448000Y431500D02*
X1451000D01*
G01X1435500Y437000D02*
X1432000D01*
X1431900Y437100D01*
G01X1447700Y442500D02*
X1451000D01*
G01X1435500Y448000D02*
X1431900D01*
G01X1448000Y437000D02*
X1451000D01*
G01X1435500Y442500D02*
X1432000D01*
X1431900Y442600D01*
G01X1447500Y448000D02*
X1451000D01*
G01X1435500Y453500D02*
X1431900D01*
G01X1444550Y412364D02*
X1451219D01*
X1451754Y412899D01*
X1452802D01*
X1454069Y414166D01*
G01X1439651Y412466D02*
X1440848Y411269D01*
X1441477D01*
X1442572Y412364D01*
X1444550D01*
G01X1449350Y411414D02*
X1451613D01*
X1452148Y411949D01*
X1452786D01*
X1454069Y410666D01*
G01X1439813Y409422D02*
X1440710Y410319D01*
X1441871D01*
X1442966Y411414D01*
X1449350D01*
G01X1440200Y458855D02*
X1434612D01*
X1430570Y457961D01*
G01X1433023Y462477D02*
X1425261Y460749D01*
X1421619Y461733D01*
G01X1440200Y459805D02*
X1437930D01*
G01X1432817Y463405D02*
X1425283Y461728D01*
X1412123Y465283D01*
G01X1432500Y466959D02*
X1423632Y465180D01*
X1417112Y466942D01*
X1417111Y466941D01*
G01X1428642Y485300D02*
X1421608D01*
G01X1432314Y467891D02*
X1430584Y467544D01*
G01X1428642Y486250D02*
X1426993D01*
G01X1432813Y497650D02*
X1427489D01*
X1417799Y499589D01*
X1413141Y498658D01*
X1404310Y492405D01*
G01X1473563Y17283D02*
Y14812D01*
X1472363Y13612D01*
Y6039D01*
X1472813Y5589D01*
X1474388D01*
G01X1493770Y6909D02*
X1492263D01*
X1491813Y7359D01*
Y10587D01*
X1491461Y10939D01*
Y13339D01*
X1492461Y14339D01*
Y17283D01*
G01X1483012D02*
Y14660D01*
X1481906Y13554D01*
Y12108D01*
X1482451Y11563D01*
X1484135D01*
G01X1470414Y17283D02*
Y14575D01*
X1471413Y13576D01*
Y6039D01*
X1470963Y5589D01*
X1469388D01*
G01X1488770Y6909D02*
X1490413D01*
X1490863Y7359D01*
Y10193D01*
X1490511Y10545D01*
Y13139D01*
X1489311Y14339D01*
Y17283D01*
G01X1479863D02*
Y14599D01*
X1480459Y14004D01*
X1480956Y13506D01*
Y12014D01*
X1480505Y11563D01*
X1479135D01*
G01X1476713Y30669D02*
Y33850D01*
X1475758Y34805D01*
Y38199D01*
X1477036Y39477D01*
G01X1492461Y30669D02*
Y33850D01*
X1493511Y34900D01*
Y36100D01*
X1493100Y36511D01*
Y38313D01*
X1491836Y39577D01*
G01X1486162Y30669D02*
Y33850D01*
X1485239Y34773D01*
Y38230D01*
X1486486Y39477D01*
G01X1473563Y30669D02*
Y33850D01*
X1474808Y35095D01*
Y38205D01*
X1473536Y39477D01*
G01X1467264Y30669D02*
Y33850D01*
X1466318Y34796D01*
Y38209D01*
X1467586Y39477D01*
G01X1495611Y30669D02*
Y33850D01*
X1494461Y35000D01*
Y36494D01*
X1494050Y36905D01*
Y38291D01*
X1495336Y39577D01*
G01X1483012Y30669D02*
Y33850D01*
X1484289Y35127D01*
Y38174D01*
X1482986Y39477D01*
G01X1507076Y87681D02*
X1503307D01*
X1502768Y88220D01*
X1501414D01*
X1499875Y86681D01*
G01X1507076Y89649D02*
X1503249D01*
X1503248Y89650D01*
X1502768Y89170D01*
X1501186D01*
X1499875Y90481D01*
G01X1513335Y92921D02*
X1511992Y94264D01*
X1510524D01*
X1509846Y93586D01*
X1507076D01*
G01X1483366Y120746D02*
X1483666Y121046D01*
X1485842D01*
X1486300Y120588D01*
G01X1483366Y115902D02*
X1485486D01*
X1486300Y115088D01*
G01X1484113Y128513D02*
X1487929D01*
X1489192Y127250D01*
G01Y132750D02*
Y131292D01*
X1488435Y130535D01*
X1486891D01*
X1485755Y131671D01*
G01X1507076Y111303D02*
X1503345D01*
X1502712Y111936D01*
X1501458D01*
X1500455Y110933D01*
G01X1507076Y99492D02*
X1503307D01*
X1502467Y100332D01*
X1499515D01*
X1498705Y99522D01*
G01X1500455Y114388D02*
X1501957Y112886D01*
X1502862D01*
X1503248Y113272D01*
X1503249Y113271D01*
X1507076D01*
G01Y101460D02*
X1503249D01*
X1503248Y101461D01*
X1503069Y101282D01*
X1500375D01*
X1498911Y102746D01*
X1498660D01*
G01X1507076Y125082D02*
X1503666D01*
X1500568Y121984D01*
Y120079D01*
X1499028Y118539D01*
X1490322D01*
X1489800Y119061D01*
Y120588D01*
G01X1507076Y123114D02*
X1503042D01*
X1501518Y121590D01*
Y119685D01*
X1499422Y117589D01*
X1490442D01*
X1489800Y116947D01*
Y115088D01*
G01X1507076Y129019D02*
X1502560D01*
X1502050Y129529D01*
X1493607D01*
X1492692Y128614D01*
Y127250D01*
G01X1507076Y130988D02*
X1502559D01*
X1502050Y130479D01*
X1493607D01*
X1492692Y131394D01*
Y132750D01*
G01X1507076Y117208D02*
X1509846D01*
X1510356Y117718D01*
X1512560D01*
X1513935Y116343D01*
G01Y104532D02*
X1512486Y105981D01*
X1510430D01*
X1509846Y105397D01*
X1507076D01*
G01X1513935Y120143D02*
X1512460Y118668D01*
X1510356D01*
X1509847Y119177D01*
X1507076D01*
G01X1513935Y108332D02*
X1512534Y106931D01*
X1510282D01*
X1509847Y107366D01*
X1507076D01*
G01X1513013Y96546D02*
X1511681Y95214D01*
X1510188D01*
X1509847Y95555D01*
X1507076D01*
G01X1493300Y120588D02*
X1496726D01*
G01X1493300Y115088D02*
X1496658D01*
G01X1496192Y127250D02*
X1497175D01*
X1497561Y126864D01*
X1500314D01*
X1500700Y127250D01*
G01X1496192Y132750D02*
X1500217D01*
X1500806Y133339D01*
G01X1491425Y397794D02*
X1489475Y398700D01*
G01X1524950Y441950D02*
X1523375Y440375D01*
G01X1521800Y441950D02*
X1520225Y440375D01*
G01X1512350Y445100D02*
X1513925Y446675D01*
G01X1515500Y445100D02*
X1513925Y446675D01*
G01X1507625Y452975D02*
X1506647Y453953D01*
G01X1520675Y457066D02*
Y455560D01*
X1519597Y454482D01*
X1518582D01*
X1517075Y452975D01*
G01X1507625Y443525D02*
X1506794Y444356D01*
X1505898D01*
X1505442Y443900D01*
G01X1522154Y439151D02*
X1523375Y440372D01*
Y440375D01*
G01X1527643Y441500D02*
X1526525Y440382D01*
Y440375D01*
G01X1510775Y452975D02*
X1512300Y454500D01*
G01D02*
X1512400D01*
G01X1487525Y449400D02*
X1489475Y450306D01*
G01Y452780D02*
X1491425Y453686D01*
G01Y456160D02*
X1493375Y457066D01*
G01X1497275Y459540D02*
X1499225Y460446D01*
G01X1491425Y449400D02*
X1491426D01*
X1493375Y450306D01*
G01X1487525Y456160D02*
X1489475Y457066D01*
G01X1495325Y460446D02*
X1493375Y459540D01*
G01X1495325Y462920D02*
X1497275Y463826D01*
G01X1524950Y445100D02*
X1523375Y443525D01*
G01X1524950Y445100D02*
X1526525Y446675D01*
G01Y443525D02*
X1527422Y444422D01*
G01X1524950Y435650D02*
X1526525Y437225D01*
G01X1524950Y426200D02*
X1526525Y424625D01*
G01X1520225D02*
X1518650Y426200D01*
G01X1509200D02*
X1507625Y427775D01*
G01Y424625D02*
X1509200Y426200D01*
G01X1513925Y424625D02*
X1515500Y426200D01*
G01X1513925Y424625D02*
X1512350Y426200D01*
G01X1520225Y427775D02*
X1518650Y429350D01*
G01X1517075Y427775D02*
X1515500Y429350D01*
G01X1513925Y427775D02*
X1512350Y429350D01*
G01X1515500D02*
X1513925Y427775D01*
G01X1518650Y429350D02*
X1517075Y427775D01*
G01Y421475D02*
X1515500Y423050D01*
G01X1513925Y421475D02*
X1512350Y423050D01*
G01X1510775Y418325D02*
X1512350Y419900D01*
G01X1510775Y418325D02*
X1509200Y419900D01*
G01X1507625Y418325D02*
X1509200Y419900D01*
G01X1510775Y421475D02*
X1512350Y419900D01*
G01Y423050D02*
X1510775Y424625D01*
G01Y421475D02*
X1512350Y423050D01*
G01X1513925Y421475D02*
X1515500Y419900D01*
G01Y423050D02*
X1513925Y424625D01*
G01Y421475D02*
X1515500Y423050D01*
G01X1512350Y426200D02*
X1510775Y427775D01*
G01Y424625D02*
X1512350Y426200D01*
G01X1509200D02*
X1510775Y424625D01*
G01X1512350Y429350D02*
X1510775Y427775D01*
G01X1509200Y423050D02*
X1510775Y421475D01*
G01X1509200Y429350D02*
X1510775Y427775D01*
G01X1518650Y426200D02*
X1517075Y427775D01*
G01X1515500Y426200D02*
X1513925Y427775D01*
G01X1520225Y430925D02*
X1519224Y431926D01*
G01X1507625Y424625D02*
X1506615Y425635D01*
G01X1507625Y430925D02*
X1506739Y431811D01*
G01X1512350Y416750D02*
X1510775Y418325D01*
G01X1518650Y423050D02*
X1517075Y421475D01*
G01X1518650Y435650D02*
X1520225Y437225D01*
G01X1517075Y440375D02*
X1515500Y438800D01*
G01X1512350D02*
X1513925Y440375D01*
G01X1510775D02*
X1512350Y438800D01*
G01X1513925Y434075D02*
X1512350Y435650D01*
G01D02*
X1510775Y437225D01*
G01Y434075D02*
X1512350Y435650D01*
G01X1509200Y438800D02*
X1510775Y440375D01*
G01X1507625D02*
X1509200Y438800D01*
G01D02*
X1507625Y437225D01*
G01X1512350Y438800D02*
X1510775Y437225D01*
G01X1509200Y435650D02*
X1510775Y437225D01*
G01X1515500Y438800D02*
X1513925Y440375D01*
G01X1518650Y438800D02*
X1517075Y440375D01*
G01X1520225Y434075D02*
X1518912Y432762D01*
G01X1507625Y440375D02*
X1506573Y439323D01*
G01X1515500Y441950D02*
X1513925Y440375D01*
G01X1512350Y441950D02*
X1510775Y440375D01*
G01X1505605Y423604D02*
X1506000Y423999D01*
Y424815D01*
G01X1507625Y440375D02*
X1506632Y441368D01*
G01X1507625Y424625D02*
X1506604Y423604D01*
G01X1506000Y424815D02*
X1505075Y425740D01*
G01X1506632Y441368D02*
X1505715D01*
G01X1506604Y423604D02*
X1505605D01*
G01X1489475Y459540D02*
X1491425Y460446D01*
G01X1487525Y462920D02*
X1487825Y463743D01*
X1488650Y464126D01*
X1489475Y463826D01*
G01X1485575Y459540D02*
X1487525Y460446D01*
G01X1485575Y466300D02*
X1485031Y463691D01*
X1485030Y463690D01*
G01X1567064Y522361D02*
X1564771D01*
G01Y523311D02*
X1576796D01*
G01X1497275Y466300D02*
X1499212Y467200D01*
X1499225Y467206D01*
G01X1489475Y466300D02*
X1489672Y466839D01*
X1490887Y467402D01*
X1491425Y467206D01*
G01X1495325Y469680D02*
X1495583Y469800D01*
X1497275Y470586D01*
G01X1495325Y476440D02*
X1497275Y477346D01*
G01X1487525Y476440D02*
X1489475Y477346D01*
G01X1497275Y473060D02*
X1499225Y473966D01*
G01X1495325Y467206D02*
X1493375Y466300D01*
G01X1491425Y469680D02*
X1493375Y470586D01*
G01X1495325Y473966D02*
X1493375Y473060D01*
G01X1491425Y476440D02*
X1493375Y477346D01*
G01X1489475Y479820D02*
X1491154Y480600D01*
X1491425Y480726D01*
G01X1499225Y476440D02*
X1499481Y477140D01*
X1500476Y477601D01*
X1501175Y477346D01*
G01X1526525Y483200D02*
X1528475Y484106D01*
G01X1518725Y483200D02*
X1520675Y484106D01*
G01X1522625Y476440D02*
X1524575Y477346D01*
G01X1510925Y476440D02*
X1512875Y477346D01*
G01X1495325Y483200D02*
X1497275Y484106D01*
G01Y486580D02*
X1499225Y487486D01*
G01X1501175Y473060D02*
X1501600Y473257D01*
X1503125Y473966D01*
G01X1505075Y473060D02*
X1505300Y473164D01*
X1507025Y473966D01*
G01X1499225Y483200D02*
X1501175Y484106D01*
G01X1503125Y483200D02*
X1504600Y483885D01*
X1505075Y484106D01*
G01X1501175Y479820D02*
X1501600Y480017D01*
X1502854Y480600D01*
X1503125Y480726D01*
G01Y476440D02*
X1503379Y477134D01*
X1504380Y477599D01*
X1504382Y477600D01*
X1505075Y477346D01*
G01X1507025Y483200D02*
X1508254D01*
X1508776Y483565D01*
X1508975Y484106D01*
G01X1505075Y479820D02*
X1505300Y479924D01*
X1507025Y480726D01*
G01X1508975Y486580D02*
X1510925Y487486D01*
G01Y483200D02*
X1512875Y484106D01*
G01X1491425Y483200D02*
X1493375Y484106D01*
G01X1489475Y486580D02*
X1490152Y486333D01*
X1491178Y486809D01*
X1491425Y487486D01*
G01X1493375Y479820D02*
X1495054Y480600D01*
X1495325Y480726D01*
G01Y487486D02*
X1493375Y486580D01*
G01X1524575Y479820D02*
X1524838Y479942D01*
X1526254Y480600D01*
X1526525Y480726D01*
G01X1522625Y483200D02*
X1524575Y484106D01*
G01X1520675Y479820D02*
X1522625Y480726D01*
G01X1514825Y476440D02*
X1516775Y477346D01*
G01X1524415Y651234D02*
X1522992Y649811D01*
X1512121D01*
X1509696Y652236D01*
G01X1524415Y647294D02*
X1523048Y648661D01*
X1512121D01*
X1509696Y646236D01*
G01X1586109Y17268D02*
Y14796D01*
X1585009Y13696D01*
Y12064D01*
X1585718Y11355D01*
X1586998D01*
G01X1577048Y12506D02*
X1575794D01*
X1575559Y12741D01*
Y13696D01*
X1576659Y14796D01*
Y17268D01*
G01X1567498Y12506D02*
X1566394D01*
X1566009Y12891D01*
Y13596D01*
X1567209Y14796D01*
Y17268D01*
G01X1554609D02*
Y14796D01*
X1555709Y13696D01*
Y12809D01*
X1555206Y12306D01*
X1554148D01*
G01X1548698Y12506D02*
X1547762D01*
X1547209Y13059D01*
Y13696D01*
X1548309Y14796D01*
Y17268D01*
G01X1582959D02*
Y14796D01*
X1584059Y13696D01*
Y11978D01*
X1583436Y11355D01*
X1581998D01*
G01X1573048Y12506D02*
X1574306D01*
X1574609Y12809D01*
Y13696D01*
X1573509Y14796D01*
Y17268D01*
G01X1563498Y12506D02*
X1564606D01*
X1565059Y12959D01*
Y13796D01*
X1564059Y14796D01*
Y17268D01*
G01X1557759D02*
Y14796D01*
X1556659Y13696D01*
Y12841D01*
X1557194Y12306D01*
X1558148D01*
G01X1544698Y12506D02*
X1545706D01*
X1546259Y13059D01*
Y13696D01*
X1545159Y14796D01*
Y17268D01*
G01X1579998Y39484D02*
X1578723Y38209D01*
Y34934D01*
X1579809Y33848D01*
Y30668D01*
G01X1570548Y39484D02*
X1569273Y38209D01*
Y34934D01*
X1570359Y33848D01*
Y30668D01*
G01X1560898Y39684D02*
X1559623Y38409D01*
Y35134D01*
X1560909Y33848D01*
Y30668D01*
G01X1551748Y39484D02*
X1550473Y38209D01*
Y34834D01*
X1551459Y33848D01*
Y30668D01*
G01X1585948Y39484D02*
X1587223Y38209D01*
Y34962D01*
X1586109Y33848D01*
Y30668D01*
G01X1576498Y39484D02*
X1577773Y38209D01*
Y34962D01*
X1576659Y33848D01*
Y30668D01*
G01X1567048Y39484D02*
X1568323Y38209D01*
Y34962D01*
X1567209Y33848D01*
Y30668D01*
G01X1557398Y39684D02*
X1558673Y38409D01*
Y34762D01*
X1557759Y33848D01*
Y30668D01*
G01X1548248Y39484D02*
X1549523Y38209D01*
Y35062D01*
X1548309Y33848D01*
Y30668D01*
G01X1589448Y39484D02*
X1588173Y38209D01*
Y34934D01*
X1589259Y33848D01*
Y30668D01*
G01X1602717Y126514D02*
X1601603Y125400D01*
X1599905D01*
X1599381Y124876D01*
X1595124D01*
X1593821Y126179D01*
X1588188D01*
X1586485Y124476D01*
X1572082D01*
X1567183Y129375D01*
X1565079D01*
G01X1558100Y128926D02*
Y128006D01*
X1558856Y127250D01*
X1559706D01*
X1561831Y129375D01*
X1565079D01*
G01X1569492Y125722D02*
X1571688Y123526D01*
X1586879D01*
X1588582Y125229D01*
X1593427D01*
X1594730Y123926D01*
X1599775D01*
X1600299Y124450D01*
X1601632D01*
X1602717Y123365D01*
G01X1569492Y125722D02*
X1566789Y128425D01*
X1562225D01*
X1560100Y126300D01*
X1559250D01*
X1558100Y125150D01*
Y124427D01*
G01X1554627Y100877D02*
X1555277D01*
X1556050Y101650D01*
Y102894D01*
X1558386Y105230D01*
X1561986D01*
X1563032Y106276D01*
G01D02*
X1565133Y108377D01*
Y109013D01*
X1566087Y109968D01*
X1566724D01*
X1570681Y113925D01*
X1573691D01*
X1578842Y119076D01*
X1584542D01*
X1584992Y119526D01*
X1586342D01*
X1586792Y119076D01*
X1588142D01*
X1588592Y119526D01*
X1589942D01*
X1590392Y119076D01*
X1591742D01*
X1592192Y119526D01*
X1593542D01*
X1593992Y119076D01*
X1595342D01*
X1595792Y119526D01*
X1597142D01*
X1597592Y119076D01*
X1599173D01*
X1599497Y119400D01*
X1601902D01*
X1602717Y120215D01*
G01X1558136Y100877D02*
X1557672D01*
X1557075Y101474D01*
Y102575D01*
X1558780Y104280D01*
X1562380D01*
X1571075Y112975D01*
X1574085D01*
X1576148Y115038D01*
G01D02*
X1579236Y118126D01*
X1599567D01*
X1599882Y118441D01*
X1604093D01*
X1605867Y120215D01*
G01X1534400Y441950D02*
X1535975Y440375D01*
G01X1543850Y429350D02*
X1542275Y427775D01*
G01X1531250Y441950D02*
X1532825Y440375D01*
G01X1528350Y441741D02*
X1529675Y440416D01*
Y440375D01*
G01X1539125Y437225D02*
X1537550Y438800D01*
G01X1543300Y432567D02*
X1540633D01*
X1539125Y434075D01*
G01X1540700Y435650D02*
X1539125Y437225D01*
G01X1532825Y446675D02*
X1531250Y445100D01*
G01X1539125Y446675D02*
X1537550Y445100D01*
G01X1535975Y443525D02*
X1534400Y445100D01*
G01X1535975Y446675D02*
X1537550Y448250D01*
G01X1539125Y446675D02*
X1540700Y445100D01*
G01X1537550D02*
X1535975Y446675D01*
G01X1532825D02*
X1531250Y448250D01*
G01Y445100D02*
X1532825Y443525D01*
G01X1534400Y445100D02*
X1535975Y446675D01*
G01X1532825D02*
X1534400Y445100D01*
G01X1531250D02*
X1529675Y446675D01*
G01Y443525D02*
X1528692Y444508D01*
G01X1534400Y448250D02*
X1535975Y446675D01*
G01X1537550Y448250D02*
X1539125Y446675D01*
G01X1548889Y433423D02*
X1547975Y432509D01*
Y432500D01*
G01X1546525Y426691D02*
X1545441Y427775D01*
X1545425D01*
G01X1532825Y437225D02*
X1531250Y435650D01*
G01D02*
X1529675Y437225D01*
G01X1534400Y435650D02*
X1532825Y437225D01*
G01X1531250Y438800D02*
X1532825Y437225D01*
G01X1531250Y426200D02*
X1529675Y424625D01*
G01X1532825D02*
X1531250Y426200D01*
G01X1535975Y430925D02*
X1534400Y429350D01*
G01X1535975Y424625D02*
X1534400Y426200D01*
G01X1539125Y424625D02*
X1540700Y426200D01*
G01X1539125Y427775D02*
X1537550Y426200D01*
G01X1539125Y427775D02*
X1540700Y429350D01*
G01X1539125Y427775D02*
X1537550Y429350D01*
G01X1539125Y424625D02*
X1537550Y426200D01*
G01X1535975Y424625D02*
X1537550Y426200D01*
G01Y429350D02*
X1535975Y427775D01*
G01Y430925D02*
X1533978Y432922D01*
G01X1534400Y429350D02*
X1535975Y427775D01*
G01X1532825D02*
X1534400Y429350D01*
G01X1529675Y427775D02*
X1531250Y429350D01*
G01D02*
X1532825Y430925D01*
G01Y427775D02*
X1531250Y429350D01*
G01X1534400Y426200D02*
X1535975Y427775D01*
G01X1532825Y424625D02*
X1534400Y426200D01*
G01X1531250D02*
X1532825Y427775D01*
G01X1537550Y423050D02*
X1539125Y424625D01*
G01X1534400Y423050D02*
X1535975Y424625D01*
G01X1531250Y423050D02*
X1532825Y424625D01*
G01X1563575Y459540D02*
X1564844Y460130D01*
X1565192Y460291D01*
X1565525Y460446D01*
G01X1561625Y462920D02*
X1563575Y463826D01*
G01X1547975Y479820D02*
X1549654Y480600D01*
X1549925Y480726D01*
G01Y476440D02*
X1551875Y477346D01*
G01X1544075Y473060D02*
X1546025Y473966D01*
G01Y476440D02*
X1547975Y477346D01*
G01X1700348Y546633D02*
X1701106D01*
G03X1702373Y547900I0J1267D01*
G01Y548478D01*
G03X1700751Y550100I-1622J0D01*
G01X1697858D01*
G03X1693998Y548501I0J-5459D01*
G01X1689295Y543798D01*
G02X1685570Y542255I-3725J3725D01*
G01X1684300D01*
G03X1681968Y541289I0J-3298D01*
G01X1679029Y538350D01*
X1679004Y538326D01*
G02X1676159Y537147I-2845J2843D01*
G01X1673377D01*
G02X1668506Y542018I0J4871D01*
G01Y542765D01*
G03X1666348Y544923I-2158J0D01*
G01X1664723D01*
G03X1664273Y544698I43J-649D01*
G02X1663823Y544473I-493J424D01*
G01X1662473D01*
G02X1662023Y544698I43J649D01*
G03X1661573Y544923I-493J-424D01*
G01X1660223D01*
G03X1659773Y544698I43J-649D01*
G02X1659323Y544473I-493J424D01*
G01X1657973D01*
G02X1657523Y544698I43J649D01*
G03X1657073Y544923I-493J-424D01*
G01X1655723D01*
G03X1654089Y544246I0J-2311D01*
G01X1649509Y539666D01*
G02X1646091Y538250I-3418J3418D01*
G01X1621350D01*
G03X1615900Y532800I0J-5450D01*
G01Y531450D01*
G03X1616125Y531000I649J43D01*
G02X1616350Y530550I-424J-493D01*
G01Y529200D01*
G02X1616125Y528750I-649J43D01*
G03X1615900Y528300I424J-493D01*
G01Y526950D01*
G03X1616125Y526500I649J43D01*
G02X1616350Y526050I-424J-493D01*
G01Y524700D01*
G02X1616125Y524250I-649J43D01*
G03X1615900Y523800I424J-493D01*
G01Y522135D01*
G02X1614391Y518491I-5154J0D01*
G01X1613436Y517536D01*
G03X1613277Y517059I489J-428D01*
G02X1613118Y516582I-648J-49D01*
G01X1612164Y515627D01*
G02X1611686Y515468I-428J489D01*
G03X1611209Y515309I-49J-648D01*
G01X1607688Y511788D01*
G02X1605845Y511025I-1843J1844D01*
G01X1594516D01*
G02X1591715Y512185I0J3962D01*
G01X1582273Y521627D01*
G03X1580501Y522361I-1772J-1772D01*
G01X1567064D01*
G01X1576796Y523311D02*
X1580501D01*
G02X1582945Y522299I0J-3457D01*
G01X1592387Y512857D01*
G03X1594516Y511975I2129J2129D01*
G01X1605845D01*
G03X1607016Y512460I0J1656D01*
G01X1613719Y519163D01*
G03X1614950Y522135I-2972J2972D01*
G01Y532800D01*
G02X1621350Y539200I6400J0D01*
G01X1646090D01*
G03X1648837Y540338I0J3884D01*
G01X1653417Y544918D01*
G02X1655723Y545873I2306J-2306D01*
G01X1666348D01*
G02X1669456Y542765I0J-3108D01*
G01Y542018D01*
G03X1673377Y538097I3921J0D01*
G01X1676159D01*
G03X1678332Y538997I0J3073D01*
G01X1681296Y541961D01*
G02X1684299Y543205I3003J-3003D01*
G01X1685569D01*
G03X1688623Y544470I0J4319D01*
G01X1693326Y549173D01*
G02X1697857Y551050I4531J-4531D01*
G01X1700751D01*
G02X1703323Y548478I0J-2572D01*
G01Y547900D01*
G03X1704590Y546633I1267J0D01*
G01X1705348D01*
G01X1557725Y483200D02*
X1559675Y484106D01*
G01Y479820D02*
X1561354Y480600D01*
X1561625Y480726D01*
G01X1555775Y486580D02*
X1556000Y486685D01*
X1557725Y487486D01*
G01X1559675Y486580D02*
X1561625Y487486D01*
G01X1565525Y483200D02*
X1566100Y483467D01*
X1567475Y484106D01*
G01X1561625Y483200D02*
X1563575Y484106D01*
G01X1557725Y476440D02*
X1559675Y477346D01*
G01X1571545Y482842D02*
X1569425Y483200D01*
G01X1563575Y486580D02*
X1564844Y487170D01*
X1565192Y487331D01*
X1565525Y487486D01*
G01X1561625Y476440D02*
X1563575Y477346D01*
G01X1569425Y476440D02*
X1571375Y477346D01*
G01X1567475Y479820D02*
X1569425Y480726D01*
G01X1534325Y476440D02*
X1536275Y477346D01*
G01X1528475Y486580D02*
X1530425Y487486D01*
G01X1532375Y479820D02*
X1534054Y480600D01*
X1534325Y480726D01*
G01Y473966D02*
X1532375Y473060D01*
G01X1536275Y479820D02*
X1537954Y480600D01*
X1538225Y480726D01*
G01X1530425Y483200D02*
X1532375Y484106D01*
G01X1528475Y479820D02*
X1530154Y480600D01*
X1530425Y480726D01*
G01X1540175Y486580D02*
X1542125Y487486D01*
G01X1538225Y483200D02*
X1540175Y484106D01*
G01X1544075Y486580D02*
X1546025Y487486D01*
G01X1549925Y483200D02*
X1551875Y484106D01*
G01X1536275Y486580D02*
X1538225Y487486D01*
G01X1540175Y479820D02*
X1541854Y480600D01*
X1542125Y480726D01*
G01Y483200D02*
X1544075Y484106D01*
G01X1546025Y483200D02*
X1547975Y484106D01*
G01X1614459Y17268D02*
Y14796D01*
X1613359Y13696D01*
Y8655D01*
X1612808Y8104D01*
Y5875D01*
X1613258Y5425D01*
X1614833D01*
G01X1605009Y17268D02*
Y14796D01*
X1603873Y13660D01*
Y11805D01*
X1604323Y11355D01*
X1605898D01*
G01X1595848Y11406D02*
X1594800D01*
X1594359Y11847D01*
Y13596D01*
X1595559Y14796D01*
Y17268D01*
G01X1611309D02*
Y14796D01*
X1612409Y13696D01*
Y9049D01*
X1611858Y8498D01*
Y5875D01*
X1611408Y5425D01*
X1609833D01*
G01X1601859Y17268D02*
Y14796D01*
X1602923Y13732D01*
Y11805D01*
X1602473Y11355D01*
X1600898D01*
G01X1591848Y11406D02*
X1592900D01*
X1593409Y11915D01*
Y13796D01*
X1592409Y14796D01*
Y17268D01*
G01X1617393Y41527D02*
X1616118Y40252D01*
Y38600D01*
X1616509Y38209D01*
Y34948D01*
X1617609Y33848D01*
Y30668D01*
G01X1604848Y39479D02*
X1606123Y38204D01*
Y34962D01*
X1605009Y33848D01*
Y30668D01*
G01X1598898Y39484D02*
X1597623Y38209D01*
Y34934D01*
X1598709Y33848D01*
Y30668D01*
G01X1613893Y41527D02*
X1615168Y40252D01*
Y38206D01*
X1615559Y37815D01*
Y34948D01*
X1614459Y33848D01*
Y30668D01*
G01X1608348Y39479D02*
X1607073Y38204D01*
Y34934D01*
X1608159Y33848D01*
Y30668D01*
G01X1595398Y39484D02*
X1596673Y38209D01*
Y34962D01*
X1595559Y33848D01*
Y30668D01*
G01X1627715Y39934D02*
X1625995D01*
X1625620Y39559D01*
Y34979D01*
X1627059Y33540D01*
Y30668D01*
G01X1637398Y39862D02*
X1635823D01*
X1635300Y39339D01*
Y35101D01*
X1636509Y33892D01*
Y30668D01*
G01X1645959D02*
Y34084D01*
X1644859Y35184D01*
Y38659D01*
X1645662Y39462D01*
X1646848D01*
G01X1622635Y39900D02*
X1624299D01*
X1624670Y39529D01*
Y34269D01*
X1623909Y33508D01*
Y30668D01*
G01X1632398Y39862D02*
X1633973D01*
X1634350Y39485D01*
Y35075D01*
X1633359Y34084D01*
Y30668D01*
G01X1642809D02*
Y34084D01*
X1643909Y35184D01*
Y38691D01*
X1643138Y39462D01*
X1641848D01*
G01X1623909Y17268D02*
Y14560D01*
X1622809Y13460D01*
Y11800D01*
X1623854Y10755D01*
X1624798D01*
G01X1634148Y6825D02*
X1632876D01*
X1632164Y7537D01*
Y13441D01*
X1633359Y14636D01*
Y17268D01*
G01X1643865Y11105D02*
X1642379D01*
X1641828Y11656D01*
Y13219D01*
X1642809Y14200D01*
Y17268D01*
G01X1620759D02*
Y14560D01*
X1621859Y13460D01*
Y11800D01*
X1620814Y10755D01*
X1619798D01*
G01X1630209Y17268D02*
Y14480D01*
X1631214Y13475D01*
Y7316D01*
X1630723Y6825D01*
X1629148D01*
G01X1638865Y11105D02*
X1640227D01*
X1640878Y11756D01*
Y13281D01*
X1639659Y14500D01*
Y17268D01*
G01X1648748Y6325D02*
X1650323D01*
X1650782Y6784D01*
Y9256D01*
X1650209Y9829D01*
Y13696D01*
X1649109Y14796D01*
Y17268D01*
G01X1624764Y107617D02*
X1623300Y106153D01*
Y100800D01*
X1621700Y99200D01*
G01X1630418Y192807D02*
Y193876D01*
X1628950Y195344D01*
G01X1633711Y192804D02*
Y194223D01*
X1632590Y195344D01*
G01X1635351Y185444D02*
X1637100Y187193D01*
Y188014D01*
X1636811Y188303D01*
G01X1639811D02*
X1639258Y187750D01*
Y185620D01*
G01X1621623Y187726D02*
X1620921Y187024D01*
Y186387D01*
X1622248Y185060D01*
G01D02*
X1621700D01*
X1621043Y184403D01*
Y183961D01*
X1621707Y183297D01*
X1622400D01*
X1623037Y182660D01*
Y181967D01*
X1623673Y181331D01*
X1624366D01*
X1625003Y180694D01*
Y180001D01*
X1625639Y179365D01*
X1626332D01*
X1626969Y178728D01*
Y178035D01*
X1627605Y177399D01*
X1628298D01*
X1628935Y176762D01*
Y176069D01*
X1630473Y174531D01*
Y173740D01*
X1630963Y173250D01*
Y172349D01*
X1630473Y171859D01*
Y170884D01*
X1630748Y170609D01*
X1631064D01*
G01X1618623Y187726D02*
X1618651D01*
X1619819Y186558D01*
Y185263D01*
X1619500Y184944D01*
G01D02*
X1620093Y184351D01*
Y183567D01*
X1629523Y174137D01*
Y170539D01*
X1631064Y167459D01*
G01X1632724Y174600D02*
Y176406D01*
X1629591Y179539D01*
Y184844D01*
X1629473Y184962D01*
G01X1611057Y465508D02*
X1612081Y466532D01*
X1613563D01*
X1614543Y465552D01*
X1622410D01*
X1623749Y464213D01*
G01X1608813Y483559D02*
X1609938Y482434D01*
X1611393D01*
X1614310Y479517D01*
X1616194D01*
X1617700Y478011D01*
Y475957D01*
G01X1608813Y480359D02*
X1609938Y481484D01*
X1610999D01*
X1611705Y480778D01*
Y480141D01*
X1612659Y479187D01*
X1613296D01*
X1613916Y478567D01*
X1615800D01*
X1616250Y478117D01*
Y477183D01*
X1615971Y476904D01*
X1614426Y476740D01*
X1614000Y476265D01*
Y475970D01*
G01X1611057Y468708D02*
X1612283Y467482D01*
X1613957D01*
X1614937Y466502D01*
X1622352D01*
X1623705Y467855D01*
G01X1603957Y476708D02*
X1604865Y475800D01*
X1606376D01*
X1609376Y472800D01*
X1617644D01*
X1618650Y471794D01*
Y470902D01*
X1619607Y469945D01*
G01X1603957Y473508D02*
X1605299Y474850D01*
X1605982D01*
X1606718Y474114D01*
Y473478D01*
X1607673Y472523D01*
X1608309D01*
X1608982Y471850D01*
X1612734D01*
X1613184Y471400D01*
X1614534D01*
X1614984Y471850D01*
X1617250D01*
X1617700Y471400D01*
Y470396D01*
X1617249Y469945D01*
X1616607D01*
G01X1655409Y30668D02*
Y34084D01*
X1654273Y35220D01*
Y39012D01*
X1654723Y39462D01*
X1656298D01*
G01X1664859Y30668D02*
Y34084D01*
X1663723Y35220D01*
Y39012D01*
X1664173Y39462D01*
X1665748D01*
G01X1674309Y30668D02*
Y34084D01*
X1673209Y35184D01*
Y38709D01*
X1673962Y39462D01*
X1675198D01*
G01X1683759Y30668D02*
Y34084D01*
X1682659Y35184D01*
Y38859D01*
X1683262Y39462D01*
X1684648D01*
G01X1689098D02*
X1690438D01*
X1691159Y38741D01*
Y35184D01*
X1690059Y34084D01*
Y30668D01*
G01X1652259D02*
Y34084D01*
X1653323Y35148D01*
Y39012D01*
X1652873Y39462D01*
X1651298D01*
G01X1661709Y30668D02*
Y34084D01*
X1662773Y35148D01*
Y39012D01*
X1662323Y39462D01*
X1660748D01*
G01X1671159Y30668D02*
Y34084D01*
X1672259Y35184D01*
Y38641D01*
X1671438Y39462D01*
X1670198D01*
G01X1679648D02*
X1681138D01*
X1681709Y38891D01*
Y35184D01*
X1680609Y34084D01*
Y30668D01*
G01X1694098Y39462D02*
X1692662D01*
X1692109Y38909D01*
Y35184D01*
X1693209Y34084D01*
Y30668D01*
G01X1653748Y6325D02*
X1652182D01*
X1651732Y6775D01*
Y9650D01*
X1651159Y10223D01*
Y13696D01*
X1652259Y14796D01*
Y17268D01*
G01X1662373Y10154D02*
X1661146D01*
X1660450Y10850D01*
Y13301D01*
X1661709Y14560D01*
Y17268D01*
G01X1671979Y6236D02*
X1670404D01*
X1669954Y6686D01*
Y13591D01*
X1671159Y14796D01*
Y17268D01*
G01X1680609D02*
Y14560D01*
X1679403Y13354D01*
Y11831D01*
X1679853Y11381D01*
X1681428D01*
G01X1690059Y17268D02*
Y14560D01*
X1688959Y13460D01*
Y11240D01*
X1689474Y10725D01*
X1690948D01*
G01X1657369Y10258D02*
X1658759D01*
X1659500Y10999D01*
Y13619D01*
X1658559Y14560D01*
Y17268D01*
G01X1666979Y6236D02*
X1668554D01*
X1669004Y6686D01*
Y13801D01*
X1668009Y14796D01*
Y17268D01*
G01X1677459D02*
Y14560D01*
X1678453Y13566D01*
Y11831D01*
X1678003Y11381D01*
X1676428D01*
G01X1686909Y17268D02*
Y14560D01*
X1688009Y13460D01*
Y11208D01*
X1687526Y10725D01*
X1685948D01*
G01X1700200Y11317D02*
X1698841D01*
X1698172Y11986D01*
Y13459D01*
X1699509Y14796D01*
Y17268D01*
G01X1709771Y11261D02*
X1708476D01*
X1707767Y11970D01*
Y13604D01*
X1708959Y14796D01*
Y17268D01*
G01X1695200Y11317D02*
X1696603D01*
X1697222Y11936D01*
Y13677D01*
X1696359Y14540D01*
Y17268D01*
G01X1704771Y11261D02*
X1706220D01*
X1706817Y11858D01*
Y13788D01*
X1705809Y14796D01*
Y17268D01*
G01X1703073Y39679D02*
X1702279D01*
X1701648Y39048D01*
Y35095D01*
X1702659Y34084D01*
Y30668D01*
G01X1712308Y39350D02*
X1711550D01*
X1710800Y38600D01*
Y35393D01*
X1712109Y34084D01*
Y30668D01*
G01X1699273Y39679D02*
X1700121D01*
X1700698Y39102D01*
Y35273D01*
X1699509Y34084D01*
Y30668D01*
G01X1708959D02*
Y34084D01*
X1709862Y34987D01*
X1709850Y34999D01*
Y38650D01*
X1709150Y39350D01*
X1708508D01*
G01X1719297Y11180D02*
X1717722D01*
X1717222Y11680D01*
Y13609D01*
X1718409Y14796D01*
Y17268D01*
G01X1727859D02*
Y14796D01*
X1726659Y13596D01*
Y11941D01*
X1727219Y11381D01*
X1728678D01*
G01X1738168Y22312D02*
X1736800D01*
X1736465Y21977D01*
Y21120D01*
X1737309Y20276D01*
Y17268D01*
G01X1748152Y23197D02*
X1746924D01*
X1745936Y22209D01*
Y20261D01*
X1746759Y19438D01*
Y17268D01*
G01X1775107D02*
Y12746D01*
X1773149Y10788D01*
X1768297D01*
X1767303Y11782D01*
X1767278D01*
X1764745Y14315D01*
Y22625D01*
X1763360Y24010D01*
G01X1756992Y20007D02*
X1758014Y18985D01*
Y14382D01*
X1764261Y8135D01*
X1780086D01*
X1783457Y11506D01*
Y13696D01*
X1784557Y14796D01*
Y17268D01*
G01X1714297Y11180D02*
X1715822D01*
X1716272Y11630D01*
Y13783D01*
X1715259Y14796D01*
Y17268D01*
G01X1724709D02*
Y14796D01*
X1725709Y13796D01*
Y11909D01*
X1725181Y11381D01*
X1723678D01*
G01X1733168Y22312D02*
X1734658D01*
X1734988Y21982D01*
Y21037D01*
X1734159Y20208D01*
Y17268D01*
G01X1743152Y23197D02*
X1744076D01*
X1744986Y22287D01*
Y20627D01*
X1743609Y19250D01*
Y17268D01*
G01X1771957D02*
Y14324D01*
X1772128Y14153D01*
X1773576D01*
X1773895Y13834D01*
Y12878D01*
X1772755Y11738D01*
X1771578D01*
X1771128Y12188D01*
X1769778D01*
X1769328Y11738D01*
X1768691D01*
X1768241Y12188D01*
Y12800D01*
X1767286Y13754D01*
X1766650D01*
X1765695Y14709D01*
Y15436D01*
X1766145Y15886D01*
Y17236D01*
X1765695Y17686D01*
Y19036D01*
X1766145Y19486D01*
Y20836D01*
X1765695Y21286D01*
Y22636D01*
X1767069Y24010D01*
G01X1760693Y20045D02*
X1758964Y18316D01*
Y14776D01*
X1759563Y14177D01*
X1760200D01*
X1761154Y13222D01*
Y12586D01*
X1762109Y11631D01*
X1762746D01*
X1763700Y10676D01*
Y10040D01*
X1764655Y9085D01*
X1765292D01*
X1765742Y9535D01*
X1767092D01*
X1767542Y9085D01*
X1768892D01*
X1769342Y9535D01*
X1770692D01*
X1771142Y9085D01*
X1772492D01*
X1772942Y9535D01*
X1774292D01*
X1774742Y9085D01*
X1776092D01*
X1776542Y9535D01*
X1777892D01*
X1778342Y9085D01*
X1779692D01*
X1780647Y10040D01*
Y10676D01*
X1781601Y11631D01*
X1782238D01*
X1782507Y11900D01*
Y13696D01*
X1781407Y14796D01*
Y17268D01*
G01X1721559Y30668D02*
Y34084D01*
X1720333Y35310D01*
Y39233D01*
X1720980Y39880D01*
X1721758D01*
G01X1731183Y39465D02*
X1730545D01*
X1729758Y38678D01*
Y35335D01*
X1731009Y34084D01*
Y30668D01*
G01X1740459D02*
Y33840D01*
X1739227Y35072D01*
Y38627D01*
X1740086Y39486D01*
X1740598D01*
G01X1750250Y35925D02*
X1749225D01*
X1748809Y35509D01*
Y34292D01*
X1749909Y33192D01*
Y30668D01*
G01X1775107D02*
Y34084D01*
X1776207Y35184D01*
Y35821D01*
X1775757Y36271D01*
X1770991D01*
X1770541Y35821D01*
X1769191D01*
X1768741Y36271D01*
X1767391D01*
X1766941Y35821D01*
X1765591D01*
X1765141Y36271D01*
X1763791D01*
X1762837Y35316D01*
Y34680D01*
X1761883Y33725D01*
X1761247D01*
X1759395Y31872D01*
X1758315D01*
X1756895Y30452D01*
G01X1718409Y30668D02*
Y34084D01*
X1719383Y35058D01*
Y39217D01*
X1718720Y39880D01*
X1717958D01*
G01X1727383Y39465D02*
X1728305D01*
X1728808Y38962D01*
Y35033D01*
X1727859Y34084D01*
Y30668D01*
G01X1736700Y39600D02*
X1737300D01*
X1738277Y38623D01*
Y35052D01*
X1737309Y34084D01*
Y30668D01*
G01X1746550Y35925D02*
X1747375D01*
X1747859Y35441D01*
Y34460D01*
X1746759Y33360D01*
Y30668D01*
G01X1756895Y34252D02*
X1758325Y32822D01*
X1759001D01*
X1763397Y37221D01*
X1776151D01*
X1777157Y36215D01*
Y35184D01*
X1778257Y34084D01*
Y30668D01*
G01X1752000Y38865D02*
X1753679Y39688D01*
X1754541Y42205D01*
X1758036Y45700D01*
X1776632D01*
X1786329Y36003D01*
Y35462D01*
X1787707Y34084D01*
Y30668D01*
G01X1755400Y37700D02*
X1754579Y39379D01*
X1755369Y41688D01*
X1755884Y42204D01*
X1756521D01*
X1757475Y43159D01*
Y43795D01*
X1758430Y44750D01*
X1759780D01*
X1760230Y44300D01*
X1761580D01*
X1762030Y44750D01*
X1763380D01*
X1763830Y44300D01*
X1765180D01*
X1765630Y44750D01*
X1766980D01*
X1767430Y44300D01*
X1768780D01*
X1769230Y44750D01*
X1770580D01*
X1771030Y44300D01*
X1772380D01*
X1772830Y44750D01*
X1776238D01*
X1777193Y43795D01*
Y43159D01*
X1778147Y42204D01*
X1778784D01*
X1779738Y41250D01*
Y40613D01*
X1780693Y39659D01*
X1781329D01*
X1782284Y38704D01*
Y38068D01*
X1783238Y37113D01*
X1783875D01*
X1785379Y35609D01*
Y34906D01*
X1784557Y34084D01*
Y30668D01*
G01X1764988Y176525D02*
X1766299D01*
X1767000Y177226D01*
Y180655D01*
X1765909Y181746D01*
Y186937D01*
G01X1752390Y176525D02*
X1753701D01*
X1754450Y177274D01*
Y181399D01*
X1753315Y182535D01*
Y186937D01*
X1753311D01*
G01X1739792Y176525D02*
X1741103D01*
X1741817Y177239D01*
Y180983D01*
X1740717Y182083D01*
Y186937D01*
X1740713D01*
G01X1732193Y176525D02*
X1730882D01*
X1730168Y177239D01*
Y181017D01*
X1731268Y182117D01*
Y186937D01*
X1731264D01*
G01X1769988Y176525D02*
X1768677D01*
X1767950Y177252D01*
Y180850D01*
X1769063Y181963D01*
Y186937D01*
X1769059D01*
G01X1757390Y176525D02*
X1756079D01*
X1755400Y177204D01*
Y181349D01*
X1756461Y182410D01*
Y186937D01*
G01X1744792Y176525D02*
X1743481D01*
X1742767Y177239D01*
Y181017D01*
X1743867Y182117D01*
Y186932D01*
X1743862Y186937D01*
G01X1727193Y176525D02*
X1728504D01*
X1729218Y177239D01*
Y181031D01*
X1728114Y182135D01*
Y186937D01*
G01X1762760Y204236D02*
Y199978D01*
X1762765Y199973D01*
X1761615Y198823D01*
Y197321D01*
X1762093Y196843D01*
X1763668D01*
G01X1750161Y204236D02*
Y199968D01*
X1749057Y198864D01*
Y197293D01*
X1749507Y196843D01*
X1751082D01*
G01X1737563Y204236D02*
Y200870D01*
X1736498Y199805D01*
Y197266D01*
X1736988Y196776D01*
X1738563D01*
G01X1772209Y204236D02*
Y201029D01*
X1773266Y199972D01*
Y197291D01*
X1772816Y196841D01*
X1771241D01*
G01X1759610Y204236D02*
Y199868D01*
X1760665Y198813D01*
Y197293D01*
X1760215Y196843D01*
X1758668D01*
G01X1747012Y204236D02*
X1747016D01*
Y199863D01*
X1748107Y198772D01*
Y197293D01*
X1747657Y196843D01*
X1746082D01*
G01X1734413Y204236D02*
Y200826D01*
X1735548Y199691D01*
Y197226D01*
X1735098Y196776D01*
X1733563D01*
G01X1762996Y460603D02*
Y465917D01*
X1762992Y465921D01*
X1764092Y467021D01*
Y470345D01*
X1763725Y471232D01*
Y475205D01*
X1763275Y475655D01*
X1761700D01*
G01X1737799Y460603D02*
Y465917D01*
X1737795Y465921D01*
X1738895Y467021D01*
Y487335D01*
X1738475Y487755D01*
X1736900D01*
G01X1750397Y460603D02*
Y465917D01*
X1750393Y465921D01*
X1751380Y466908D01*
Y486934D01*
X1750459Y487855D01*
X1749300D01*
G01X1766145Y460603D02*
Y465918D01*
X1765042Y467021D01*
Y470534D01*
X1764675Y471421D01*
Y475205D01*
X1765125Y475655D01*
X1766700D01*
G01X1740948Y460603D02*
Y465918D01*
X1739845Y467021D01*
Y487275D01*
X1740325Y487755D01*
X1741900D01*
G01X1753547Y460603D02*
Y465917D01*
X1752330Y467134D01*
Y486956D01*
X1753229Y487855D01*
X1754300D01*
G01X1769295Y441754D02*
X1769291D01*
Y447072D01*
X1770391Y448172D01*
Y449869D01*
X1769852Y450408D01*
X1768366D01*
G01X1744098Y441754D02*
X1744094D01*
Y447072D01*
X1745194Y448172D01*
Y449958D01*
X1744744Y450408D01*
X1743169D01*
G01X1756696Y441754D02*
X1756692D01*
Y447072D01*
X1757792Y448172D01*
Y449998D01*
X1757382Y450408D01*
X1755767D01*
G01X1772445Y441754D02*
X1772441D01*
Y447072D01*
X1771341Y448172D01*
Y449869D01*
X1771880Y450408D01*
X1773366D01*
G01X1747248Y441754D02*
X1747244D01*
Y447072D01*
X1746144Y448172D01*
Y449958D01*
X1746594Y450408D01*
X1748169D01*
G01X1759846Y441754D02*
X1759842D01*
Y447072D01*
X1758742Y448172D01*
Y449998D01*
X1759152Y450408D01*
X1760767D01*
G01X1819453Y186937D02*
X1819457D01*
Y182207D01*
X1818300Y181050D01*
Y177296D01*
X1819071Y176525D01*
X1820382D01*
G01X1806854Y186937D02*
X1806859Y186932D01*
Y181465D01*
X1805759Y180365D01*
Y177239D01*
X1806473Y176525D01*
X1807784D01*
G01X1794256Y186937D02*
X1794260D01*
Y181961D01*
X1793050Y180751D01*
Y177049D01*
X1793574Y176525D01*
X1795185D01*
G01X1781658Y186937D02*
X1781662D01*
Y181913D01*
X1780500Y180751D01*
Y177301D01*
X1781276Y176525D01*
X1782587D01*
G01X1816303Y186937D02*
Y181998D01*
X1817350Y180951D01*
Y177182D01*
X1816693Y176525D01*
X1815382D01*
G01X1803705Y186937D02*
Y181637D01*
X1804809Y180533D01*
Y177239D01*
X1804095Y176525D01*
X1802784D01*
G01X1791106Y186937D02*
Y181746D01*
X1792100Y180752D01*
Y177129D01*
X1791496Y176525D01*
X1790185D01*
G01X1778508Y186937D02*
Y181746D01*
X1779550Y180704D01*
Y177177D01*
X1778898Y176525D01*
X1777587D01*
G01X1775358Y204236D02*
Y201064D01*
X1774216Y199922D01*
Y197291D01*
X1774666Y196841D01*
X1776241D01*
G01X1825752Y204236D02*
Y200759D01*
X1824657Y199664D01*
Y197291D01*
X1825107Y196841D01*
X1826682D01*
G01X1813154Y204236D02*
Y199741D01*
X1812016Y198603D01*
Y197291D01*
X1812466Y196841D01*
X1814041D01*
G01X1800555Y204236D02*
Y199742D01*
X1799416Y198603D01*
Y197291D01*
X1799866Y196841D01*
X1801441D01*
G01X1787957Y204236D02*
Y201063D01*
X1786816Y199922D01*
Y197291D01*
X1787266Y196841D01*
X1788841D01*
G01X1822602Y204236D02*
Y200737D01*
X1823707Y199632D01*
Y197291D01*
X1823257Y196841D01*
X1821682D01*
G01X1810004Y204236D02*
Y199665D01*
X1811066Y198603D01*
Y197291D01*
X1810616Y196841D01*
X1809041D01*
G01X1797406Y204236D02*
Y199663D01*
X1798466Y198603D01*
Y197291D01*
X1798016Y196841D01*
X1796441D01*
G01X1784807Y204236D02*
Y201030D01*
X1785866Y199971D01*
Y197291D01*
X1785416Y196841D01*
X1783841D01*
G01X1775594Y460603D02*
Y465917D01*
X1775590Y465921D01*
X1776690Y467021D01*
Y470295D01*
X1776325Y471177D01*
Y474605D01*
X1775875Y475055D01*
X1774300D01*
G01X1788193Y460603D02*
Y465917D01*
X1788189Y465921D01*
X1789289Y467021D01*
Y469808D01*
X1791997Y476346D01*
Y478633D01*
X1791330Y479300D01*
X1789975D01*
G01X1800791Y460603D02*
Y465517D01*
X1800787Y465521D01*
X1801887Y466621D01*
Y467598D01*
X1803630Y471806D01*
Y473425D01*
X1803100Y473955D01*
X1801525D01*
G01X1813389Y460603D02*
Y465917D01*
X1813385Y465921D01*
X1814427Y466963D01*
Y477830D01*
X1813937Y478320D01*
X1812375D01*
G01X1825988Y460603D02*
Y465917D01*
X1825984Y465921D01*
X1827137Y467074D01*
Y476057D01*
X1826267Y476927D01*
X1825297D01*
G01X1778744Y460603D02*
Y465917D01*
X1777640Y467021D01*
Y470484D01*
X1777275Y471366D01*
Y474605D01*
X1777725Y475055D01*
X1779300D01*
G01X1791342Y460603D02*
Y465918D01*
X1790239Y467021D01*
Y469619D01*
X1792947Y476157D01*
Y478626D01*
X1793621Y479300D01*
X1794975D01*
G01X1803941Y460603D02*
Y465553D01*
X1802837Y466657D01*
Y467409D01*
X1804580Y471617D01*
Y473585D01*
X1804950Y473955D01*
X1806525D01*
G01X1816539Y460603D02*
Y465917D01*
X1815377Y467079D01*
Y477837D01*
X1815860Y478320D01*
X1817375D01*
G01X1829967Y476927D02*
X1828977D01*
X1828087Y476037D01*
Y466968D01*
X1829137Y465918D01*
Y460603D01*
G01X1781893Y441754D02*
X1781889D01*
Y447072D01*
X1782989Y448172D01*
Y449804D01*
X1782385Y450408D01*
X1780964D01*
G01X1794492Y441754D02*
X1794488D01*
Y447072D01*
X1795588Y448172D01*
Y449836D01*
X1795016Y450408D01*
X1793563D01*
G01X1807090Y441754D02*
X1807086D01*
Y447072D01*
X1808186Y448172D01*
Y450063D01*
X1807841Y450408D01*
X1806161D01*
G01X1819689Y441754D02*
X1819685D01*
Y447072D01*
X1820785Y448172D01*
Y449869D01*
X1820246Y450408D01*
X1818760D01*
G01X1832287Y441754D02*
X1832283D01*
Y447072D01*
X1833383Y448172D01*
Y450095D01*
X1832878Y450600D01*
X1831495D01*
G01X1785043Y441754D02*
X1785039D01*
Y447072D01*
X1783939Y448172D01*
Y449804D01*
X1784543Y450408D01*
X1785964D01*
G01X1797641Y441754D02*
X1797637D01*
Y447073D01*
X1796538Y448172D01*
Y449836D01*
X1797110Y450408D01*
X1798563D01*
G01X1810240Y441754D02*
X1810236D01*
Y447072D01*
X1809136Y448172D01*
Y450063D01*
X1809481Y450408D01*
X1811161D01*
G01X1822838Y441754D02*
X1822834D01*
Y447073D01*
X1821735Y448172D01*
Y449869D01*
X1822274Y450408D01*
X1823760D01*
G01X1835437Y441754D02*
X1835433D01*
Y447072D01*
X1834333Y448172D01*
Y450095D01*
X1834838Y450600D01*
X1836495D01*
G01X1909421Y208805D02*
X1910826Y207400D01*
X1912144D01*
X1913979Y205565D01*
Y203625D01*
X1914900Y202704D01*
Y201350D01*
G01X1909438Y204307D02*
Y205769D01*
X1910119Y206450D01*
X1911750D01*
X1913029Y205171D01*
Y203889D01*
X1912579Y203439D01*
X1911850D01*
X1911400Y202989D01*
Y201350D01*
G01X1915359Y190300D02*
Y192541D01*
X1914821Y193079D01*
Y193779D01*
X1913692Y194908D01*
Y196642D01*
X1914900Y197850D01*
G01X1913390Y190300D02*
Y192520D01*
X1913871Y193001D01*
Y193385D01*
X1912742Y194514D01*
Y196508D01*
X1911400Y197850D01*
G01X1909453Y190300D02*
Y198442D01*
X1907287Y200608D01*
Y202536D01*
X1906280Y203543D01*
X1905394D01*
X1904042Y204895D01*
G01X1907485Y190300D02*
Y192371D01*
X1907739Y192625D01*
X1908228D01*
X1908503Y192900D01*
Y194250D01*
X1908053Y194700D01*
Y196050D01*
X1908503Y196500D01*
Y198048D01*
X1906337Y200214D01*
Y202142D01*
X1905886Y202593D01*
X1905038D01*
X1903917Y201472D01*
G01X1956901Y218391D02*
X1957458Y217834D01*
X1960433D01*
G01X1956901Y215241D02*
X1957526Y215866D01*
X1960433D01*
G01X1953740Y217834D02*
X1952684D01*
X1952190Y217340D01*
X1951140D01*
X1950238Y216438D01*
X1948406D01*
X1944943Y219901D01*
X1943751D01*
X1943217Y220435D01*
Y221154D01*
G01Y217645D02*
Y218501D01*
X1943667Y218951D01*
X1944549D01*
X1948012Y215488D01*
X1950632D01*
X1951534Y216390D01*
X1952190D01*
X1952714Y215866D01*
X1953740D01*
G54D349*
G01X8466Y64413D02*
X7212D01*
X5399Y62600D01*
X920D01*
X-1080Y60600D01*
G01X71900Y161200D02*
X75500D01*
X76100Y161800D01*
Y166600D01*
X74582Y168118D01*
X72900D01*
G01X3354Y517143D02*
X5738Y514759D01*
Y513450D01*
G01X7313Y516456D02*
Y513450D01*
G01X-1550Y507737D02*
X-2937D01*
X-4800Y509600D01*
Y510000D01*
X-6150Y511350D01*
X-6710D01*
X-7360Y512000D01*
G01X22292Y503187D02*
X24979Y500500D01*
X25000D01*
G01X17750Y504587D02*
X20892D01*
X22292Y503187D01*
G01X-1959Y539702D02*
X-4520D01*
G01X-5488Y575702D02*
X-1959D01*
G01X54889Y-10601D02*
Y-9911D01*
X57309Y-7491D01*
X57629D01*
X58320Y-6800D01*
G01X90831Y184982D02*
Y175691D01*
X85150Y170010D01*
Y165450D01*
X82700Y163000D01*
X79900D01*
G01X72485Y307250D02*
Y308285D01*
X73600Y309400D01*
X74608D01*
X75626Y310418D01*
G01X74500Y313500D02*
Y312272D01*
X75700Y311072D01*
Y310418D01*
X75626D01*
G01X113588Y252322D02*
X115878D01*
X116892Y251308D01*
X118863D01*
X119790Y252235D01*
X122165D01*
G01X114120Y220530D02*
X115350Y219300D01*
X119131D01*
X120066Y220235D01*
X122165D01*
G01X111962Y316200D02*
X114740D01*
X115350Y315590D01*
G01X122165Y316235D02*
X120066D01*
X118571Y314740D01*
X116260D01*
X115410Y315590D01*
X115350D01*
G01X122165Y348235D02*
X119806D01*
X118741Y347170D01*
X116561D01*
X115145Y348586D01*
X113366D01*
G01X305448Y196641D02*
Y196193D01*
X301790Y192535D01*
X286090D01*
X285390Y191835D01*
X268295D01*
X263651Y187191D01*
X259560D01*
X258630Y186261D01*
G01X260438Y184453D02*
X261626Y185641D01*
X264294D01*
G01X271099Y173790D02*
X271663Y174354D01*
Y177659D01*
X273439Y179435D01*
X286574D01*
X290074Y182935D01*
X305774D01*
X314660Y191821D01*
X317148D01*
G01X256792Y188000D02*
X257494Y188702D01*
Y188741D01*
G01X267487Y177402D02*
X268219Y178134D01*
Y178601D01*
X272153Y182535D01*
G01X269291Y175598D02*
X270045Y176352D01*
Y178234D01*
X272796Y180985D01*
X286426D01*
X289576Y184135D01*
X305276D01*
X315648Y194507D01*
Y194707D01*
G01X285834Y187185D02*
X270224D01*
X265580Y182541D01*
X263768D01*
X263043Y181816D01*
G01X327729Y197141D02*
Y189462D01*
X311658Y173391D01*
X308839D01*
X305640Y170192D01*
X299429D01*
X298849Y169612D01*
G01X309738Y193691D02*
X303782Y187735D01*
X288082D01*
X285982Y185635D01*
X270867D01*
X265823Y180591D01*
X265433D01*
X264856Y180014D01*
G01X328929Y197141D02*
Y188964D01*
X312156Y172191D01*
X309831D01*
X306282Y168642D01*
X301539D01*
X300576Y167679D01*
G01X262230Y182630D02*
X263691Y184091D01*
X264937D01*
G01X307846Y174591D02*
X304997Y171742D01*
X299352D01*
X298036Y170426D01*
G01X265669Y179200D02*
X265910Y179441D01*
X266866D01*
X271510Y184085D01*
X286130D01*
X288580Y186535D01*
X304280D01*
X310458Y192713D01*
G01X330129Y197141D02*
Y188466D01*
X312654Y170991D01*
X310824D01*
X306925Y167092D01*
X301617D01*
X301390Y166865D01*
G01X324129Y197141D02*
Y190956D01*
X310164Y176991D01*
X305861D01*
X303712Y174842D01*
X295238D01*
X294618Y174222D01*
G01X310662Y175791D02*
X306854D01*
X304355Y173292D01*
X297295D01*
X296326Y172323D01*
G01X322929Y191454D02*
X309666Y178191D01*
X304867D01*
X303068Y176392D01*
X292982D01*
X292823Y176233D01*
G01X283629Y216909D02*
X281379D01*
G01X287009Y203260D02*
X284759D01*
G01X287009Y211060D02*
X284759D01*
G01X283629Y205210D02*
X281379D01*
G01X283629Y209109D02*
X281379D01*
G01X293769Y203260D02*
X291519D01*
G01X293769Y211060D02*
X291519D01*
G01X307167Y196214D02*
X302288Y191335D01*
X286588D01*
X285538Y190285D01*
X268938D01*
X264294Y185641D01*
G01X300483Y196126D02*
X298092Y193735D01*
X285592D01*
X285242Y193385D01*
X267652D01*
X263008Y188741D01*
X257494D01*
G01X289078Y185335D02*
X286278Y182535D01*
X272153D01*
G01X314192Y195185D02*
Y194749D01*
X304778Y185335D01*
X289078D01*
G01X290389Y201309D02*
X288139D01*
G01X308308Y193959D02*
X303284Y188935D01*
X287584D01*
X285834Y187185D01*
G01X290389Y213009D02*
X288139D01*
G01X290389Y205210D02*
X288139D01*
G01X302786Y190135D02*
X287086D01*
X285686Y188735D01*
X269581D01*
X264937Y184091D01*
G01X290389Y209109D02*
X288139D01*
G01X266729Y257860D02*
X264179D01*
G01X283629Y228610D02*
X281379D01*
G01X290389Y224709D02*
X288139D01*
G01X280249Y218860D02*
X277999D01*
G01X273489Y257860D02*
X271239D01*
G01X287009Y230559D02*
X284759D01*
G01X290389Y228610D02*
X288139D01*
G01X280249Y222760D02*
X277999D01*
G01X287009Y218860D02*
X284759D01*
G01X266729Y242260D02*
X264092D01*
G01X273489D02*
X271239D01*
G01X266729Y261760D02*
X264179D01*
G01X266729Y246160D02*
X264179D01*
G01X273489D02*
X271239D01*
G01X273489Y250060D02*
X271239D01*
G01X280249Y226660D02*
X277999D01*
G01X290389Y220809D02*
X288139D01*
G01X273489Y253960D02*
X271239D01*
G01X270109Y248109D02*
X267859D01*
G01X283629Y224709D02*
X281379D01*
G01X287009Y222760D02*
X284759D01*
G01X270109Y255909D02*
X267859D01*
G01X280249Y238360D02*
X277999D01*
G01X283629Y236409D02*
X281379D01*
G01X287009Y250060D02*
X284759D01*
G01X290389Y248109D02*
X288139D01*
G01X280249Y242260D02*
X277999D01*
G01X287009Y238360D02*
X284759D01*
G01X283629Y248109D02*
X281379D01*
G01X290389Y244209D02*
X288139D01*
G01X280249Y246160D02*
X277999D01*
G01X290389Y240309D02*
X288139D01*
G01X283629Y244209D02*
X281379D01*
G01X287009Y242260D02*
X284759D01*
G01X302586Y404851D02*
X291728D01*
X287780Y408799D01*
X283640D01*
X282290Y407449D01*
X281235D01*
G01Y409999D02*
X288278D01*
X292226Y406051D01*
X302481D01*
G01X285122Y425049D02*
X284548D01*
G01X302481Y414451D02*
X295720D01*
X285122Y425049D01*
G01X299306Y403651D02*
X291230D01*
X287282Y407599D01*
X284138D01*
X281438Y404899D01*
X280174D01*
G01X286241Y419949D02*
X286826D01*
X294724Y412051D01*
X302481D01*
G01X285148Y422499D02*
X285974D01*
X295222Y413251D01*
X302481D01*
G01Y408451D02*
X293230D01*
X287982Y413699D01*
X286648D01*
G01X329658Y395641D02*
Y406655D01*
X326948Y409365D01*
Y410847D01*
X311332Y426463D01*
X307671D01*
X306969Y427165D01*
G01X286648Y416259D02*
X287120D01*
X293728Y409651D01*
X302481D01*
G01X328148Y409863D02*
Y411839D01*
X311976Y428011D01*
X310498D01*
X308846Y429663D01*
G01X302481Y407251D02*
X292732D01*
X287434Y412549D01*
X286648D01*
G01X328458Y395641D02*
Y406157D01*
X325748Y408867D01*
Y409855D01*
X310690Y424913D01*
X307593D01*
X306192Y426314D01*
G01X286648Y417399D02*
X287678D01*
X294226Y410851D01*
X302481D01*
G01X332058Y395641D02*
Y407651D01*
X329348Y410361D01*
Y412831D01*
X312400Y429779D01*
X310357D01*
X309659Y430477D01*
G01X326058Y395641D02*
Y405161D01*
X309404Y421815D01*
X303435D01*
X301992Y423258D01*
G01X327258Y395641D02*
Y405659D01*
X324548Y408369D01*
Y408863D01*
X310047Y423364D01*
X305536D01*
X304588Y424312D01*
G01X322192Y403320D02*
Y404571D01*
G01X323498Y403189D02*
Y405528D01*
X308760Y420266D01*
X301420D01*
X300747Y420939D01*
G01X307968Y160773D02*
Y161556D01*
X313803Y167391D01*
X314148D01*
X333729Y186972D01*
G01X331329Y187968D02*
X313152Y169791D01*
X311818D01*
X307569Y165542D01*
X303689D01*
X303258Y165111D01*
G01X305730Y163992D02*
X305358Y163620D01*
G01X344468Y205210D02*
X342218D01*
G01X300529Y214960D02*
X298279D01*
G01X310668Y216909D02*
X308418D01*
G01X297149D02*
X294899D01*
G01X307289Y214960D02*
X305039D01*
G01X303909Y213009D02*
X301659D01*
G01X303909Y216909D02*
X301659D01*
G01X347848Y207159D02*
X345598D01*
G01X351228Y205210D02*
X348978D01*
G01X351228Y216909D02*
X348978D01*
G01X344468Y213009D02*
X342218D01*
G01X341088Y214960D02*
X338838D01*
G01X297149Y205210D02*
X294899D01*
G01X297149Y209109D02*
X294899D01*
G01X307502Y194851D02*
X302786Y190135D01*
G01X326529Y197141D02*
Y189960D01*
X311160Y174591D01*
X307846D01*
G01X325329Y197141D02*
Y190458D01*
X310662Y175791D01*
G01X333729Y195141D02*
Y186972D01*
G01X322929Y197141D02*
Y191454D01*
G01X331329Y197141D02*
Y187968D01*
G01X332529Y197141D02*
Y187470D01*
X313650Y168591D01*
X312810D01*
X308211Y163992D01*
X305730D01*
G01X341088Y226660D02*
X338838Y230560D01*
G01X300529Y222760D02*
X298279D01*
G01X310668Y220809D02*
X308418D01*
G01X297149D02*
X294899D01*
G01X307289Y222760D02*
X305039D01*
G01X330948Y236409D02*
X328698D01*
G01X303909Y224709D02*
X301659D01*
G01X330948Y248109D02*
X328698D01*
G01X330948Y240309D02*
X328698D01*
G01X303909Y220809D02*
X301659D01*
G01X330948Y244209D02*
X328698D01*
G01X327568Y238360D02*
X325318D01*
G01X327568Y246160D02*
X325318D01*
G01X337708Y240309D02*
X335458D01*
G01X337708Y244209D02*
X335458D01*
G01X324188Y240309D02*
X321938D01*
G01X324188Y244209D02*
X321938D01*
G01X334328Y238360D02*
X332078D01*
G01X334328Y246160D02*
X332078D01*
G01X354607Y218860D02*
X352357D01*
G01X347848D02*
X345598D01*
G01X341088Y222760D02*
X338838D01*
G01X354607D02*
X352357D01*
G01X351228Y224709D02*
X348978D01*
G01X351228Y228610D02*
X348978D01*
G01X354607Y230559D02*
X352357D01*
G01X351228Y236409D02*
X348978D01*
G01X351228Y240309D02*
X348978D01*
G01X354607Y234460D02*
X352357D01*
G01X347848Y242260D02*
X345598D01*
G01X347848Y234460D02*
X345598D01*
G01X344468Y240309D02*
X342218D01*
G01X344468Y228610D02*
X342218D01*
G01X344468Y236409D02*
X342218D01*
G01X330948Y263709D02*
X328698D01*
G01X327568Y257860D02*
X325318D01*
G01X334328Y265660D02*
X332078D01*
G01X334328Y261760D02*
X332078D01*
G01X314048Y273460D02*
X311798D01*
G01X324188Y267609D02*
X321938D01*
G01X310668Y271509D02*
X308418D01*
G01X320808Y273460D02*
X318558D01*
G01X354607Y242260D02*
X352357D01*
G01X351228Y337809D02*
X348978D01*
G01X344468Y384609D02*
X342218D01*
G01X347848Y367060D02*
X345598D01*
G01X351228Y372909D02*
X348978D01*
G01X344468D02*
X342218D01*
G01X341088Y374860D02*
X338838D01*
G01X341088Y370959D02*
X338838D01*
G01X341088Y378760D02*
X338838D01*
G01X305472Y401965D02*
X302586Y404851D01*
G01X307071Y402064D02*
X303084Y406051D01*
X302481D01*
G01X314714Y406307D02*
X306570Y414451D01*
X302481D01*
G01X300498Y402459D02*
X299306Y403651D01*
G01X312666Y404959D02*
X305574Y412051D01*
X302481D01*
G01X313748Y405575D02*
X306072Y413251D01*
X302481D01*
G01X308948Y403583D02*
X304080Y408451D01*
X302481D01*
G01X310448Y403781D02*
X304578Y409651D01*
X302481D01*
G01X330858Y395641D02*
Y407153D01*
G01X308248Y402585D02*
X303582Y407251D01*
X302481D01*
G01X311367Y404560D02*
X305076Y410851D01*
X302481D01*
G01X335658Y395641D02*
Y409145D01*
X332948Y411855D01*
Y415807D01*
X314713Y434042D01*
Y436182D01*
X314082Y436813D01*
G01X333258Y395641D02*
Y408149D01*
X330548Y410859D01*
Y413823D01*
X312731Y431640D01*
X312079D01*
X311171Y432548D01*
G01X334458Y395641D02*
Y408647D01*
X331748Y411357D01*
Y414815D01*
X313241Y433322D01*
Y434049D01*
X312483Y434807D01*
G01X354607Y378760D02*
X352357D01*
G01X354607Y374860D02*
X352357D01*
G01X351228Y369010D02*
X348978D01*
G01X354607Y367060D02*
X352357D01*
G01X347848Y351460D02*
X345598D01*
G01X351228Y361209D02*
X348978D01*
G01X347848Y363160D02*
X345598D01*
G01X344468Y357309D02*
X342218D01*
G01X344468Y369010D02*
X342218D01*
G01X344468Y361209D02*
X342218D01*
G01X354607Y351460D02*
X352357D01*
G01X354607Y363160D02*
X352357D01*
G01X354607Y355360D02*
X352357D01*
G01X351228Y341709D02*
X348978D01*
G01X351228Y345609D02*
X348978D01*
G01X330858Y407153D02*
X328148Y409863D01*
G01X394683Y22923D02*
Y33667D01*
X393020Y35330D01*
Y45239D01*
X396392Y48611D01*
Y55199D01*
X394683Y56908D01*
Y60723D01*
G01Y-14877D02*
Y-12009D01*
X395892Y-10800D01*
Y-8350D01*
X392892Y-5350D01*
Y7251D01*
X396504Y10863D01*
Y13187D01*
X394682Y15009D01*
Y17157D01*
G01D02*
Y22922D01*
X394683Y22923D01*
G01X419723Y196112D02*
X419773Y196062D01*
Y165082D01*
X416017Y161326D01*
Y159300D01*
G01X374887Y207159D02*
X372637D01*
G01X401926D02*
X399676D01*
G01X374887Y211060D02*
X372637D01*
G01X395166D02*
X392916D01*
G01X391787Y213009D02*
X389537D01*
G01X398546D02*
X396296D01*
G01X371507D02*
X369257D01*
G01X398546Y216909D02*
X396296D01*
G01X378267D02*
X376017D01*
G01X364747D02*
X362497D01*
G01X385027Y213009D02*
X382777D01*
G01X388407Y211060D02*
X386157D01*
G01X405306Y216909D02*
X407706D01*
G01X371507D02*
X369257D01*
G01X385027D02*
X382777D01*
G01X361367Y211060D02*
X359117D01*
G01X364747Y213009D02*
X362497D01*
G01X357987Y216909D02*
X355737D01*
G01X357987Y213009D02*
X355737D01*
G01X389537Y216909D02*
X391787D01*
G01X378267Y224709D02*
X376017D01*
G01X368127Y218860D02*
X365877D01*
G01X374887Y222760D02*
X372637D01*
G01X368127D02*
X365877D01*
G01X374887Y218860D02*
X372637D01*
G01X371507Y224709D02*
X369257D01*
G01X364747D02*
X362497D01*
G01X388407Y222760D02*
X386157D01*
G01X401926Y218860D02*
X399676D01*
G01X398546Y228610D02*
X396296D01*
G01X391787Y224709D02*
X389537D01*
G01X401926Y222760D02*
X399676D01*
G01X385027Y224709D02*
X382777D01*
G01X381647Y218860D02*
X379397D01*
G01X381647Y222760D02*
X379397D01*
G01X395166Y218860D02*
X392916D01*
G01X361367D02*
X359117D01*
G01X361367Y222760D02*
X359117D01*
G01X357987Y224709D02*
X355737D01*
G01X388407Y218860D02*
X386157D01*
G01X395166Y222760D02*
X392916D01*
G01X396296Y224709D02*
X398546D01*
G01X381647Y230559D02*
X379397D01*
G01X368127Y242260D02*
X365877D01*
G01X405306Y236409D02*
X407706D01*
G01X374887Y234460D02*
X372637D01*
G01X368127D02*
X365877D01*
G01X374887Y230559D02*
X372637D01*
G01X368127D02*
X365877D01*
G01X371507Y236409D02*
X369257D01*
G01X364747D02*
X362497D01*
G01X371507Y228610D02*
X369257D01*
G01X364747D02*
X362497D01*
G01X385027D02*
X382777D01*
G01X391787Y236409D02*
X389537D01*
G01X401926Y230559D02*
X399676D01*
G01Y234460D02*
X401926D01*
G01X385027Y236409D02*
X382777D01*
G01X395166Y230559D02*
X392916D01*
G01X405306Y224709D02*
X407706D01*
G01X405306Y228610D02*
X407706D01*
G01X378267Y236409D02*
X376017D01*
G01X371507Y240309D02*
X369257D01*
G01X378267D02*
X376017D01*
G01X388407Y230559D02*
X386157D01*
G01X374887Y242260D02*
X372637D01*
G01X401926Y238360D02*
X399676D01*
G01X361367Y242260D02*
X359117D01*
G01X364747Y240309D02*
X362497D01*
G01X361367Y230559D02*
X359117D01*
G01X361367Y234460D02*
X359117D01*
G01X357987Y228610D02*
X355737D01*
G01X357987Y236409D02*
X355737D01*
G01X357987Y240309D02*
X355737D01*
G01X388407Y234460D02*
X386157D01*
G01X395166D02*
X392916D01*
G01X391787Y228610D02*
X389537D01*
G01X398546Y236409D02*
X396296D01*
G01X361367Y267975D02*
X361492Y268100D01*
G01X378267Y372909D02*
X376017D01*
G01X371507Y384609D02*
X369257D01*
G01X398546Y380709D02*
X396296D01*
G01X371507Y372909D02*
X369257D01*
G01X364747D02*
X362497D01*
G01X372637Y378760D02*
X374887D01*
G01X364747Y380709D02*
X362497D01*
G01X372637Y374860D02*
X374887D01*
G01X368127D02*
X365877D01*
G01X378267Y380709D02*
X376017D01*
G01X368127Y378760D02*
X365877D01*
G01X385027Y384609D02*
X382777D01*
G01X388407Y374860D02*
X386157D01*
G01X401926Y378760D02*
X399676D01*
G01X398546Y369010D02*
X396296D01*
G01X388407Y386560D02*
X386157D01*
G01X391787Y372909D02*
X389537D01*
G01X405306Y380709D02*
X403056D01*
G01X401926Y374860D02*
X399676D01*
G01X381647Y386560D02*
X379397D01*
G01X371507Y380709D02*
X369257D01*
G01X385027D02*
X382777D01*
G01X385027Y372909D02*
X382777D01*
G01X381647Y378760D02*
X379397D01*
G01X381647Y374860D02*
X379397D01*
G01X395166Y378760D02*
X392916D01*
G01X361367Y386560D02*
X359117D01*
G01X364747Y384609D02*
X362497D01*
G01X361367Y378760D02*
X359117D01*
G01X357987Y380709D02*
X355737D01*
G01X361367Y374860D02*
X359117D01*
G01X357987Y372909D02*
X355737D01*
G01X357987Y384609D02*
X355737D01*
G01X388407Y378760D02*
X386157D01*
G01X395166Y374860D02*
X392916D01*
G01X391787Y380709D02*
X389537D01*
G01X398546Y372909D02*
X396296D01*
G01X381647Y367060D02*
X379397D01*
G01X368127Y355360D02*
X365877D01*
G01X405306Y361209D02*
X403056D01*
G01X371507Y369010D02*
X369257D01*
G01X364747D02*
X362497D01*
G01X371507Y361209D02*
X369257D01*
G01X364747D02*
X362497D01*
G01X372637Y367060D02*
X374887D01*
G01X368127D02*
X365877D01*
G01X372637Y363160D02*
X374887D01*
G01X368127D02*
X365877D01*
G01X385027Y369010D02*
X382777D01*
G01X391787Y361209D02*
X389537D01*
G01X401926Y367060D02*
X399676D01*
G01X401926Y363160D02*
X399676D01*
G01X385027Y361209D02*
X382777D01*
G01X395166Y367060D02*
X392916D01*
G01X405306Y372909D02*
X403056D01*
G01X405306Y369010D02*
X403056D01*
G01X378267Y361209D02*
X376017D01*
G01X371507Y357309D02*
X369257D01*
G01X378267D02*
X376017D01*
G01X388407Y367060D02*
X386157D01*
G01X372637Y355360D02*
X374887D01*
G01X381647Y363160D02*
X379397D01*
G01X361367Y355360D02*
X359117D01*
G01X364747Y357309D02*
X362497D01*
G01X361367Y363160D02*
X359117D01*
G01X361367Y367060D02*
X359117D01*
G01X357987Y361209D02*
X355737D01*
G01X357987Y369010D02*
X355737D01*
G01X357987Y357309D02*
X355737D01*
G01X361367Y351460D02*
X359117D01*
G01X388407Y363160D02*
X386157D01*
G01X395166D02*
X392916D01*
G01X391787Y369010D02*
X389537D01*
G01X398546Y361209D02*
X396296D01*
G01X394683Y561700D02*
Y554591D01*
X392892Y552800D01*
Y535600D01*
G01Y535200D02*
Y530721D01*
X394587Y529026D01*
G01X394683Y561723D02*
Y561700D01*
G01X424423Y196112D02*
Y162231D01*
X423574Y161382D01*
Y158900D01*
G01X421323Y196112D02*
Y164231D01*
X418536Y161444D01*
Y159100D01*
G01X432173Y196112D02*
Y162718D01*
X433431Y161460D01*
Y159100D01*
G01X427523Y196112D02*
Y159380D01*
X427243Y159100D01*
Y158861D01*
G01X422873Y197280D02*
Y163080D01*
X421055Y161262D01*
Y159000D01*
G01X435273Y196112D02*
Y164118D01*
X438469Y160922D01*
Y159300D01*
G01X436823Y196062D02*
Y164869D01*
X440988Y160704D01*
Y159600D01*
G01X433723Y196112D02*
Y163469D01*
X435950Y161242D01*
Y159100D01*
G01X429073Y196400D02*
Y159449D01*
X429762Y158760D01*
G01X425973Y196112D02*
Y158981D01*
X426093Y158861D01*
G01X430623Y196400D02*
Y159367D01*
X430912Y159078D01*
Y158726D01*
G01X443398Y196291D02*
Y185157D01*
X458042Y170513D01*
Y161550D01*
X458592Y161000D01*
G01X444948Y196691D02*
Y185800D01*
X459592Y171156D01*
Y163500D01*
X461692Y161400D01*
G01X440298Y196405D02*
Y183871D01*
X454942Y169227D01*
Y164050D01*
X453892Y163000D01*
X451992D01*
G01X441848Y196245D02*
Y184514D01*
X456492Y169870D01*
Y162300D01*
X455892Y161700D01*
G01X448048Y195343D02*
Y187086D01*
X465754Y169380D01*
Y162462D01*
X465554Y162262D01*
Y161600D01*
G01X449598Y195305D02*
Y187729D01*
X468504Y168823D01*
Y162588D01*
X468704Y162388D01*
Y161700D01*
G01X446498Y195305D02*
Y186443D01*
X464204Y168737D01*
Y162388D01*
X464404Y162188D01*
Y161600D01*
G01X451148Y195244D02*
Y188372D01*
X470054Y169466D01*
Y162562D01*
X469854Y162362D01*
Y161700D01*
G01X455798Y196056D02*
Y190301D01*
X482296Y163803D01*
G01X458088Y197401D02*
Y195396D01*
X457348Y194656D01*
Y190944D01*
X482392Y165900D01*
X484392D01*
G01X452698Y196694D02*
Y189015D01*
X476992Y164721D01*
Y161900D01*
G01X454248Y196743D02*
Y189658D01*
X479792Y164114D01*
Y162700D01*
G01X464248Y194574D02*
X480916Y177906D01*
X507826D01*
X516110Y169622D01*
Y165830D01*
G01X465641Y195374D02*
X481559Y179456D01*
X508469D01*
X518660Y169265D01*
Y165438D01*
G01X479179Y197187D02*
X486060Y190306D01*
X512970D01*
X531334Y171942D01*
X532196D01*
X532938Y171200D01*
G01X479959Y198600D02*
X486703Y191856D01*
X513613D01*
X531869Y173600D01*
X534102D01*
G01X462078Y192358D02*
X479630Y174806D01*
X506540D01*
X511010Y170336D01*
Y167318D01*
G01X463158Y193471D02*
X480273Y176356D01*
X507183D01*
X513560Y169979D01*
Y166768D01*
G01X475939Y196041D02*
X484774Y187206D01*
X511684D01*
X529692Y169198D01*
Y167319D01*
G01X476865Y197308D02*
X485417Y188756D01*
X512327D01*
X531592Y169491D01*
Y168982D01*
G01X471901Y193500D02*
X482845Y182556D01*
X509755D01*
X522360Y169951D01*
Y164932D01*
X522392Y164900D01*
G01X473195Y194399D02*
X483488Y184106D01*
X510398D01*
X525910Y168594D01*
Y164832D01*
X525942Y164800D01*
G01X470692Y192517D02*
X482203Y181006D01*
X509112D01*
X521210Y168908D01*
Y164932D01*
X521242Y164900D01*
G01X474187Y195600D02*
X484131Y185656D01*
X511041D01*
X527060Y169637D01*
Y164832D01*
X527092Y164800D01*
G01X438363Y220096D02*
X436113D01*
G01Y227896D02*
X438363D01*
G01X448503Y222047D02*
X446253D01*
G01X448503Y225947D02*
X446253D01*
G01X434983Y222047D02*
X432733D01*
G01X434983Y225947D02*
X432733D01*
G01X445123Y220096D02*
X442873D01*
G01X445123Y227896D02*
X442873D01*
G01X458643Y220096D02*
X456393D01*
G01X458643Y227896D02*
X456393D01*
G01X468783Y222047D02*
X466533D01*
G01X468783Y225947D02*
X466533D01*
G01X455263Y222047D02*
X453013D01*
G01X455263Y225947D02*
X453013D01*
G01X465403Y220096D02*
X463153D01*
G01X465403Y227896D02*
X463153D01*
G01X478922Y220096D02*
X476672D01*
G01X478922Y227896D02*
X476672D01*
G01X473292Y222047D02*
X475542D01*
G01X473292Y225947D02*
X475542D01*
G01X441743Y218147D02*
X439493D01*
G01X462023D02*
X459773D01*
G01X441743Y229847D02*
X439493D01*
G01X462023D02*
X459773D01*
G01X441743Y222047D02*
X439493D01*
G01X462023D02*
X459773D01*
G01X441743Y225947D02*
X439493D01*
G01X462023D02*
X459773D01*
G01X428224Y222047D02*
X425974D01*
G01X428224Y225947D02*
X425974D01*
G01X424844Y220096D02*
X422594D01*
G01X424844Y227896D02*
X422594D01*
G01X468783Y233746D02*
X466533D01*
G01X468783Y241547D02*
X466533D01*
G01X478922Y235696D02*
X476672D01*
G01X478922Y239596D02*
X476672D01*
G01X465403Y235696D02*
X463153D01*
G01X465403Y239596D02*
X463153D01*
G01X473292Y233746D02*
X475542D01*
G01X473292Y241547D02*
X475542D01*
G01X421464Y218147D02*
X419214D01*
G01X472163Y231797D02*
X469913D01*
G01X421464Y225947D02*
X419214D01*
G01X472163Y243496D02*
X469913D01*
G01X421464Y222047D02*
X419214D01*
G01X472163Y235696D02*
X469913D01*
G01X421464Y229847D02*
X419214D01*
G01X472163Y239596D02*
X469913D01*
G01X418084Y251296D02*
Y253546D01*
G01X462023Y264947D02*
X459773D01*
G01X475542Y311747D02*
X477792D01*
G01X472163Y309797D02*
X469913D01*
G01X434983Y358547D02*
X437233D01*
G01X431604Y360496D02*
X433854D01*
G01X448503Y358547D02*
X450753D01*
G01X438323Y419868D02*
Y440530D01*
X441293Y443500D01*
G01X439873Y419880D02*
Y439681D01*
G01X422823Y419400D02*
Y440569D01*
X419892Y443500D01*
G01X424373Y419400D02*
Y441519D01*
X422435Y443457D01*
G01X435223Y419500D02*
Y442331D01*
X441042Y448150D01*
G01X430573Y419581D02*
Y444281D01*
X431392Y445100D01*
Y447900D01*
X431192Y448100D01*
G01X429023Y419631D02*
Y444931D01*
X429842Y445750D01*
Y447900D01*
X430042Y448100D01*
G01X433673Y419581D02*
Y442981D01*
X435242Y444550D01*
Y446150D01*
X435103Y446289D01*
G01X449172Y416866D02*
Y430947D01*
X463592Y445367D01*
Y449100D01*
G01X450722Y416866D02*
Y430304D01*
X466192Y445774D01*
Y448100D01*
G01X461572Y416820D02*
Y425801D01*
X474921Y439150D01*
X480049D01*
X484399Y443500D01*
X485792D01*
G01X463122Y416820D02*
Y425158D01*
X475564Y437600D01*
X480692D01*
X484792Y441700D01*
X487592D01*
G01X446072Y416820D02*
Y432233D01*
X459192Y445353D01*
Y450600D01*
X458392Y451400D01*
G01X447622Y416830D02*
Y431590D01*
X460992Y444960D01*
Y450300D01*
G01X458472Y416866D02*
Y427087D01*
X473635Y442250D01*
X478243D01*
X479292Y443299D01*
Y445000D01*
X480242Y445950D01*
G01X470392Y416292D02*
X478651Y424551D01*
X511387D01*
X520792Y433956D01*
Y438001D01*
G01X467192Y417480D02*
X477363Y427651D01*
X510101D01*
X515592Y433142D01*
Y438200D01*
G01X468505Y416600D02*
X478006Y426101D01*
X510744D01*
X518192Y433549D01*
Y437650D01*
G01X477928Y409901D02*
X483278Y415251D01*
X515247D01*
X528194Y428198D01*
X530190D01*
X530988Y428996D01*
G01X453822Y416947D02*
Y429018D01*
X470492Y445688D01*
Y446200D01*
X474953Y450661D01*
Y450934D01*
G01X474692Y414500D02*
X475181D01*
X480582Y419901D01*
X513316D01*
X526042Y432627D01*
Y433370D01*
X527392Y434720D01*
Y435000D01*
G01X452272Y416997D02*
Y429661D01*
X468992Y446381D01*
Y446893D01*
X473847Y451748D01*
X474140D01*
G01X474142Y415082D02*
Y415655D01*
X479938Y421451D01*
X512673D01*
X524492Y433270D01*
Y434000D01*
X526305Y435813D01*
X526578D01*
G01X456922Y416947D02*
Y427731D01*
X473541Y444350D01*
X475092D01*
X476992Y446250D01*
Y446500D01*
G01X530392Y432041D02*
Y431800D01*
X528987Y430395D01*
X528197D01*
X514603Y416801D01*
X481870D01*
X477969Y412900D01*
X477492D01*
G01X421464Y358547D02*
X423714D01*
G01X468783Y346847D02*
X471033D01*
G01X425923Y419500D02*
Y442968D01*
X424954Y443937D01*
G01X427473Y419500D02*
Y446981D01*
G01X439873Y439681D02*
X441092Y440900D01*
G01X436773Y419500D02*
Y441681D01*
X441092Y446000D01*
X442792D01*
G01X432123Y419569D02*
Y443631D01*
X433692Y445200D01*
Y446150D01*
X433892Y446350D01*
G01X460022Y416866D02*
Y426444D01*
X474278Y440700D01*
X479406D01*
X480992Y442286D01*
Y443100D01*
X483492Y445600D01*
G01X471593Y415300D02*
X479294Y423001D01*
X512030D01*
X522792Y433763D01*
Y436700D01*
G01X455372Y416935D02*
Y428374D01*
X472898Y445900D01*
X474449D01*
X475949Y447400D01*
X476265D01*
G01X476892Y413432D02*
Y414017D01*
X481226Y418351D01*
X513960D01*
X527550Y431941D01*
X528340D01*
X529299Y432900D01*
X529628D01*
G01X535251Y204496D02*
X533001D01*
G01X536381Y222047D02*
X538631D01*
G01X499202Y270796D02*
X501452D01*
G01X499202Y255196D02*
X501452D01*
G01X499202Y251296D02*
X501452D01*
G01X519481Y270796D02*
X521731D01*
G01X489062Y261047D02*
X486812D01*
G01X485682Y262996D02*
X483432D01*
G01X516102Y261047D02*
X518352D01*
G01X522861D02*
X525111D01*
G01X512722Y251296D02*
X514972D01*
G01X516102Y272747D02*
X518352D01*
G01X519481Y255196D02*
X521731D01*
G01X519481Y251296D02*
X521731D01*
G01X495822Y264947D02*
X498072D01*
G01X509342Y245447D02*
X511592D01*
G01X512722Y243496D02*
X514972D01*
G01X485682Y231797D02*
X483432D01*
G01X482302Y218147D02*
X480052D01*
G01X482302Y225947D02*
X480052D01*
G01X482302Y222047D02*
X480052D01*
G01X482302Y229847D02*
X480052D01*
G01X522861Y272747D02*
X525111D01*
G01X492442Y266896D02*
X494692D01*
G01X502582Y257147D02*
X504832D01*
G01X505962Y251296D02*
X508212D01*
G01X502582Y249347D02*
X504832D01*
G01X505962Y247396D02*
X508212D01*
G01X516102Y245447D02*
X518352D01*
G01X529621Y257147D02*
X531871D01*
G01X526241Y255196D02*
X528491D01*
G01X509342Y253247D02*
X511592D01*
G01X522861Y268847D02*
X525111D01*
G01X516102Y241547D02*
X518352D01*
G01X516102Y237647D02*
X518352D01*
G01X519481Y239596D02*
X521731D01*
G01X519481Y243496D02*
X521731D01*
G01X522861Y249347D02*
X525111D01*
G01X522861Y245447D02*
X525111D01*
G01X505962Y266896D02*
X508212D01*
G01X495822Y253247D02*
X498072D01*
G01X495822Y257147D02*
X498072D01*
G01X522861D02*
X525111D01*
G01X526241Y259096D02*
X528491D01*
G01X516102Y268847D02*
X518352D01*
G01X516102Y249347D02*
X518352D01*
G01X499202Y262996D02*
X501452D01*
G01X502582Y261047D02*
X504832D01*
G01X495822D02*
X498072D01*
G01X492442Y259096D02*
X494692D01*
G01X492442Y274696D02*
X494692D01*
G01X529621Y327347D02*
X531871D01*
G01X482302Y284447D02*
X484552D01*
G01X478922Y329296D02*
X481172D01*
G01X489062Y323446D02*
X491312D01*
G01X492442Y317596D02*
X494692D01*
G01X485682Y321496D02*
X487932D01*
G01X482302Y327347D02*
X484552D01*
G01X485682Y325396D02*
X487932D01*
G01X537342Y426650D02*
X535542Y424850D01*
X529232D01*
X516533Y412151D01*
X484564D01*
X479948Y407535D01*
G01X480748Y406141D02*
X485208Y410601D01*
X517176D01*
X529875Y423300D01*
X537792D01*
X538392Y423900D01*
G01X478922Y408702D02*
X483921Y413701D01*
X515890D01*
X528589Y426400D01*
X532560D01*
X533242Y427082D01*
G01X579900Y117700D02*
X589650D01*
G01X543141Y268847D02*
X545391D01*
G01X656190Y301548D02*
Y297590D01*
X654600Y296000D01*
G01X703438Y269597D02*
X697307Y275728D01*
G01D02*
X695920Y277115D01*
Y279620D01*
X693040Y282500D01*
X691495D01*
X690048Y281053D01*
G01X705320Y270430D02*
X703878D01*
X696820Y277488D01*
Y280080D01*
X693500Y283400D01*
X690701D01*
X690048Y284053D01*
G01X709959Y218298D02*
X712058D01*
X713404Y219644D01*
X714644D01*
X716000Y221000D01*
X718000Y221100D01*
G01X771773Y220235D02*
X769978D01*
X768932Y219189D01*
X766232D01*
X765632Y218589D01*
X765186D01*
G01X761600Y249020D02*
X763080Y250500D01*
X766999D01*
X767688Y251189D01*
X768932D01*
X769978Y252235D01*
X771773D01*
G01Y316235D02*
X769978D01*
X768932Y315189D01*
X766232D01*
X765757Y314714D01*
X764095D01*
X762417Y316392D01*
G01X771723Y380235D02*
X769928D01*
X768882Y379189D01*
X766790D01*
X766134Y378533D01*
X764331D01*
X762452Y380412D01*
Y380738D01*
G01X908238Y186261D02*
X909168Y187191D01*
X913259D01*
X917903Y191835D01*
X934998D01*
X935698Y192535D01*
X951398D01*
X955056Y196193D01*
Y196641D01*
G01X910046Y184453D02*
X911234Y185641D01*
X913902D01*
G01X906400Y188000D02*
X907102Y188702D01*
Y188741D01*
G01X917095Y177402D02*
X917827Y178134D01*
Y178601D01*
X921761Y182535D01*
G01X918899Y175598D02*
X919653Y176352D01*
Y178234D01*
X922404Y180985D01*
X936034D01*
X939184Y184135D01*
X954884D01*
X965256Y194507D01*
Y194707D01*
G01X912651Y181816D02*
X913376Y182541D01*
X915188D01*
X919832Y187185D01*
X935442D01*
G01X914464Y180014D02*
X915041Y180591D01*
X915431D01*
X920475Y185635D01*
X935590D01*
X937690Y187735D01*
X953390D01*
X959346Y193691D01*
G01X911838Y182630D02*
X913299Y184091D01*
X914545D01*
G01X915277Y179200D02*
X915518Y179441D01*
X916474D01*
X921118Y184085D01*
X935738D01*
X938188Y186535D01*
X953888D01*
X960066Y192713D01*
G01X950091Y196126D02*
X947700Y193735D01*
X935200D01*
X934850Y193385D01*
X917260D01*
X912616Y188741D01*
X907102D01*
G01X952194Y404851D02*
X941336D01*
X937388Y408799D01*
X933248D01*
X931898Y407449D01*
X930843D01*
G01X956679Y402064D02*
X952692Y406051D01*
X941834D01*
X937886Y409999D01*
X930843D01*
G01X948914Y403651D02*
X940838D01*
X936890Y407599D01*
X933746D01*
X931046Y404899D01*
X929782D01*
G01X962274Y404959D02*
X955182Y412051D01*
X944332D01*
X936434Y419949D01*
X935849D01*
G01X963356Y405575D02*
X955680Y413251D01*
X944830D01*
X935582Y422499D01*
X934756D01*
G01X958556Y403583D02*
X953688Y408451D01*
X942838D01*
X937590Y413699D01*
X936256D01*
G01X960056Y403781D02*
X954186Y409651D01*
X943336D01*
X936728Y416259D01*
X936256D01*
G01X957856Y402585D02*
X953190Y407251D01*
X942340D01*
X937042Y412549D01*
X936256D01*
G01X960975Y404560D02*
X954684Y410851D01*
X943834D01*
X937286Y417399D01*
X936256D01*
G01X920707Y173790D02*
X921271Y174354D01*
Y177659D01*
X923047Y179435D01*
X936182D01*
X939682Y182935D01*
X955382D01*
X964268Y191821D01*
X966756D01*
G01X948457Y169612D02*
X949037Y170192D01*
X955248D01*
X958447Y173391D01*
X961266D01*
X977337Y189462D01*
Y197141D01*
G01X950184Y167678D02*
Y167679D01*
X951147Y168642D01*
X955890D01*
X959439Y172191D01*
X961764D01*
X978537Y188964D01*
Y197141D01*
G01X947644Y170426D02*
X948960Y171742D01*
X954605D01*
X957454Y174591D01*
G01X950998Y166865D02*
X951225Y167092D01*
X956533D01*
X957815Y168374D01*
G01X973737Y197141D02*
Y190956D01*
X959772Y176991D01*
X955469D01*
X953320Y174842D01*
X944846D01*
X944226Y174222D01*
G01X945934Y172323D02*
X946903Y173292D01*
X953963D01*
X956462Y175791D01*
X960270D01*
G01X957576Y160773D02*
Y161556D01*
X963411Y167391D01*
X963756D01*
X966215Y169850D01*
G01X942431Y176233D02*
X942590Y176392D01*
X952676D01*
X954475Y178191D01*
X959274D01*
X972537Y191454D01*
G01X980937Y187968D02*
X962760Y169791D01*
X961426D01*
X957177Y165542D01*
X953297D01*
X952866Y165111D01*
G01X954966Y163620D02*
X955338Y163992D01*
G01X933237Y216909D02*
X930987D01*
G01X950137Y214960D02*
X947887D01*
G01X960276Y216909D02*
X958026D01*
G01X946757D02*
X944507D01*
G01X956897Y214960D02*
X954647D01*
G01X953517Y213009D02*
X951267D01*
G01X953517Y216909D02*
X951267D01*
G01X936617Y203260D02*
X934367D01*
G01X936617Y211060D02*
X934367D01*
G01X946757Y205210D02*
X944507D01*
G01X946757Y209109D02*
X944507D01*
G01X933237Y205210D02*
X930987D01*
G01X933237Y209109D02*
X930987D01*
G01X943377Y203260D02*
X941127D01*
G01X943377Y211060D02*
X941127D01*
G01X956775Y196214D02*
X951896Y191335D01*
X936196D01*
X935146Y190285D01*
X918546D01*
X913902Y185641D01*
G01X963800Y195185D02*
Y194749D01*
X954386Y185335D01*
X938686D01*
G01D02*
X935886Y182535D01*
X921761D01*
G01X939997Y201309D02*
X937747D01*
G01X957916Y193959D02*
X952892Y188935D01*
X937192D01*
X935442Y187185D01*
G01X939997Y213009D02*
X937747D01*
G01X939997Y205210D02*
X937747D01*
G01X957110Y194851D02*
X952394Y190135D01*
G01D02*
X936694D01*
X935294Y188735D01*
X919189D01*
X914545Y184091D01*
G01X976137Y197141D02*
Y189960D01*
X960768Y174591D01*
X957454D01*
G01X939997Y209109D02*
X937747D01*
G01X979737Y197141D02*
Y188466D01*
X962262Y170991D01*
X960432D01*
X957815Y168374D01*
G01X974937Y197141D02*
Y190458D01*
X960270Y175791D01*
G01X966215Y169850D02*
X983337Y186972D01*
G01X972537Y191454D02*
Y197141D01*
G01X955338Y163992D02*
X957819D01*
X962418Y168591D01*
X963258D01*
X982137Y187470D01*
Y197141D01*
G01X916337Y257860D02*
X913787D01*
G01X933237Y228610D02*
X930987D01*
G01X939997Y224709D02*
X937747D01*
G01X929857Y218860D02*
X927607D01*
G01X923097Y257860D02*
X920847D01*
G01X936617Y230559D02*
X934367D01*
G01X939997Y228610D02*
X937747D01*
G01X929857Y222760D02*
X927607D01*
G01X936617Y218860D02*
X934367D01*
G01X950137Y222760D02*
X947887D01*
G01X960276Y220809D02*
X958026D01*
G01X946757D02*
X944507D01*
G01X916337Y242260D02*
X913700D01*
G01X956897Y222760D02*
X954647D01*
G01X923097Y242260D02*
X920847D01*
G01X916337Y261760D02*
X913787D01*
G01X916337Y246160D02*
X913787D01*
G01X923097D02*
X920847D01*
G01X923097Y250060D02*
X920847D01*
G01X929857Y226660D02*
X927607D01*
G01X939997Y220809D02*
X937747D01*
G01X953517Y224709D02*
X951267D01*
G01X923097Y253960D02*
X920847D01*
G01X919717Y248109D02*
X917467D01*
G01X933237Y224709D02*
X930987D01*
G01X936617Y222760D02*
X934367D01*
G01X953517Y220809D02*
X951267D01*
G01X919717Y255909D02*
X917467D01*
G01X973796Y240309D02*
X971546D01*
G01X973796Y244209D02*
X971546D01*
G01X929857Y238360D02*
X927607D01*
G01X933237Y236409D02*
X930987D01*
G01X936617Y250060D02*
X934367D01*
G01X939997Y248109D02*
X937747D01*
G01X929857Y242260D02*
X927607D01*
G01X936617Y238360D02*
X934367D01*
G01X933237Y248109D02*
X930987D01*
G01X939997Y244209D02*
X937747D01*
G01X929857Y246160D02*
X927607D01*
G01X939997Y240309D02*
X937747D01*
G01X933237Y244209D02*
X930987D01*
G01X936617Y242260D02*
X934367D01*
G01X963656Y273460D02*
X961406D01*
G01X973796Y267609D02*
X971546D01*
G01X960276Y271509D02*
X958026D01*
G01X970416Y273460D02*
X968166D01*
G01X970416Y285160D02*
X968166D01*
G01X955080Y401965D02*
X952194Y404851D01*
G01X964322Y406307D02*
X956178Y414451D01*
X945328D01*
X934730Y425049D01*
G01X950106Y402459D02*
X948914Y403651D01*
G01X971800Y403320D02*
Y404571D01*
G01X934730Y425049D02*
X934156D01*
G01X979266Y395641D02*
Y406655D01*
X976556Y409365D01*
Y410847D01*
X960940Y426463D01*
X957279D01*
X956577Y427165D01*
G01X977756Y409863D02*
Y411839D01*
X961584Y428011D01*
X960106D01*
X958454Y429663D01*
G01X978066Y395641D02*
Y406157D01*
X975356Y408867D01*
Y409855D01*
X960298Y424913D01*
X957201D01*
X955800Y426314D01*
G01X981666Y395641D02*
Y407651D01*
X978956Y410361D01*
Y412831D01*
X962008Y429779D01*
X959965D01*
X959267Y430477D01*
G01X975666Y395641D02*
Y405161D01*
X959012Y421815D01*
X953043D01*
X951600Y423258D01*
G01X976866Y395641D02*
Y405659D01*
X974156Y408369D01*
Y408863D01*
X959655Y423364D01*
X955144D01*
X954196Y424312D01*
G01X985266Y395641D02*
Y409145D01*
X982556Y411855D01*
Y415807D01*
X964321Y434042D01*
Y436182D01*
X963690Y436813D01*
G01X973106Y403189D02*
Y405528D01*
X958368Y420266D01*
X951028D01*
X950355Y420939D01*
G01X982866Y395641D02*
Y408149D01*
X980156Y410859D01*
Y413823D01*
X962339Y431640D01*
X961687D01*
X960779Y432548D01*
G01X984066Y395641D02*
Y408647D01*
X981356Y411357D01*
Y414815D01*
X962849Y433322D01*
Y434049D01*
X962091Y434807D01*
G01X1024495Y207159D02*
X1022245D01*
G01X994076Y205210D02*
X991826D01*
G01X1024495Y211060D02*
X1022245D01*
G01X997456Y207159D02*
X995206D01*
G01X1000836Y205210D02*
X998586D01*
G01X1021115Y213009D02*
X1018865D01*
G01X1000836Y216909D02*
X998586D01*
G01X994076Y213009D02*
X991826D01*
G01X990696Y214960D02*
X988446D01*
G01X1025625Y216909D02*
X1027875D01*
G01X1014355D02*
X1012105D01*
G01X1034635Y213009D02*
X1032385D01*
G01X983337Y195141D02*
Y186972D01*
G01X980937Y197141D02*
Y187968D01*
G01X1021115Y216909D02*
X1018865D01*
G01X1034635D02*
X1032385D01*
G01X1010975Y211060D02*
X1008725D01*
G01X1014355Y213009D02*
X1012105D01*
G01X1007595Y216909D02*
X1005345D01*
G01X1007595Y213009D02*
X1005345D01*
G01X990696Y226660D02*
X988446Y230560D01*
G01X980556Y236409D02*
X978306D01*
G01X980556Y248109D02*
X978306D01*
G01X980556Y240309D02*
X978306D01*
G01X980556Y244209D02*
X978306D01*
G01X977176Y238360D02*
X974926D01*
G01X977176Y246160D02*
X974926D01*
G01X987316Y240309D02*
X985066D01*
G01X987316Y244209D02*
X985066D01*
G01X983936Y238360D02*
X981686D01*
G01X983936Y246160D02*
X981686D01*
G01X1025625Y224709D02*
X1027875D01*
G01X1004215Y218860D02*
X1001965D01*
G01X997456D02*
X995206D01*
G01X990696Y222760D02*
X988446D01*
G01X1017735Y218860D02*
X1015485D01*
G01X1024495Y222760D02*
X1022245D01*
G01X1017735D02*
X1015485D01*
G01X1024495Y218860D02*
X1022245D01*
G01X1021115Y224709D02*
X1018865D01*
G01X1014355D02*
X1012105D01*
G01X1004215Y222760D02*
X1001965D01*
G01X1000836Y224709D02*
X998586D01*
G01X1034635D02*
X1032385D01*
G01X1031255Y218860D02*
X1029005D01*
G01X1031255Y222760D02*
X1029005D01*
G01X1010975Y218860D02*
X1008725D01*
G01X1010975Y222760D02*
X1008725D01*
G01X1007595Y224709D02*
X1005345D01*
G01X1000836Y228610D02*
X998586D01*
G01X1004215Y230559D02*
X1001965D01*
G01X1000836Y236409D02*
X998586D01*
G01X1000836Y240309D02*
X998586D01*
G01X1031255Y230559D02*
X1029005D01*
G01X1017735Y242260D02*
X1015485D01*
G01X1004215Y234460D02*
X1001965D01*
G01X997456Y242260D02*
X995206D01*
G01X997456Y234460D02*
X995206D01*
G01X994076Y240309D02*
X991826D01*
G01X994076Y228610D02*
X991826D01*
G01X994076Y236409D02*
X991826D01*
G01X1024495Y234460D02*
X1022245D01*
G01X1017735D02*
X1015485D01*
G01X1024495Y230559D02*
X1022245D01*
G01X1017735D02*
X1015485D01*
G01X1021115Y236409D02*
X1018865D01*
G01X1014355D02*
X1012105D01*
G01X1021115Y228610D02*
X1018865D01*
G01X1014355D02*
X1012105D01*
G01X1034635D02*
X1032385D01*
G01X1034635Y236409D02*
X1032385D01*
G01X980556Y263709D02*
X978306D01*
G01X977176Y257860D02*
X974926D01*
G01X1027875Y236409D02*
X1025625D01*
G01X1021115Y240309D02*
X1018865D01*
G01X1027875D02*
X1025625D01*
G01X1024495Y242260D02*
X1022245D01*
G01X1010975D02*
X1008725D01*
G01X1014355Y240309D02*
X1012105D01*
G01X1010975Y230559D02*
X1008725D01*
G01X1010975Y234460D02*
X1008725D01*
G01X1007595Y228610D02*
X1005345D01*
G01X1007595Y236409D02*
X1005345D01*
G01X1004215Y242260D02*
X1001965D01*
G01X1007595Y240309D02*
X1005345D01*
G01X1010975Y261760D02*
X1008725D01*
G01X1000836Y337809D02*
X998586D01*
G01X997456Y312460D02*
X995206D01*
G01X997456Y316360D02*
X995206D01*
G01X983936Y285160D02*
X981686D01*
G01X994076Y384609D02*
X991826D01*
G01X1025625Y372909D02*
X1027875D01*
G01X1021115Y384609D02*
X1018865D01*
G01X997456Y367060D02*
X995206D01*
G01X1000836Y372909D02*
X998586D01*
G01X994076D02*
X991826D01*
G01X990696Y374860D02*
X988446D01*
G01X990696Y370959D02*
X988446D01*
G01X990696Y378760D02*
X988446D01*
G01X1021115Y372909D02*
X1018865D01*
G01X1014355D02*
X1012105D01*
G01X1022245Y378760D02*
X1024495D01*
G01X1014355Y380709D02*
X1012105D01*
G01X1022245Y374860D02*
X1024495D01*
G01X1017735D02*
X1015485D01*
G01X1025625Y380709D02*
X1027875D01*
G01X1017735Y378760D02*
X1015485D01*
G01X1034635Y384609D02*
X1032385D01*
G01X980466Y395641D02*
Y407153D01*
G01X1031255Y386560D02*
X1029005D01*
G01X1021115Y380709D02*
X1018865D01*
G01X1004215Y378760D02*
X1001965D01*
G01X1004215Y374860D02*
X1001965D01*
G01X1034635Y380709D02*
X1032385D01*
G01X1034635Y372909D02*
X1032385D01*
G01X1031255Y378760D02*
X1029005D01*
G01X1031255Y374860D02*
X1029005D01*
G01X1010975Y386560D02*
X1008725D01*
G01X1014355Y384609D02*
X1012105D01*
G01X1010975Y378760D02*
X1008725D01*
G01X1007595Y380709D02*
X1005345D01*
G01X1010975Y374860D02*
X1008725D01*
G01X1007595Y372909D02*
X1005345D01*
G01X1000836Y369010D02*
X998586D01*
G01X1004215Y367060D02*
X1001965D01*
G01X1007595Y384609D02*
X1005345D01*
G01X1031255Y367060D02*
X1029005D01*
G01X1017735Y355360D02*
X1015485D01*
G01X997456Y351460D02*
X995206D01*
G01X1000836Y361209D02*
X998586D01*
G01X997456Y363160D02*
X995206D01*
G01X994076Y357309D02*
X991826D01*
G01X994076Y369010D02*
X991826D01*
G01X994076Y361209D02*
X991826D01*
G01X1021115Y369010D02*
X1018865D01*
G01X1014355D02*
X1012105D01*
G01X1021115Y361209D02*
X1018865D01*
G01X1014355D02*
X1012105D01*
G01X1022245Y367060D02*
X1024495D01*
G01X1017735D02*
X1015485D01*
G01X1022245Y363160D02*
X1024495D01*
G01X1017735D02*
X1015485D01*
G01X1034635Y369010D02*
X1032385D01*
G01X1034635Y361209D02*
X1032385D01*
G01X1027875D02*
X1025625D01*
G01X1021115Y357309D02*
X1018865D01*
G01X1004215Y351460D02*
X1001965D01*
G01X1004215Y363160D02*
X1001965D01*
G01X1025625Y357309D02*
X1027875D01*
G01X1022245Y355360D02*
X1024495D01*
G01X1031255Y363160D02*
X1029005D01*
G01X1010975Y355360D02*
X1008725D01*
G01X1014355Y357309D02*
X1012105D01*
G01X1010975Y363160D02*
X1008725D01*
G01X1010975Y367060D02*
X1008725D01*
G01X1007595Y361209D02*
X1005345D01*
G01X1007595Y369010D02*
X1005345D01*
G01X1004215Y355360D02*
X1001965D01*
G01X1007595Y357309D02*
X1005345D01*
G01X1010975Y351460D02*
X1008725D01*
G01X1000836Y341709D02*
X998586D01*
G01X1000836Y345609D02*
X998586D01*
G01X980466Y407153D02*
X977756Y409863D01*
G01X1045525Y15357D02*
Y16376D01*
X1044290Y17611D01*
Y22922D01*
X1044291Y22923D01*
G01X1044293D02*
X1044291D01*
G01D02*
Y32809D01*
X1042500Y34600D01*
Y45111D01*
X1046000Y48611D01*
Y51799D01*
X1045800Y51999D01*
Y55399D01*
X1044291Y56908D01*
G01X1045525Y15357D02*
X1045419D01*
X1042500Y12438D01*
Y-5350D01*
X1045500Y-8350D01*
Y-10800D01*
X1044291Y-12009D01*
Y-14877D01*
X1044293D01*
G01X1072481Y197280D02*
Y163080D01*
X1070663Y161262D01*
Y159000D01*
G01X1073182Y158900D02*
Y161382D01*
X1074031Y162231D01*
Y196112D01*
G01X1084881D02*
Y164118D01*
X1088077Y160922D01*
Y159300D01*
G01X1086431Y196062D02*
Y164869D01*
X1090596Y160704D01*
Y159600D01*
G01X1065625Y159300D02*
Y161326D01*
X1069381Y165082D01*
Y196062D01*
X1069331Y196112D01*
G01X1068144Y159100D02*
Y161444D01*
X1070931Y164231D01*
Y196112D01*
G01X1081781D02*
Y162718D01*
X1083039Y161460D01*
Y159100D01*
G01X1083331Y196112D02*
Y163469D01*
X1085558Y161242D01*
Y159100D01*
G01X1076851Y158861D02*
Y159100D01*
X1077131Y159380D01*
Y196112D01*
G01X1079370Y158760D02*
X1078681Y159449D01*
Y169850D01*
G01X1075581Y196112D02*
Y158981D01*
X1075701Y158861D01*
G01X1080231Y196400D02*
Y159367D01*
X1080520Y159078D01*
Y158726D01*
G01X1051534Y207159D02*
X1049284D01*
G01X1078681Y196400D02*
Y169850D01*
G01X1044774Y211060D02*
X1042524D01*
G01X1041395Y213009D02*
X1039145D01*
G01X1048154D02*
X1045904D01*
G01X1048154Y216909D02*
X1045904D01*
G01X1038015Y211060D02*
X1035765D01*
G01X1054914Y216909D02*
X1057314D01*
G01X1108200Y161000D02*
X1107650Y161550D01*
Y170513D01*
X1093006Y185157D01*
Y196291D01*
G01X1094556Y196691D02*
Y185800D01*
X1109200Y171156D01*
Y163500D01*
X1111300Y161400D01*
G01X1101600Y163000D02*
X1103500D01*
X1104550Y164050D01*
Y169227D01*
X1089906Y183871D01*
Y196405D01*
G01X1091456Y196245D02*
Y184514D01*
X1106100Y169870D01*
Y162300D01*
X1105500Y161700D01*
G01X1039145Y216909D02*
X1041395D01*
G01X1087971Y220096D02*
X1085721D01*
G01Y227896D02*
X1087971D01*
G01X1084591Y222047D02*
X1082341D01*
G01X1084591Y225947D02*
X1082341D01*
G01X1094731Y220096D02*
X1092481D01*
G01X1094731Y227896D02*
X1092481D01*
G01X1091351Y218147D02*
X1089101D01*
G01X1091351Y229847D02*
X1089101D01*
G01X1091351Y222047D02*
X1089101D01*
G01X1091351Y225947D02*
X1089101D01*
G01X1038015Y222760D02*
X1035765D01*
G01X1051534Y218860D02*
X1049284D01*
G01X1048154Y228610D02*
X1045904D01*
G01X1041395Y224709D02*
X1039145D01*
G01X1051534Y222760D02*
X1049284D01*
G01X1077832Y222047D02*
X1075582D01*
G01X1077832Y225947D02*
X1075582D01*
G01X1074452Y220096D02*
X1072202D01*
G01X1074452Y227896D02*
X1072202D01*
G01X1071072Y218147D02*
X1068822D01*
G01X1071072Y225947D02*
X1068822D01*
G01X1071072Y222047D02*
X1068822D01*
G01X1071072Y229847D02*
X1068822D01*
G01X1044774Y218860D02*
X1042524D01*
G01X1038015D02*
X1035765D01*
G01X1044774Y222760D02*
X1042524D01*
G01X1045904Y224709D02*
X1048154D01*
G01X1054914Y236409D02*
X1057314D01*
G01X1041395D02*
X1039145D01*
G01X1051534Y230559D02*
X1049284D01*
G01Y234460D02*
X1051534D01*
G01X1044774Y230559D02*
X1042524D01*
G01X1054914Y224709D02*
X1057314D01*
G01X1054914Y228610D02*
X1057314D01*
G01X1038015Y230559D02*
X1035765D01*
G01X1051534Y238360D02*
X1049284D01*
G01X1038015Y234460D02*
X1035765D01*
G01X1044774D02*
X1042524D01*
G01X1041395Y228610D02*
X1039145D01*
G01X1048154Y236409D02*
X1045904D01*
G01X1071072Y253247D02*
Y255728D01*
G01X1087971Y255196D02*
Y257800D01*
G01X1091351Y257147D02*
Y259600D01*
G01X1094731Y259096D02*
Y261500D01*
G01X1084591Y253247D02*
Y255497D01*
G01X1081212Y255196D02*
Y257600D01*
G01X1067692Y251296D02*
Y254000D01*
G01X1084591Y358547D02*
X1086841D01*
G01X1081212Y360496D02*
X1083462D01*
G01X1090901Y443500D02*
X1087931Y440530D01*
Y419868D01*
G01X1089481Y419880D02*
Y439681D01*
G01X1072431Y419400D02*
Y440569D01*
X1069500Y443500D01*
G01X1073981Y419400D02*
Y441519D01*
X1072043Y443457D01*
G01X1084831Y419500D02*
Y442331D01*
X1090650Y448150D01*
G01X1080181Y419581D02*
Y444281D01*
X1081000Y445100D01*
Y447900D01*
X1080800Y448100D01*
G01X1078631Y419631D02*
Y444931D01*
X1079450Y445750D01*
Y447900D01*
X1079650Y448100D01*
G01X1083281Y419581D02*
Y442981D01*
X1084850Y444550D01*
Y446150D01*
X1084711Y446289D01*
G01X1048154Y380709D02*
X1045904D01*
G01X1038015Y374860D02*
X1035765D01*
G01X1051534Y378760D02*
X1049284D01*
G01X1048154Y369010D02*
X1045904D01*
G01X1038015Y386560D02*
X1035765D01*
G01X1041395Y372909D02*
X1039145D01*
G01X1054914Y380709D02*
X1052664D01*
G01X1051534Y374860D02*
X1049284D01*
G01X1044774Y378760D02*
X1042524D01*
G01X1038015D02*
X1035765D01*
G01X1044774Y374860D02*
X1042524D01*
G01X1041395Y380709D02*
X1039145D01*
G01X1048154Y372909D02*
X1045904D01*
G01X1054914Y361209D02*
X1052664D01*
G01X1041395D02*
X1039145D01*
G01X1051534Y367060D02*
X1049284D01*
G01X1051534Y363160D02*
X1049284D01*
G01X1044774Y367060D02*
X1042524D01*
G01X1054914Y372909D02*
X1052664D01*
G01X1054914Y369010D02*
X1052664D01*
G01X1071072Y358547D02*
X1073322D01*
G01X1038015Y367060D02*
X1035765D01*
G01X1038015Y363160D02*
X1035765D01*
G01X1044774D02*
X1042524D01*
G01X1041395Y369010D02*
X1039145D01*
G01X1048154Y361209D02*
X1045904D01*
G01X1075531Y419500D02*
Y442968D01*
X1074562Y443937D01*
G01X1077081Y419500D02*
Y446981D01*
G01X1089481Y439681D02*
X1090700Y440900D01*
G01X1086381Y419500D02*
Y441681D01*
X1090700Y446000D01*
X1092400D01*
G01X1081731Y419569D02*
Y443631D01*
X1083300Y445200D01*
Y446150D01*
X1083500Y446350D01*
G01X1095680Y416820D02*
Y432233D01*
X1108800Y445353D01*
Y450600D01*
X1108000Y451400D01*
G01X1097230Y416830D02*
Y431590D01*
X1110600Y444960D01*
Y450300D01*
G01X1105406Y196056D02*
Y190301D01*
X1131904Y163803D01*
G01X1107696Y197401D02*
Y195396D01*
X1106956Y194656D01*
Y190944D01*
X1132000Y165900D01*
X1134000D01*
G01X1102306Y196694D02*
Y189015D01*
X1126600Y164721D01*
Y161900D01*
G01X1103856Y196743D02*
Y189658D01*
X1129400Y164114D01*
Y162700D01*
G01X1115162Y161600D02*
Y162262D01*
X1115362Y162462D01*
Y169380D01*
X1097656Y187086D01*
Y195343D01*
G01X1118312Y161700D02*
Y162388D01*
X1118112Y162588D01*
Y168823D01*
X1099206Y187729D01*
Y195305D01*
G01X1114012Y161600D02*
Y162188D01*
X1113812Y162388D01*
Y168737D01*
X1096106Y186443D01*
Y195305D01*
G01X1119462Y161700D02*
Y162362D01*
X1119662Y162562D01*
Y169466D01*
X1100756Y188372D01*
Y195244D01*
G01X1165718Y165830D02*
Y169622D01*
X1157434Y177906D01*
X1134819D01*
G01X1113856Y194574D02*
X1130524Y177906D01*
X1134819D01*
G01X1115249Y195374D02*
X1131167Y179456D01*
X1134819D01*
G01X1168268Y165438D02*
Y169265D01*
X1158077Y179456D01*
X1134819D01*
G01X1128787Y197187D02*
X1134819Y191155D01*
G01D02*
X1135668Y190306D01*
X1162578D01*
X1180942Y171942D01*
X1181804D01*
X1182546Y171200D01*
G01X1129567Y198600D02*
X1134819Y193348D01*
G01D02*
X1136311Y191856D01*
X1163221D01*
X1181477Y173600D01*
X1183710D01*
G01X1111686Y192358D02*
X1129238Y174806D01*
X1134819D01*
G01X1160618Y167318D02*
Y170336D01*
X1156148Y174806D01*
X1134819D01*
G01X1112766Y193471D02*
X1129881Y176356D01*
X1134819D01*
G01X1163168Y166768D02*
Y169979D01*
X1156791Y176356D01*
X1134819D01*
G01X1125547Y196041D02*
X1134382Y187206D01*
X1161292D01*
X1179300Y169198D01*
Y167319D01*
G01X1126473Y197308D02*
X1135025Y188756D01*
X1161935D01*
X1181200Y169491D01*
Y168982D01*
G01X1134819Y182556D02*
X1159363D01*
X1171968Y169951D01*
Y164932D01*
X1172000Y164900D01*
G01X1121509Y193500D02*
X1132453Y182556D01*
X1134819D01*
G01Y184106D02*
X1160006D01*
X1175518Y168594D01*
Y164832D01*
X1175550Y164800D01*
G01X1122803Y194399D02*
X1133096Y184106D01*
X1134819D01*
G01Y181006D02*
X1158720D01*
X1170818Y168908D01*
Y164932D01*
X1170850Y164900D01*
G01X1120300Y192517D02*
X1131811Y181006D01*
X1134819D01*
G01Y185656D02*
X1160649D01*
X1176668Y169637D01*
Y164832D01*
X1176700Y164800D01*
G01X1123795Y195600D02*
X1133739Y185656D01*
X1134819D01*
G01X1148810Y270796D02*
X1151060D01*
G01X1145430Y264947D02*
X1147680D01*
G01X1098111Y222047D02*
X1095861D01*
G01X1098111Y225947D02*
X1095861D01*
G01X1108251Y220096D02*
X1106001D01*
G01X1108251Y227896D02*
X1106001D01*
G01X1118391Y222047D02*
X1116141D01*
G01X1118391Y225947D02*
X1116141D01*
G01X1104871Y222047D02*
X1102621D01*
G01X1104871Y225947D02*
X1102621D01*
G01X1115011Y220096D02*
X1112761D01*
G01X1115011Y227896D02*
X1112761D01*
G01X1128530Y220096D02*
X1126280D01*
G01X1128530Y227896D02*
X1126280D01*
G01X1133040Y231797D02*
X1135290D01*
G01X1122900Y222047D02*
X1125150D01*
G01X1122900Y225947D02*
X1125150D01*
G01X1111631Y218147D02*
X1109381D01*
G01X1131910D02*
X1129660D01*
G01X1111631Y229847D02*
X1109381D01*
G01X1131910Y225947D02*
X1129660D01*
G01X1111631Y222047D02*
X1109381D01*
G01X1131910D02*
X1129660D01*
G01X1111631Y225947D02*
X1109381D01*
G01X1131910Y229847D02*
X1129660D01*
G01X1118391Y233746D02*
X1116141D01*
G01X1118391Y241547D02*
X1116141D01*
G01X1128530Y235696D02*
X1126280D01*
G01X1128530Y239596D02*
X1126280D01*
G01X1115011Y235696D02*
X1112761D01*
G01X1115011Y239596D02*
X1112761D01*
G01X1122900Y233746D02*
X1125150D01*
G01X1122900Y241547D02*
X1125150D01*
G01X1121771Y231797D02*
X1119521D01*
G01X1121771Y243496D02*
X1119521D01*
G01X1121771Y235696D02*
X1119521D01*
G01X1121771Y239596D02*
X1119521D01*
G01X1101491Y262996D02*
Y265400D01*
G01X1104871Y264947D02*
Y267300D01*
G01X1098111Y261047D02*
Y263400D01*
G01X1118391Y268847D02*
X1116141D01*
G01X1142050Y266896D02*
X1144300D01*
G01X1152190Y257147D02*
X1154440D01*
G01X1155570Y251296D02*
X1157820D01*
G01X1152190Y249347D02*
X1154440D01*
G01X1155570Y247396D02*
X1157820D01*
G01X1155570Y266896D02*
X1157820D01*
G01X1111631Y264947D02*
X1109381D01*
G01X1151060Y262996D02*
X1148810D01*
G01X1154440Y261047D02*
X1152190D01*
G01X1131910Y323446D02*
X1134160D01*
G01X1125150Y292247D02*
X1127400D01*
G01X1131910Y284447D02*
X1134160D01*
G01X1115011Y337096D02*
X1116440D01*
X1118391Y339047D01*
G01X1130780Y329296D02*
X1128530D01*
G01X1138670Y323446D02*
X1140920D01*
G01X1145430Y307847D02*
X1147680D01*
G01X1148810Y309797D02*
X1151060D01*
G01X1148810Y305896D02*
X1151060D01*
G01X1142050Y301996D02*
X1144300D01*
G01X1131910Y303947D02*
X1134160D01*
G01X1135290Y298096D02*
X1137540D01*
G01X1138670Y303947D02*
X1140920D01*
G01X1135290Y305896D02*
X1137540D01*
G01X1138670Y296147D02*
X1140920D01*
G01X1135290Y294196D02*
X1137540D01*
G01X1125150Y311747D02*
X1127400D01*
G01X1121771Y309797D02*
X1119521D01*
G01X1155570Y305896D02*
X1157820D01*
G01X1148810Y301996D02*
X1151060D01*
G01X1142050Y317596D02*
X1144300D01*
G01X1135290Y321496D02*
X1137540D01*
G01X1131910Y327347D02*
X1134160D01*
G01X1135290Y325396D02*
X1137540D01*
G01X1098111Y358547D02*
X1100361D01*
G01X1098780Y416866D02*
Y430947D01*
X1113200Y445367D01*
Y449100D01*
G01X1100330Y416866D02*
Y430304D01*
X1115800Y445774D01*
Y448100D01*
G01X1111180Y416820D02*
Y425801D01*
X1124529Y439150D01*
X1129657D01*
X1134007Y443500D01*
X1135400D01*
G01X1112730Y416820D02*
Y425158D01*
X1125172Y437600D01*
X1130300D01*
X1134400Y441700D01*
X1137200D01*
G01X1108080Y416866D02*
Y427087D01*
X1123243Y442250D01*
X1127851D01*
X1128900Y443299D01*
Y445000D01*
X1129850Y445950D01*
G01X1120000Y416292D02*
X1128259Y424551D01*
X1160995D01*
X1170400Y433956D01*
Y438001D01*
G01X1186950Y426650D02*
X1185150Y424850D01*
X1178840D01*
X1166141Y412151D01*
X1134172D01*
X1129556Y407535D01*
G01X1130356Y406141D02*
X1134816Y410601D01*
X1166784D01*
X1179483Y423300D01*
X1187400D01*
X1188000Y423900D01*
G01X1116800Y417480D02*
X1126971Y427651D01*
X1159709D01*
X1165200Y433142D01*
Y438200D01*
G01X1118113Y416600D02*
X1127614Y426101D01*
X1160352D01*
X1167800Y433549D01*
Y437650D01*
G01X1127536Y409901D02*
X1132886Y415251D01*
X1164855D01*
X1177802Y428198D01*
X1179798D01*
X1180596Y428996D01*
G01X1103430Y416947D02*
Y429018D01*
X1120100Y445688D01*
Y446200D01*
X1124561Y450661D01*
Y450934D01*
G01X1124300Y414500D02*
X1124789D01*
X1130190Y419901D01*
X1162924D01*
X1175650Y432627D01*
Y433370D01*
X1177000Y434720D01*
Y435000D01*
G01X1101880Y416997D02*
Y429661D01*
X1118600Y446381D01*
Y446893D01*
X1123455Y451748D01*
X1123748D01*
G01X1176186Y435813D02*
X1175913D01*
X1174100Y434000D01*
Y433270D01*
X1162281Y421451D01*
X1129546D01*
X1123750Y415655D01*
Y415082D01*
G01X1106530Y416947D02*
Y427731D01*
X1123149Y444350D01*
X1124700D01*
X1126600Y446250D01*
Y446500D01*
G01X1127100Y412900D02*
X1127577D01*
X1131478Y416801D01*
X1164211D01*
X1177805Y430395D01*
X1178595D01*
X1180000Y431800D01*
Y432041D01*
G01X1118391Y346847D02*
X1120641D01*
G01X1109630Y416866D02*
Y426444D01*
X1123886Y440700D01*
X1129014D01*
X1130600Y442286D01*
Y443100D01*
X1133100Y445600D01*
G01X1121201Y415300D02*
X1128902Y423001D01*
X1161638D01*
X1172400Y433763D01*
Y436700D01*
G01X1128530Y408702D02*
X1133529Y413701D01*
X1165498D01*
X1177250Y425453D01*
G01X1104980Y416935D02*
Y428374D01*
X1122506Y445900D01*
X1124057D01*
X1125557Y447400D01*
X1125873D01*
G01X1126500Y413432D02*
Y414017D01*
X1130834Y418351D01*
X1163568D01*
X1177158Y431941D01*
X1177948D01*
X1178907Y432900D01*
X1179236D01*
G01X1167960Y261047D02*
X1165710D01*
G01X1172469D02*
X1174719D01*
G01X1162330Y251296D02*
X1164580D01*
G01X1167960Y272747D02*
X1165710D01*
G01X1169089Y255196D02*
X1171339D01*
G01X1169089Y251296D02*
X1171339D01*
G01X1158950Y245447D02*
X1161200D01*
G01X1162330Y243496D02*
X1164580D01*
G01X1172469Y272747D02*
X1174719D01*
G01X1167960Y233746D02*
X1165710D01*
G01X1167960Y249347D02*
X1165710D01*
G01X1179229Y257147D02*
X1181479D01*
G01X1175849Y255196D02*
X1178099D01*
G01X1158950Y253247D02*
X1161200D01*
G01X1172469Y268847D02*
X1174719D01*
G01X1167960Y241547D02*
X1165710D01*
G01X1167960Y245447D02*
X1165710D01*
G01X1167960Y237647D02*
X1165710D01*
G01X1169089Y239596D02*
X1171339D01*
G01X1169089Y243496D02*
X1171339D01*
G01X1172469Y249347D02*
X1174719D01*
G01X1172469Y245447D02*
X1174719D01*
G01X1172469Y257147D02*
X1174719D01*
G01X1175849Y259096D02*
X1178099D01*
G01X1167960Y268847D02*
X1165710D01*
G01X1202889Y333196D02*
X1205139D01*
G01X1196129Y313696D02*
X1198379D01*
G01X1196129Y325396D02*
X1198379D01*
G01X1177250Y425453D02*
X1178197Y426400D01*
X1182168D01*
X1182850Y427082D01*
G01X1278900Y-14800D02*
X1283625Y-19525D01*
X1298643D01*
X1299549Y-18619D01*
G01X1386210Y389910D02*
X1385400Y389100D01*
X1384900D01*
G01X1382899D02*
X1379460D01*
X1378726Y388366D01*
X1377666D01*
G01X1398260Y527120D02*
X1399595Y528455D01*
X1401960D01*
G01X1454902Y273603D02*
X1456476Y275177D01*
G01X1443878Y272028D02*
X1442304Y270454D01*
X1442303D01*
G01X1448603D02*
X1450177Y272028D01*
G01X1445454Y273603D02*
X1447028Y275177D01*
G01X1461202Y273603D02*
X1462776Y275177D01*
G01X1445454Y286202D02*
X1447028Y287776D01*
G01X1461400Y264700D02*
Y267502D01*
X1462776Y268878D01*
G01X1445454Y276753D02*
X1447028Y278327D01*
G01X1442304Y305098D02*
X1443878Y303524D01*
G01X1445454Y308247D02*
X1447028Y306673D01*
G01X1451753Y286202D02*
X1453327Y287776D01*
G01X1448603Y286202D02*
X1450177Y287776D01*
G01X1448603Y314546D02*
X1450177Y312972D01*
G01X1454928Y317723D02*
X1453327Y316122D01*
G01X1448603Y317696D02*
X1450177Y316122D01*
G01X1456476D02*
X1458400Y318046D01*
Y318500D01*
G01X1445454Y305098D02*
X1447028Y303524D01*
G01X1448603Y305098D02*
X1450177Y303524D01*
G01X1464351Y279902D02*
X1465925Y281476D01*
G01X1461202Y301948D02*
X1462776Y300374D01*
G01X1464351Y283052D02*
X1465925Y284626D01*
G01X1464350Y308247D02*
X1462776Y306673D01*
G01X1454902Y286202D02*
X1456476Y287776D01*
G01X1454902Y314546D02*
X1456476Y312972D01*
G01X1454902Y311397D02*
X1456476Y309823D01*
G01X1463610Y321329D02*
X1461282Y319001D01*
Y317778D01*
X1459626Y316122D01*
G01X1445454Y301948D02*
X1447028Y300374D01*
G01X1454902Y289351D02*
X1456476Y290925D01*
G01X1458052Y286202D02*
X1459626Y287776D01*
G01X1464351Y301948D02*
X1465925Y300374D01*
G01X1448603Y279902D02*
X1450177Y281476D01*
G01X1451753Y298798D02*
X1453327Y297224D01*
G01X1468399Y324930D02*
Y323919D01*
X1464575Y320095D01*
Y314322D01*
X1465925Y312972D01*
G01X1458052Y311397D02*
X1459626Y309823D01*
G01X1456476Y294075D02*
X1454902Y295649D01*
G01X1445454Y311397D02*
X1447028Y309823D01*
G01X1442304Y311397D02*
X1443878Y309823D01*
G01X1454902Y298798D02*
X1456476Y297224D01*
G01X1464351Y305098D02*
X1465925Y303524D01*
G01X1454902Y283052D02*
X1456476Y284626D01*
G01X1442304Y308247D02*
X1443878Y306673D01*
G01X1448603Y298798D02*
X1450177Y297224D01*
G01X1445454Y298798D02*
X1447028Y297224D01*
G01X1451753Y289351D02*
X1453327Y290925D01*
G01X1442304Y279902D02*
X1443878Y281476D01*
G01X1470650Y503432D02*
X1470182Y503900D01*
X1460500D01*
X1459600Y503000D01*
G01X1471850Y503930D02*
X1470680Y505100D01*
X1460500D01*
X1459600Y506000D01*
G01X1436160Y554655D02*
X1436605D01*
X1439770Y551490D01*
X1439800D01*
G01X1483779Y70353D02*
X1487424D01*
X1490821Y73750D01*
G01X1483779Y80353D02*
X1487841D01*
X1488921Y81433D01*
Y84029D01*
X1490057Y85165D01*
G01X1473798Y273603D02*
X1472224Y275177D01*
G01X1470649Y273603D02*
X1469075Y275177D01*
G01X1486574Y267127D02*
X1484823Y268878D01*
G01X1483247Y267304D02*
X1481673Y268878D01*
G01X1480098Y273603D02*
X1478524Y275177D01*
G01X1470649Y276753D02*
X1469075Y278327D01*
G01X1470649Y270454D02*
X1469075Y272028D01*
G01X1493199Y255507D02*
X1493057Y255649D01*
Y259193D01*
X1491250Y261000D01*
X1471500D01*
X1467600Y264900D01*
Y266001D01*
X1465925Y267676D01*
Y268878D01*
G01X1495682Y255861D02*
X1494046Y257497D01*
Y259694D01*
X1491740Y262000D01*
X1472000D01*
X1468400Y265600D01*
Y266399D01*
X1467700Y267099D01*
Y273402D01*
X1465925Y275177D01*
G01X1483247Y270454D02*
X1481673Y272028D01*
G01X1483247Y273603D02*
X1481673Y275177D01*
G01X1480098Y270454D02*
X1478524Y272028D01*
G01X1473798Y305098D02*
X1472224Y303524D01*
G01X1473231Y320250D02*
X1472224Y319243D01*
Y316122D01*
G01X1480098Y298798D02*
X1478524Y297224D01*
G01X1486397Y283052D02*
X1484823Y284626D01*
G01X1496628Y288440D02*
X1495560D01*
X1493075Y290925D01*
X1491122D01*
G01X1480098Y283052D02*
X1478524Y284626D01*
G01X1476948Y279902D02*
X1475374Y281476D01*
G01X1480098Y286202D02*
X1478524Y287776D01*
G01X1486397Y286202D02*
X1484823Y287776D01*
G01X1489546Y286202D02*
X1487972Y287776D01*
G01X1473798Y283052D02*
X1472224Y284626D01*
G01X1470649Y305098D02*
X1469075Y303524D01*
G01X1483247Y298798D02*
X1481673Y297224D01*
G01X1475374Y294075D02*
X1476948Y295649D01*
G01X1483247Y289351D02*
X1481673Y290925D01*
G01X1470649Y283052D02*
X1469075Y284626D01*
G01X1489546Y279902D02*
X1487972Y281476D01*
G01X1489546Y301948D02*
X1487972Y300374D01*
G01X1489546Y311397D02*
X1487972Y309823D01*
G01X1470649Y308247D02*
X1469075Y306673D01*
G01X1493290Y287984D02*
X1491816Y289458D01*
X1489439D01*
X1487972Y290925D01*
G01X1473798Y311397D02*
X1472224Y309823D01*
G01X1486397Y301948D02*
X1484823Y300374D01*
G01X1508428Y318669D02*
Y316409D01*
X1508829Y316008D01*
X1512009D01*
X1513351Y317350D01*
X1514716D01*
X1517106Y314960D01*
X1518260D01*
X1519280Y315980D01*
X1523636D01*
X1528513Y320857D01*
Y322534D01*
G01X1470649Y314546D02*
X1469075Y312972D01*
G01X1476948Y286202D02*
X1475374Y287776D01*
G01X1503125Y381800D02*
X1504600Y381115D01*
X1505075Y380894D01*
G01X1475098Y389193D02*
X1473080Y387175D01*
Y384170D01*
X1472940Y384030D01*
G01X1514825Y462920D02*
X1516775Y463826D01*
G01X1503125Y462920D02*
X1504600Y463605D01*
X1505075Y463826D01*
G01X1522625Y462920D02*
X1524575Y463826D01*
G01X1518725Y462920D02*
X1520675Y463826D01*
G01X1580599Y146538D02*
X1577332D01*
X1575863Y148007D01*
Y150237D01*
X1574000Y152100D01*
G01X1593401Y145489D02*
X1585148D01*
X1584099Y146538D01*
G01X1580599Y143538D02*
X1578917D01*
X1575155Y147300D01*
Y147299D01*
X1575121D01*
X1574000Y148420D01*
Y149500D01*
G01X1587477Y144569D02*
X1585130D01*
X1584099Y143538D01*
G01X1602717Y139113D02*
X1598687D01*
X1593231Y144569D01*
X1587477D01*
G01X1530101Y132671D02*
X1530800Y131972D01*
X1536801D01*
G01X1561925Y192675D02*
X1559894D01*
X1558369Y194200D01*
X1555600D01*
X1554000Y192600D01*
Y188862D01*
X1566858Y176004D01*
Y175192D01*
G01X1554400Y262300D02*
X1553848D01*
X1552388Y260840D01*
X1551273D01*
X1550750Y261363D01*
Y262563D01*
G01X1534325Y462920D02*
X1536275Y463826D01*
G01X1530425Y462920D02*
X1530426D01*
X1532375Y463826D01*
G01X1528475Y466300D02*
X1530412Y467200D01*
X1530425Y467206D01*
G01X1532375Y466300D02*
X1534312Y467200D01*
X1534325Y467206D01*
G01X1570378Y489021D02*
X1573979D01*
X1575000Y488000D01*
Y487500D01*
X1578000Y484500D01*
Y483800D01*
X1579600Y482200D01*
X1583428D01*
X1588528Y487300D01*
X1590000D01*
G01X1567850Y601563D02*
X1570660D01*
G01X1567850Y603138D02*
X1569138D01*
X1569300Y603300D01*
X1571560D01*
X1573260Y601600D01*
G01X1593401Y145489D02*
X1594710D01*
X1595099Y145100D01*
Y143831D01*
X1598392Y140538D01*
X1607591D01*
X1609016Y139113D01*
G01X1605867D02*
X1604292Y137538D01*
G01X1607239Y131358D02*
X1609232D01*
X1610926Y129664D01*
X1612166D01*
G01X1640000Y456900D02*
X1640700Y457600D01*
X1648300D01*
X1653800Y452100D01*
Y449400D01*
X1654950Y448250D01*
X1656000D01*
G01X1659000D02*
X1661202D01*
X1664650Y451698D01*
Y456250D01*
X1660900Y460000D01*
X1640400D01*
X1640100Y459700D01*
G01X1711869Y81690D02*
X1714850Y78709D01*
Y77778D01*
G01X1656260Y132814D02*
X1657835Y134389D01*
G01X1656260Y142262D02*
X1657835Y143837D01*
G01X1653111Y142262D02*
X1654685Y143837D01*
G01X1659410Y145412D02*
X1657835Y146987D01*
G01X1653111Y145412D02*
X1651536Y146988D01*
G01X1659410Y148562D02*
X1660985Y150137D01*
G01X1656260Y148562D02*
Y148564D01*
X1654686Y150138D01*
G01X1659410Y151711D02*
X1657836Y153288D01*
G01X1662560Y151711D02*
X1664135Y153286D01*
G01X1653111Y139113D02*
X1654685Y140687D01*
G01X1659410Y142262D02*
X1660985Y143837D01*
G01X1653111Y126514D02*
X1654686Y124940D01*
G01X1659410Y126514D02*
X1660985Y128089D01*
G01X1665709Y132814D02*
X1667284Y131239D01*
G01X1653111Y129664D02*
X1654685Y131239D01*
G01X1659410Y129664D02*
X1660985Y131239D01*
G01X1656260Y129664D02*
X1657835Y131239D01*
G01X1662560Y126514D02*
X1660985Y124939D01*
G01X1662560Y148562D02*
X1660985Y146987D01*
G01X1653111Y151711D02*
X1654686Y153288D01*
G01X1662560Y139113D02*
X1660985Y140688D01*
G01X1657119Y401669D02*
X1657755Y401033D01*
Y396875D01*
X1653600Y392720D01*
Y370475D01*
X1656900Y367175D01*
Y357200D01*
X1653650Y353950D01*
X1652936D01*
X1652186Y354700D01*
G01X1662550Y410500D02*
Y404316D01*
X1661513Y403279D01*
X1660470D01*
X1658841Y401650D01*
Y396688D01*
X1654500Y392347D01*
Y370848D01*
X1659100Y366248D01*
Y362067D01*
G01X1652186Y352100D02*
X1653136Y353050D01*
X1654049D01*
X1659100Y358101D01*
Y362067D01*
G01X1655550Y413500D02*
X1654750Y414300D01*
Y414583D01*
X1654720Y414613D01*
Y421320D01*
G01X1655550Y410500D02*
Y413500D01*
G01X1659050D02*
X1657280Y415270D01*
Y421320D01*
G01X1659050Y410500D02*
Y413500D01*
G01X1655250Y445000D02*
X1656000Y445750D01*
Y448250D01*
G01X1654720Y437500D02*
Y444470D01*
X1655250Y445000D01*
G01X1658750D02*
Y448000D01*
X1659000Y448250D01*
G01X1657280Y437500D02*
Y443530D01*
X1658750Y445000D01*
G01X1661522Y453751D02*
X1660689D01*
X1660684Y453746D01*
X1659350D01*
X1659000Y453396D01*
Y451750D01*
G01X1776400Y81600D02*
X1778243Y83443D01*
X1780928D01*
X1782548Y85063D01*
G01X1765500Y79750D02*
X1762000D01*
G01X1771000Y79800D02*
X1770950Y79750D01*
X1765500D01*
G01X1757998Y73637D02*
X1758000D01*
Y73640D01*
X1759390D01*
X1762000Y76250D01*
G01X1769250Y70350D02*
X1767550Y68650D01*
X1765350D01*
X1764213Y69787D01*
X1753713D01*
X1743200Y80300D01*
G01X1728000Y82000D02*
Y85200D01*
X1729300Y86500D01*
X1737000D01*
X1743200Y80300D01*
G01X1728000Y73000D02*
X1726250D01*
X1726000Y73250D01*
X1722000D01*
G01X1728000Y73000D02*
X1736400D01*
X1740400Y69000D01*
G01X1722000Y76750D02*
X1720150D01*
X1719650Y76250D01*
X1718500D01*
G01X1721400Y79500D02*
X1722000Y78900D01*
Y76750D01*
G01X1737488Y115876D02*
X1737490D01*
X1739064Y117450D01*
G01X1737488Y119026D02*
Y119024D01*
X1735914Y117450D01*
G01X1724890Y100128D02*
Y100126D01*
X1723314Y98550D01*
G01X1724890Y103278D02*
Y103276D01*
X1723314Y101700D01*
G01X1760554Y237712D02*
X1759362D01*
X1758962Y238112D01*
Y239313D01*
X1759646Y239997D01*
Y244105D01*
G01X1756496D02*
Y240021D01*
X1757157Y239360D01*
Y238113D01*
X1756756Y237712D01*
X1755554D01*
G01X1833210Y76430D02*
X1833530D01*
G01X1798384Y250498D02*
X1797182D01*
X1796781Y250097D01*
Y248806D01*
X1797441Y248146D01*
G01X1793384Y250498D02*
X1794576D01*
X1794976Y250098D01*
Y248897D01*
X1794292Y248213D01*
Y244105D01*
G01X1817282Y250498D02*
X1816080D01*
X1815679Y250097D01*
Y248854D01*
X1816339Y248194D01*
G01X1812282Y250498D02*
X1813474D01*
X1813874Y250098D01*
Y248897D01*
X1813190Y248213D01*
G01X1779451Y237712D02*
X1778259D01*
X1777859Y238112D01*
Y239313D01*
X1778543Y239997D01*
Y244105D01*
G01X1775394D02*
Y239984D01*
X1776054Y239324D01*
Y238113D01*
X1775653Y237712D01*
X1774451D01*
G01X1840675Y86900D02*
X1838277D01*
X1836750Y85373D01*
Y81300D01*
G01X1856650Y169600D02*
Y168750D01*
X1855000Y167100D01*
G01D02*
X1854637Y166737D01*
Y161652D01*
G01X1944611Y193400D02*
X1947666Y190345D01*
G01D02*
X1949901Y188110D01*
G01X1963300Y191000D02*
Y186713D01*
X1960760Y184173D01*
G54D67*
X-1550Y496713D03*
Y498288D03*
Y499863D03*
Y501438D03*
Y503013D03*
Y504587D03*
Y506162D03*
Y507737D03*
Y509312D03*
Y510887D03*
X656450Y255913D03*
Y257488D03*
Y259063D03*
Y260638D03*
Y262213D03*
Y263787D03*
Y265362D03*
Y266937D03*
Y268512D03*
Y270087D03*
X1347350Y53413D03*
Y54988D03*
Y56563D03*
Y58138D03*
Y59713D03*
Y61287D03*
Y62862D03*
Y64437D03*
Y66012D03*
Y67587D03*
G54D178*
X1255730Y314160D03*
G54D286*
X1719500Y499620D03*
G54D268*
X1634611Y506852D03*
Y510789D03*
Y514726D03*
Y518663D03*
Y479293D03*
Y483230D03*
Y487167D03*
Y491104D03*
Y495041D03*
Y498978D03*
Y502915D03*
Y522600D03*
X1656611Y510789D03*
Y514726D03*
Y518663D03*
Y479293D03*
Y483230D03*
Y487167D03*
Y522600D03*
Y491104D03*
Y495041D03*
Y498978D03*
Y502915D03*
Y506852D03*
G54D196*
X1296586Y198653D03*
X1286850Y207463D03*
G54D277*
X1711046Y495760D03*
G54D85*
X105300Y272900D03*
X101550Y281400D03*
X97800Y272900D03*
X106200Y303900D03*
X98700D03*
X102450Y312400D03*
X1217275Y127924D03*
X1224775D03*
X1221025Y136424D03*
X1564831Y331926D03*
X1572331D03*
X1568581Y323426D03*
X1652485Y207858D03*
X1659985D03*
X1656235Y199358D03*
X1871150Y565850D03*
X1867400Y574350D03*
X1874900D03*
X1933500Y540000D03*
X1926000D03*
X1929750Y548500D03*
G54D169*
X1245946Y265866D03*
G54D259*
X1623812Y268699D03*
G54D76*
X72800Y105000D03*
G54D295*
X1787000Y135500D03*
Y143500D03*
X1882660Y540663D03*
X1890660D03*
X1905100Y538000D03*
X1913100D03*
G54D94*
X62250Y291105D03*
Y293075D03*
Y295045D03*
Y297015D03*
Y298985D03*
Y300955D03*
Y302925D03*
Y304895D03*
G54D187*
X1260765Y451319D03*
X1253522Y445355D03*
G54D58*
X48700Y250260D03*
X29000D03*
X48700Y261300D03*
X29000D03*
G54D49*
X24582Y-3053D03*
X225718Y130200D03*
X222829Y141300D03*
X210896Y140300D03*
X213828Y134900D03*
X195800Y124600D03*
X200900Y120704D03*
X231492Y140500D03*
X239892Y135000D03*
X242592Y142000D03*
X267186Y141000D03*
X270504Y136000D03*
X234192Y134000D03*
X256492Y130000D03*
X259149Y140500D03*
X249872Y141500D03*
X252612Y135500D03*
X245292Y125500D03*
X251642Y123500D03*
X331592Y114748D03*
X335792Y104069D03*
X333692Y110190D03*
X329573Y107022D03*
X324692Y114882D03*
X353714Y103936D03*
X349692Y108643D03*
X347592Y103993D03*
X345492Y112063D03*
X337892Y113956D03*
X329730Y489798D03*
X384377Y114881D03*
X378422Y106505D03*
X375287Y127696D03*
X360617Y103689D03*
X377272Y116996D03*
X363186Y108014D03*
X374137Y140732D03*
X382392Y109922D03*
X405733Y104472D03*
X412792Y104540D03*
X377149Y462175D03*
X380350Y453103D03*
X372781Y491333D03*
X377192Y498249D03*
X403192Y498191D03*
X419092Y104695D03*
X474326Y112500D03*
X466112Y114000D03*
X460292Y115000D03*
X467262Y109000D03*
X425492Y104752D03*
X481691Y104000D03*
X496902Y116000D03*
X516442Y130500D03*
X521052Y117000D03*
X508892Y122500D03*
X511492Y133000D03*
X533203Y119500D03*
X524392Y132500D03*
X526911Y125000D03*
X537511Y135500D03*
X557692Y133500D03*
X560211Y140500D03*
X547328Y120500D03*
X555147Y139000D03*
X540992Y141000D03*
X543659Y126500D03*
X544809Y135000D03*
X660128Y296830D03*
X726287Y258979D03*
X847304Y138000D03*
X861026Y141000D03*
X858337Y125500D03*
X850036Y128500D03*
X889500Y135000D03*
X892200Y142000D03*
X881100Y140500D03*
X883800Y134000D03*
X906100Y130000D03*
X908757Y140500D03*
X899480Y141500D03*
X902220Y135500D03*
X894900Y125500D03*
X901250Y123500D03*
X916794Y141000D03*
X920112Y136000D03*
X945300Y140000D03*
X948000Y130500D03*
X936900Y135000D03*
X926300Y142500D03*
X929100Y137500D03*
X981200Y115148D03*
X985400Y104069D03*
X1033985Y115181D03*
X983300Y110390D03*
X979181Y107022D03*
X974300Y115182D03*
X1028030Y115156D03*
X1024895Y111035D03*
X1010225Y103689D03*
X1026880Y103936D03*
X1012794Y108014D03*
X1032000Y110422D03*
X1003322Y103936D03*
X999300Y108743D03*
X997200Y103793D03*
X995100Y112669D03*
X987500Y113956D03*
X1003580Y138417D03*
X1026757Y461106D03*
X1029958Y451876D03*
X979338Y490843D03*
X1022389Y490150D03*
X1026800Y497824D03*
X1081732Y104117D03*
X1068700Y104697D03*
X1055341Y104472D03*
X1062400Y104568D03*
X1075100Y104812D03*
X1055670Y464870D03*
X1052800Y498443D03*
X1051700Y476126D03*
X1059640Y474572D03*
X1047730Y470954D03*
X1131299Y104000D03*
X1119700Y116492D03*
X1123934Y112500D03*
X1109900Y115000D03*
X1116870Y109000D03*
X1146510Y115200D03*
X1166050Y130500D03*
X1170660Y117000D03*
X1158500Y122500D03*
X1161100Y133000D03*
X1182811Y119500D03*
X1207300Y133500D03*
X1209819Y140500D03*
X1174000Y132500D03*
X1176519Y125000D03*
X1196936Y120500D03*
X1204755Y139000D03*
X1190600Y141000D03*
X1193267Y126500D03*
X1187119Y135500D03*
X1194417Y135000D03*
X1202961Y464997D03*
X1190650Y466472D03*
X1194970Y474489D03*
X1359657Y96096D03*
X1354309Y505157D03*
X1349000Y505800D03*
X1563712Y590349D03*
G54D359*
G01X1550797Y416458D02*
X1549939Y415600D01*
X1549925D01*
G01X1547975Y425740D02*
Y427663D01*
G01D02*
X1547754Y427884D01*
G54D68*
X1013Y513450D03*
X2588D03*
X4163D03*
X5738D03*
X7313D03*
X8887D03*
X10462D03*
X12037D03*
X13612D03*
X15187D03*
X659013Y272650D03*
X660588D03*
X662163D03*
X663738D03*
X665313D03*
X666887D03*
X668462D03*
X670037D03*
X671612D03*
X673187D03*
X1349913Y70150D03*
X1351488D03*
X1353063D03*
X1354638D03*
X1356213D03*
X1357787D03*
X1359362D03*
X1360937D03*
X1362512D03*
X1364087D03*
G54D287*
X1743680Y505270D03*
Y515070D03*
G54D179*
X1248995Y302830D03*
G54D77*
X81500Y127000D03*
Y118000D03*
X95500Y127500D03*
Y118500D03*
X88500Y127000D03*
Y118000D03*
X1573000Y303500D03*
Y312500D03*
X1728000Y82000D03*
Y73000D03*
X1889000Y575700D03*
Y568300D03*
X1891560Y575700D03*
Y568300D03*
X1886440Y575700D03*
Y568300D03*
X1926400Y603700D03*
Y594700D03*
G54D197*
X1281987Y215066D03*
G54D86*
X84419Y327900D03*
X82450Y332500D03*
X86387Y327900D03*
Y332500D03*
X84419D03*
G54D278*
X1660158Y534035D03*
X1788110D03*
G54D296*
X1791000Y115500D03*
Y108500D03*
G54D269*
X1604323Y469147D03*
G54D95*
X64605Y307250D03*
X66575D03*
X68545D03*
X70515D03*
X72485D03*
X74455D03*
X76425D03*
X78395D03*
G54D188*
X1255969Y462926D03*
X1251312Y459613D03*
G54D59*
X48700Y255780D03*
X29000D03*
G54D87*
X82450Y328000D03*
G54D288*
X1761339Y536791D03*
X1757402D03*
X1753465D03*
X1749528D03*
X1745591D03*
X1741654D03*
X1761339D03*
X1757402D03*
X1753465D03*
X1749528D03*
X1745591D03*
X1741654D03*
G54D297*
X1822758Y542204D03*
X1800207Y540236D03*
X1822758D03*
X1800207Y538267D03*
X1800206Y587480D03*
X1822757D03*
X1800206Y585511D03*
X1822757D03*
X1800206Y583543D03*
X1822757D03*
X1800206Y581574D03*
X1822758Y538267D03*
X1822757Y581574D03*
X1800206Y579606D03*
X1822757D03*
X1800206Y577637D03*
X1822757D03*
X1800206Y575669D03*
X1822757D03*
X1800206Y573700D03*
X1822757D03*
X1800206Y571732D03*
X1800207Y536299D03*
X1822757Y571732D03*
X1800206Y569763D03*
X1822757D03*
X1800206Y567795D03*
X1822757D03*
X1800206Y565826D03*
X1822757D03*
X1800206Y563858D03*
X1822757D03*
X1800207Y561889D03*
X1822758Y536299D03*
Y561889D03*
X1800207Y559921D03*
X1822758D03*
X1800207Y557952D03*
X1822758D03*
X1800207Y555984D03*
X1822758D03*
X1800207Y554015D03*
X1822758D03*
X1800207Y552047D03*
Y534330D03*
X1822758Y552047D03*
X1800207Y550078D03*
X1822758D03*
X1800207Y548110D03*
X1822758D03*
X1800207Y546141D03*
X1822758D03*
X1800207Y544173D03*
X1822758D03*
X1800207Y542204D03*
X1822758Y534330D03*
X1800206Y591417D03*
X1822757D03*
X1800206Y589448D03*
X1822757D03*
G54D198*
X1284290Y227739D03*
G54D96*
X80750Y304895D03*
Y302925D03*
Y300955D03*
Y298985D03*
Y297015D03*
Y295045D03*
Y293075D03*
Y291105D03*
G54D279*
X1694000Y610000D03*
G54D78*
X63093Y202300D03*
X72936D03*
X82779D03*
X1892720Y525415D03*
X1914911Y495775D03*
X1934597D03*
X1924754D03*
X1900595Y525415D03*
X1908469D03*
X1916343D03*
X1924217D03*
X1922248Y518328D03*
X1912406D03*
X1904532D03*
G54D189*
X1239184Y461227D03*
X1254389Y470270D03*
G54D69*
X-6660Y499300D03*
X-11685Y495700D03*
X-11202Y516700D03*
X-6410Y546789D03*
X72131Y348000D03*
X117300Y259500D03*
X116442Y296473D03*
X117320Y291322D03*
X117352Y323322D03*
X714761Y210752D03*
X1019589Y104065D03*
G54D199*
X1285536Y330531D03*
G54D88*
X52900Y290500D03*
Y283500D03*
X112600Y170300D03*
Y163300D03*
X655500Y19000D03*
Y12000D03*
X659950Y517400D03*
Y524400D03*
X653450Y517400D03*
Y524400D03*
X656099Y582993D03*
Y575993D03*
X721500Y59500D03*
Y52500D03*
X721900Y544100D03*
Y537100D03*
X729000Y52500D03*
Y59500D03*
X729600Y537150D03*
Y544150D03*
X1302500Y57400D03*
Y50400D03*
X1314367Y504500D03*
Y511500D03*
X1307767Y504500D03*
Y511500D03*
X1303000Y584500D03*
Y591500D03*
Y597500D03*
Y604500D03*
X1382000Y119500D03*
Y112500D03*
X1389700D03*
Y119500D03*
X1376500Y524500D03*
X1384500D03*
X1376500Y531500D03*
X1384500D03*
X1466950Y532550D03*
Y539550D03*
X1512000Y260100D03*
Y253100D03*
X1474350Y532350D03*
Y539350D03*
X1500850Y534200D03*
Y541200D03*
X1493350Y534200D03*
Y541200D03*
X1527440Y542300D03*
Y549300D03*
X1729700Y514000D03*
Y507000D03*
X1761700Y516900D03*
Y509900D03*
G54D289*
X1733096Y588640D03*
X1727190D03*
X1895673Y155900D03*
X1893705D03*
X1891736D03*
X1897642D03*
X1921264D03*
X1905516D03*
X1911421D03*
X1913390D03*
X1917327D03*
X1915358D03*
X1919295D03*
X1899610D03*
X1903547D03*
X1909453D03*
X1901579D03*
X1907484D03*
G54D79*
X95275Y217545D03*
X91626Y215364D03*
X85156Y212774D03*
X89386Y212744D03*
X87416Y215504D03*
X87542Y210043D03*
X83366Y215624D03*
X95140Y220946D03*
X91809Y221009D03*
X88447Y221136D03*
X85188Y221341D03*
X72074Y243282D03*
X65180Y243368D03*
X61800Y243400D03*
X68498Y243368D03*
X49560Y649770D03*
Y644670D03*
X54360D03*
X49560Y649570D03*
Y644670D03*
X54360D03*
X49560Y654670D03*
X54360D03*
X49560D03*
X54360D03*
X214820Y649570D03*
Y644670D03*
X210020D03*
X214820Y649770D03*
Y644670D03*
X210020D03*
X214820Y654670D03*
X210020D03*
X214820D03*
X210020D03*
X238282Y649670D03*
Y644770D03*
X243082D03*
X238282Y649870D03*
Y644770D03*
X243082D03*
X238282Y654770D03*
X243082D03*
X238282D03*
X243082D03*
X402404Y649650D03*
Y644550D03*
X397604D03*
X402404Y649450D03*
Y644550D03*
X397604D03*
X402404Y654550D03*
X397604D03*
X402404D03*
X397604D03*
X425750Y649400D03*
Y644500D03*
X430550D03*
X425750Y649600D03*
Y644500D03*
X430550D03*
X425750Y654500D03*
X430550D03*
X425750D03*
X430550D03*
X589871Y649379D03*
Y644279D03*
X585071D03*
X589872Y649180D03*
Y644280D03*
X585072D03*
X589871Y654279D03*
X585071D03*
X589872Y654280D03*
X585072D03*
X613298Y649331D03*
Y644231D03*
X618098D03*
X613298Y649131D03*
Y644231D03*
X618098D03*
X613298Y654231D03*
X618098D03*
X613298D03*
X618098D03*
X905515Y649159D03*
Y644259D03*
X900715D03*
X905515Y649359D03*
Y644259D03*
X900715D03*
X905515Y654259D03*
X900715D03*
X905515D03*
X900715D03*
X928952Y649120D03*
Y644220D03*
X933752D03*
X928952Y649320D03*
Y644220D03*
X933752D03*
X928952Y654220D03*
X933752D03*
X928952D03*
X933752D03*
X1219041Y649348D03*
Y644248D03*
X1214241D03*
X1219041Y649148D03*
Y644248D03*
X1214241D03*
X1219041Y654248D03*
X1214241D03*
X1219041D03*
X1214241D03*
X1242450Y649150D03*
Y644250D03*
X1247250D03*
X1242450Y649350D03*
Y644250D03*
X1247250D03*
X1242450Y654250D03*
X1247250D03*
X1242450D03*
X1247250D03*
X1527739Y644278D03*
D03*
Y654278D03*
D03*
X1532539Y649378D03*
Y644278D03*
Y649178D03*
Y644278D03*
Y654278D03*
D03*
G54D298*
X1895945Y-2322D03*
Y5670D03*
Y13662D03*
Y21654D03*
Y29646D03*
Y37638D03*
Y45630D03*
X1900945Y-6318D03*
Y1674D03*
Y9666D03*
Y17658D03*
Y25650D03*
Y33642D03*
Y41634D03*
Y49626D03*
G54D97*
X79477Y403180D03*
X100477D03*
X79473Y431271D03*
X100473D03*
X78900Y498750D03*
X57900D03*
X730000Y341500D03*
Y370500D03*
X751000Y341500D03*
Y370500D03*
X1392050Y61959D03*
X1413050D03*
G54D299*
X1840675Y94600D03*
X1842250D03*
X1843825D03*
G54D89*
X63382Y325500D03*
X65941D03*
X63382Y332500D03*
X68500D03*
X65941D03*
X68500Y325500D03*
X679430Y492970D03*
X681990D03*
X679430Y499970D03*
X684550D03*
X681990D03*
X684550Y492970D03*
X1510987Y325669D03*
X1508428Y318669D03*
X1505869D03*
Y325669D03*
X1510987Y318669D03*
X1581941Y326000D03*
X1584500Y333000D03*
X1587059Y326000D03*
X1581941Y333000D03*
X1587059D03*
X1634882Y217000D03*
X1640000D03*
Y224000D03*
X1637441D03*
X1634882D03*
X1699941Y77668D03*
X1702500Y84668D03*
X1705059Y77668D03*
X1699941Y84668D03*
X1705059D03*
X1763118Y58000D03*
X1760559Y51000D03*
X1758000Y58000D03*
X1763118Y51000D03*
X1758000D03*
X1798055Y143789D03*
X1795495D03*
X1798055Y136789D03*
X1792935D03*
X1795495D03*
X1792935Y143789D03*
X1801070Y115000D03*
X1798510D03*
X1801070Y108000D03*
X1795950D03*
X1798510D03*
X1795950Y115000D03*
X1836000Y539500D03*
Y546500D03*
X1876070Y552500D03*
X1873510D03*
X1876070Y545500D03*
X1870950D03*
X1873510D03*
X1870950Y552500D03*
X1841118Y546500D03*
X1838559Y539500D03*
X1841118D03*
X1925803Y578500D03*
X1928362Y585500D03*
X1930921Y578500D03*
X1925803Y585500D03*
X1930921D03*
G54D98*
X67839Y375400D03*
X69413D03*
X70988D03*
X72563D03*
X74138D03*
X75713D03*
X77287D03*
X78862D03*
X80437D03*
X82012D03*
X83587D03*
X85161D03*
X716839Y286400D03*
X718413D03*
X719988D03*
X721563D03*
X723138D03*
X724713D03*
X726287D03*
X727862D03*
X729437D03*
X731012D03*
X732587D03*
X734161D03*
G54D99*
X87900Y372661D03*
Y371087D03*
Y369512D03*
Y367937D03*
Y366362D03*
Y364787D03*
Y363213D03*
Y361638D03*
Y360063D03*
Y358488D03*
Y356913D03*
Y355339D03*
X736900Y278937D03*
Y277362D03*
Y275787D03*
Y274213D03*
Y272638D03*
Y271063D03*
Y269488D03*
Y267913D03*
Y266339D03*
Y283661D03*
Y282087D03*
Y280512D03*
M02*
